-- pcdb file, Rev:1.0 written by Allegro Design Entry HDL 16.6-p007 (v16-6-112F) 10/10/2012 on Tue Dec 01 15:06:59 2015
#ISCELL
  mstr_symbols intel_corp_bpage *
  *
#ISCELL
  mstr_symbols intel_corp_bpage *
  *
#ISCELL
  mstr_symbols intel_corp_bpage *
  *
#ISCELL
  mstr_symbols intel_corp_bpage *
  *
#ISCELL
  mstr_symbols intel_corp_bpage *
  *
#ISCELL
  mstr_symbols intel_corp_bpage *
  *
#ISCELL
  mstr_symbols intel_corp_bpage *
  *
#ISCELL
  mstr_symbols intel_corp_bpage *
  *
#ISCELL
  mstr_symbols intel_corp_bpage *
  *
#ISCELL
  mstr_symbols intel_corp_bpage *
  *
#ISCELL
  mstr_symbols intel_corp_bpage *
  *
#ISCELL
  mstr_symbols intel_corp_bpage *
  *
#ISCELL
  mstr_symbols intel_corp_bpage *
  *
#ISCELL
  mstr_symbols intel_corp_bpage *
  *
#ISCELL
  mstr_symbols intel_corp_bpage *
  *
#ISCELL
  mstr_symbols intel_corp_bpage *
  *
#ISCELL
  mstr_symbols intel_corp_bpage *
  *
#ISCELL
  mstr_symbols intel_corp_bpage *
  *
#ISCELL
  mstr_symbols intel_corp_bpage *
  *
#ISCELL
  mstr_symbols intel_corp_bpage *
  *
#ISCELL
  mstr_misc prelim *
  *
#ISCELL
  mstr_symbols bom_note *
  *
#ISCELL
  mstr_symbols cad_note *
  *
#ISCELL
  mstr_symbols design_note *
  *
#ISCELL
  mstr_symbols intel_corp_bpage *
  *
#ISCELL
  mstr_standard offpage *
  page21_i10
#ISCELL
  mstr_standard offpage *
  page21_i106
#ISCELL
  mstr_standard offpage *
  page21_i107
#ISCELL
  mstr_standard offpage *
  page21_i108
#ISCELL
  mstr_standard offpage *
  page21_i11
#ISCELL
  mstr_standard offpage *
  page21_i111
#ISCELL
  mstr_standard offpage *
  page21_i12
#ISCELL
  mstr_standard offpage *
  page21_i133
#ISCELL
  mstr_standard offpage *
  page21_i134
#ISCELL
  mstr_standard offpage *
  page21_i135
#ISCELL
  mstr_standard offpage *
  page21_i136
#ISCELL
  mstr_standard offpage *
  page21_i137
#ISCELL
  mstr_standard offpage *
  page21_i145
#ISCELL
  mstr_standard offpage *
  page21_i146
#ISCELL
  mstr_standard offpage *
  page21_i147
#CELL
  mstr_discrete res *
  page21_i149
#ISCELL
  mstr_standard offpage *
  page21_i15
#CELL
  mstr_discrete res *
  page21_i150
#CELL
  mstr_discrete res *
  page21_i151
#CELL
  mstr_discrete res *
  page21_i152
#CELL
  mstr_discrete res *
  page21_i153
#CELL
  mstr_discrete res *
  page21_i154
#ISCELL
  mstr_standard offpage *
  page21_i155
#ISCELL
  mstr_standard offpage *
  page21_i156
#ISCELL
  mstr_standard offpage *
  page21_i157
#ISCELL
  mstr_symbols pvccio_cpu0 *
  page21_i158
#CELL
  mstr_discrete res *
  page21_i159
#CELL
  mstr_discrete res *
  page21_i161
#CELL
  mstr_discrete res *
  page21_i163
#CELL
  mstr_discrete res *
  page21_i164
#ISCELL
  mstr_standard offpage *
  page21_i169
#ISCELL
  mstr_standard offpage *
  page21_i170
#ISCELL
  mstr_standard offpage *
  page21_i172
#ISCELL
  mstr_standard offpage *
  page21_i175
#CELL
  mstr_discrete res *
  page21_i177
#CELL
  mstr_discrete res *
  page21_i178
#CELL
  mstr_discrete res *
  page21_i179
#ISCELL
  mstr_standard offpage *
  page21_i18
#CELL
  mstr_discrete res *
  page21_i180
#CELL
  mstr_discrete res *
  page21_i181
#CELL
  mstr_discrete res *
  page21_i182
#ISCELL
  mstr_symbols gnd *
  page21_i183
#CELL
  mstr_discrete res *
  page21_i184
#CELL
  mstr_discrete res *
  page21_i186
#ISCELL
  mstr_symbols gnd *
  page21_i187
#CELL
  mstr_discrete res *
  page21_i188
#CELL
  mstr_discrete res *
  page21_i189
#ISCELL
  mstr_standard offpage *
  page21_i196
#ISCELL
  mstr_standard offpage *
  page21_i197
#ISCELL
  mstr_standard offpage *
  page21_i2
#ISCELL
  mstr_standard offpage *
  page21_i200
#ISCELL
  mstr_standard offpage *
  page21_i201
#ISCELL
  mstr_standard offpage *
  page21_i202
#CELL
  mstr_discrete res *
  page21_i204
#ISCELL
  mstr_standard offpage *
  page21_i205
#ISCELL
  mstr_standard offpage *
  page21_i209
#ISCELL
  mstr_standard offpage *
  page21_i212
#ISCELL
  mstr_standard offpage *
  page21_i213
#ISCELL
  mstr_standard offpage *
  page21_i214
#ISCELL
  mstr_standard offpage *
  page21_i215
#CELL
  chpset_lib socket_p_mech_a *
  page21_i216
#CELL
  chpset_lib socket_p_mech_a *
  page21_i217
#CELL
  mstr_discrete res *
  page21_i219
#CELL
  mstr_discrete res *
  page21_i227
#ISCELL
  mstr_symbols p3v3_stby *
  page21_i228
#ISCELL
  mstr_standard offpage *
  page21_i233
#ISCELL
  mstr_standard offpage *
  page21_i234
#ISCELL
  mstr_standard offpage *
  page21_i235
#ISCELL
  mstr_standard offpage *
  page21_i236
#ISCELL
  mstr_standard offpage *
  page21_i237
#CELL
  mstr_discrete res *
  page21_i238
#CELL
  mstr_discrete res *
  page21_i239
#CELL
  mstr_discrete res *
  page21_i240
#CELL
  mstr_discrete res *
  page21_i241
#ISCELL
  mstr_symbols p3v3_stby *
  page21_i243
#CELL
  mstr_discrete res *
  page21_i244
#ISCELL
  mstr_standard offpage *
  page21_i247
#ISCELL
  mstr_standard offpage *
  page21_i254
#ISCELL
  mstr_standard offpage *
  page21_i255
#ISCELL
  mstr_standard offpage *
  page21_i256
#ISCELL
  mstr_symbols pvccio_cpu0 *
  page21_i257
#CELL
  mstr_discrete res *
  page21_i258
#CELL
  chpset_lib skx_ext_b *
  page21_i259
#ISCELL
  mstr_standard offpage *
  page21_i260
#ISCELL
  mstr_standard offpage *
  page21_i261
#ISCELL
  mstr_standard offpage *
  page21_i262
#ISCELL
  mstr_standard offpage *
  page21_i263
#ISCELL
  mstr_standard offpage *
  page21_i264
#ISCELL
  mstr_standard offpage *
  page21_i265
#ISCELL
  mstr_standard offpage *
  page21_i266
#ISCELL
  mstr_standard offpage *
  page21_i267
#ISCELL
  mstr_standard offpage *
  page21_i268
#ISCELL
  mstr_standard offpage *
  page21_i4
#ISCELL
  mstr_standard offpage *
  page21_i43
#ISCELL
  mstr_standard offpage *
  page21_i44
#ISCELL
  mstr_standard offpage *
  page21_i47
#ISCELL
  mstr_standard offpage *
  page21_i48
#ISCELL
  mstr_standard offpage *
  page21_i49
#ISCELL
  mstr_standard offpage *
  page21_i5
#ISCELL
  mstr_standard offpage *
  page21_i50
#ISCELL
  mstr_standard offpage *
  page21_i6
#ISCELL
  mstr_standard offpage *
  page21_i66
#ISCELL
  mstr_standard offpage *
  page21_i67
#ISCELL
  mstr_standard offpage *
  page21_i68
#ISCELL
  mstr_standard offpage *
  page21_i69
#ISCELL
  mstr_standard offpage *
  page21_i7
#ISCELL
  mstr_standard offpage *
  page21_i71
#ISCELL
  mstr_standard offpage *
  page21_i72
#ISCELL
  mstr_standard offpage *
  page21_i74
#ISCELL
  mstr_standard offpage *
  page21_i75
#ISCELL
  mstr_standard offpage *
  page21_i76
#ISCELL
  mstr_standard offpage *
  page21_i77
#ISCELL
  mstr_standard offpage *
  page21_i78
#ISCELL
  mstr_standard offpage *
  page21_i79
#ISCELL
  mstr_standard offpage *
  page21_i8
#ISCELL
  mstr_standard offpage *
  page21_i80
#ISCELL
  mstr_standard offpage *
  page21_i9
#ISCELL
  mstr_misc prelim *
  *
#ISCELL
  mstr_symbols design_note *
  *
#ISCELL
  mstr_symbols intel_corp_bpage *
  *
#ISCELL
  mstr_standard offpage *
  page22_i185
#ISCELL
  mstr_standard offpage *
  page22_i186
#CELL
  mstr_discrete res *
  page22_i188
#ISCELL
  mstr_symbols gnd *
  page22_i189
#CELL
  mstr_discrete res *
  page22_i190
#ISCELL
  mstr_standard offpage *
  page22_i195
#ISCELL
  mstr_standard offpage *
  page22_i196
#ISCELL
  mstr_standard offpage *
  page22_i197
#ISCELL
  mstr_standard offpage *
  page22_i198
#ISCELL
  mstr_standard offpage *
  page22_i199
#ISCELL
  mstr_standard offpage *
  page22_i200
#ISCELL
  mstr_symbols vcc_core *
  page22_i202
#ISCELL
  mstr_symbols vcc_core *
  page22_i203
#CELL
  chpset_lib skx_ext_b *
  page22_i204
#ISCELL
  mstr_standard offpage *
  page22_i205
#ISCELL
  mstr_standard offpage *
  page22_i206
#ISCELL
  mstr_standard offpage *
  page22_i207
#ISCELL
  mstr_misc prelim *
  *
#ISCELL
  mstr_symbols design_note *
  *
#ISCELL
  mstr_symbols intel_corp_bpage *
  *
#ISCELL
  mstr_standard offpage *
  page23_i1
#ISCELL
  mstr_standard tap *
  page23_i10
#ISCELL
  mstr_standard tap *
  page23_i100
#ISCELL
  mstr_standard tap *
  page23_i101
#ISCELL
  mstr_standard tap *
  page23_i102
#ISCELL
  mstr_standard tap *
  page23_i103
#ISCELL
  mstr_standard tap *
  page23_i104
#ISCELL
  mstr_standard tap *
  page23_i105
#ISCELL
  mstr_standard tap *
  page23_i106
#ISCELL
  mstr_standard tap *
  page23_i107
#ISCELL
  mstr_standard tap *
  page23_i108
#ISCELL
  mstr_standard tap *
  page23_i109
#ISCELL
  mstr_standard tap *
  page23_i11
#ISCELL
  mstr_standard tap *
  page23_i110
#ISCELL
  mstr_standard tap *
  page23_i111
#ISCELL
  mstr_standard tap *
  page23_i112
#ISCELL
  mstr_standard tap *
  page23_i113
#ISCELL
  mstr_standard tap *
  page23_i114
#ISCELL
  mstr_standard tap *
  page23_i115
#ISCELL
  mstr_standard tap *
  page23_i116
#ISCELL
  mstr_standard tap *
  page23_i117
#ISCELL
  mstr_standard tap *
  page23_i118
#ISCELL
  mstr_standard tap *
  page23_i119
#ISCELL
  mstr_standard tap *
  page23_i12
#ISCELL
  mstr_standard tap *
  page23_i120
#ISCELL
  mstr_standard tap *
  page23_i121
#ISCELL
  mstr_standard tap *
  page23_i122
#ISCELL
  mstr_standard tap *
  page23_i123
#ISCELL
  mstr_standard tap *
  page23_i124
#ISCELL
  mstr_standard tap *
  page23_i125
#ISCELL
  mstr_standard tap *
  page23_i126
#ISCELL
  mstr_standard tap *
  page23_i127
#ISCELL
  mstr_standard tap *
  page23_i128
#ISCELL
  mstr_standard tap *
  page23_i129
#ISCELL
  mstr_standard tap *
  page23_i13
#ISCELL
  mstr_standard tap *
  page23_i130
#ISCELL
  mstr_standard tap *
  page23_i131
#ISCELL
  mstr_standard tap *
  page23_i132
#ISCELL
  mstr_standard tap *
  page23_i133
#ISCELL
  mstr_standard tap *
  page23_i134
#ISCELL
  mstr_standard tap *
  page23_i135
#ISCELL
  mstr_standard tap *
  page23_i136
#ISCELL
  mstr_standard tap *
  page23_i137
#ISCELL
  mstr_standard tap *
  page23_i138
#ISCELL
  mstr_standard tap *
  page23_i139
#ISCELL
  mstr_standard tap *
  page23_i14
#ISCELL
  mstr_standard tap *
  page23_i140
#ISCELL
  mstr_standard tap *
  page23_i141
#ISCELL
  mstr_standard tap *
  page23_i142
#ISCELL
  mstr_standard tap *
  page23_i143
#ISCELL
  mstr_standard tap *
  page23_i144
#ISCELL
  mstr_standard tap *
  page23_i145
#ISCELL
  mstr_standard tap *
  page23_i146
#ISCELL
  mstr_standard offpage *
  page23_i147
#ISCELL
  mstr_standard offpage *
  page23_i148
#ISCELL
  mstr_standard offpage *
  page23_i149
#ISCELL
  mstr_standard tap *
  page23_i15
#ISCELL
  mstr_standard offpage *
  page23_i150
#ISCELL
  mstr_standard offpage *
  page23_i151
#ISCELL
  mstr_standard offpage *
  page23_i152
#ISCELL
  mstr_standard offpage *
  page23_i153
#ISCELL
  mstr_standard offpage *
  page23_i154
#ISCELL
  mstr_standard offpage *
  page23_i155
#ISCELL
  mstr_standard offpage *
  page23_i156
#ISCELL
  mstr_standard tap *
  page23_i157
#ISCELL
  mstr_standard tap *
  page23_i158
#ISCELL
  mstr_standard tap *
  page23_i159
#ISCELL
  mstr_standard tap *
  page23_i16
#ISCELL
  mstr_standard tap *
  page23_i160
#ISCELL
  mstr_standard tap *
  page23_i161
#ISCELL
  mstr_standard tap *
  page23_i162
#ISCELL
  mstr_standard tap *
  page23_i163
#ISCELL
  mstr_standard tap *
  page23_i164
#ISCELL
  mstr_standard tap *
  page23_i165
#ISCELL
  mstr_standard tap *
  page23_i166
#ISCELL
  mstr_standard tap *
  page23_i167
#ISCELL
  mstr_standard tap *
  page23_i168
#ISCELL
  mstr_standard tap *
  page23_i169
#ISCELL
  mstr_standard tap *
  page23_i17
#ISCELL
  mstr_standard tap *
  page23_i170
#ISCELL
  mstr_standard offpage *
  page23_i171
#CELL
  chpset_lib skx_ext_b *
  page23_i172
#ISCELL
  mstr_standard tap *
  page23_i18
#ISCELL
  mstr_standard tap *
  page23_i19
#ISCELL
  mstr_standard offpage *
  page23_i2
#ISCELL
  mstr_standard tap *
  page23_i20
#ISCELL
  mstr_standard tap *
  page23_i21
#ISCELL
  mstr_standard tap *
  page23_i22
#ISCELL
  mstr_standard tap *
  page23_i23
#ISCELL
  mstr_standard tap *
  page23_i24
#ISCELL
  mstr_standard tap *
  page23_i25
#ISCELL
  mstr_standard tap *
  page23_i26
#ISCELL
  mstr_standard tap *
  page23_i27
#ISCELL
  mstr_standard tap *
  page23_i28
#ISCELL
  mstr_standard tap *
  page23_i29
#ISCELL
  mstr_standard offpage *
  page23_i3
#ISCELL
  mstr_standard tap *
  page23_i31
#ISCELL
  mstr_standard tap *
  page23_i32
#ISCELL
  mstr_standard tap *
  page23_i33
#ISCELL
  mstr_standard tap *
  page23_i34
#ISCELL
  mstr_standard tap *
  page23_i35
#ISCELL
  mstr_standard tap *
  page23_i36
#ISCELL
  mstr_standard tap *
  page23_i37
#ISCELL
  mstr_standard tap *
  page23_i38
#ISCELL
  mstr_standard tap *
  page23_i39
#ISCELL
  mstr_standard offpage *
  page23_i4
#ISCELL
  mstr_standard tap *
  page23_i40
#ISCELL
  mstr_standard tap *
  page23_i41
#ISCELL
  mstr_standard tap *
  page23_i42
#ISCELL
  mstr_standard tap *
  page23_i43
#ISCELL
  mstr_standard tap *
  page23_i44
#ISCELL
  mstr_standard tap *
  page23_i45
#ISCELL
  mstr_standard tap *
  page23_i46
#ISCELL
  mstr_standard tap *
  page23_i47
#ISCELL
  mstr_standard tap *
  page23_i48
#ISCELL
  mstr_standard tap *
  page23_i49
#ISCELL
  mstr_standard tap *
  page23_i5
#ISCELL
  mstr_standard tap *
  page23_i50
#ISCELL
  mstr_standard tap *
  page23_i51
#ISCELL
  mstr_standard tap *
  page23_i52
#ISCELL
  mstr_standard tap *
  page23_i53
#ISCELL
  mstr_standard tap *
  page23_i54
#ISCELL
  mstr_standard tap *
  page23_i55
#ISCELL
  mstr_standard tap *
  page23_i56
#ISCELL
  mstr_standard tap *
  page23_i57
#ISCELL
  mstr_standard tap *
  page23_i58
#ISCELL
  mstr_standard tap *
  page23_i59
#ISCELL
  mstr_standard tap *
  page23_i6
#ISCELL
  mstr_standard tap *
  page23_i60
#ISCELL
  mstr_standard tap *
  page23_i61
#ISCELL
  mstr_standard tap *
  page23_i62
#ISCELL
  mstr_standard tap *
  page23_i63
#ISCELL
  mstr_standard tap *
  page23_i64
#ISCELL
  mstr_standard tap *
  page23_i65
#ISCELL
  mstr_standard tap *
  page23_i66
#ISCELL
  mstr_standard tap *
  page23_i67
#ISCELL
  mstr_standard tap *
  page23_i68
#ISCELL
  mstr_standard tap *
  page23_i69
#ISCELL
  mstr_standard tap *
  page23_i7
#ISCELL
  mstr_standard tap *
  page23_i70
#ISCELL
  mstr_standard tap *
  page23_i71
#ISCELL
  mstr_standard offpage *
  page23_i72
#ISCELL
  mstr_standard tap *
  page23_i73
#ISCELL
  mstr_standard tap *
  page23_i74
#ISCELL
  mstr_standard tap *
  page23_i75
#ISCELL
  mstr_standard tap *
  page23_i76
#ISCELL
  mstr_standard tap *
  page23_i77
#ISCELL
  mstr_standard tap *
  page23_i78
#ISCELL
  mstr_standard tap *
  page23_i79
#ISCELL
  mstr_standard tap *
  page23_i8
#ISCELL
  mstr_standard tap *
  page23_i80
#ISCELL
  mstr_standard tap *
  page23_i81
#ISCELL
  mstr_standard tap *
  page23_i82
#ISCELL
  mstr_standard tap *
  page23_i83
#ISCELL
  mstr_standard tap *
  page23_i84
#ISCELL
  mstr_standard tap *
  page23_i85
#ISCELL
  mstr_standard tap *
  page23_i86
#ISCELL
  mstr_standard tap *
  page23_i87
#ISCELL
  mstr_standard tap *
  page23_i88
#ISCELL
  mstr_standard tap *
  page23_i89
#ISCELL
  mstr_standard tap *
  page23_i9
#ISCELL
  mstr_standard tap *
  page23_i90
#ISCELL
  mstr_standard tap *
  page23_i91
#ISCELL
  mstr_standard tap *
  page23_i92
#ISCELL
  mstr_standard tap *
  page23_i93
#ISCELL
  mstr_standard tap *
  page23_i94
#ISCELL
  mstr_standard tap *
  page23_i95
#ISCELL
  mstr_standard tap *
  page23_i96
#ISCELL
  mstr_standard tap *
  page23_i97
#ISCELL
  mstr_standard tap *
  page23_i98
#ISCELL
  mstr_standard tap *
  page23_i99
#ISCELL
  mstr_misc prelim *
  *
#ISCELL
  mstr_symbols design_note *
  *
#ISCELL
  mstr_symbols intel_corp_bpage *
  *
#ISCELL
  mstr_standard offpage *
  page24_i1
#ISCELL
  mstr_standard tap *
  page24_i10
#ISCELL
  mstr_standard tap *
  page24_i100
#ISCELL
  mstr_standard tap *
  page24_i101
#ISCELL
  mstr_standard tap *
  page24_i102
#ISCELL
  mstr_standard tap *
  page24_i103
#ISCELL
  mstr_standard tap *
  page24_i104
#ISCELL
  mstr_standard tap *
  page24_i105
#ISCELL
  mstr_standard tap *
  page24_i106
#ISCELL
  mstr_standard tap *
  page24_i107
#ISCELL
  mstr_standard tap *
  page24_i108
#ISCELL
  mstr_standard tap *
  page24_i109
#ISCELL
  mstr_standard tap *
  page24_i11
#ISCELL
  mstr_standard tap *
  page24_i110
#ISCELL
  mstr_standard tap *
  page24_i111
#ISCELL
  mstr_standard tap *
  page24_i112
#ISCELL
  mstr_standard tap *
  page24_i113
#ISCELL
  mstr_standard tap *
  page24_i114
#ISCELL
  mstr_standard tap *
  page24_i115
#ISCELL
  mstr_standard tap *
  page24_i116
#ISCELL
  mstr_standard tap *
  page24_i117
#ISCELL
  mstr_standard tap *
  page24_i118
#ISCELL
  mstr_standard tap *
  page24_i119
#ISCELL
  mstr_standard tap *
  page24_i12
#ISCELL
  mstr_standard tap *
  page24_i120
#ISCELL
  mstr_standard tap *
  page24_i121
#ISCELL
  mstr_standard tap *
  page24_i122
#ISCELL
  mstr_standard tap *
  page24_i123
#ISCELL
  mstr_standard tap *
  page24_i124
#ISCELL
  mstr_standard tap *
  page24_i125
#ISCELL
  mstr_standard tap *
  page24_i126
#ISCELL
  mstr_standard tap *
  page24_i127
#ISCELL
  mstr_standard tap *
  page24_i128
#ISCELL
  mstr_standard tap *
  page24_i129
#ISCELL
  mstr_standard tap *
  page24_i13
#ISCELL
  mstr_standard tap *
  page24_i130
#ISCELL
  mstr_standard tap *
  page24_i131
#ISCELL
  mstr_standard tap *
  page24_i132
#ISCELL
  mstr_standard tap *
  page24_i133
#ISCELL
  mstr_standard tap *
  page24_i134
#ISCELL
  mstr_standard tap *
  page24_i135
#ISCELL
  mstr_standard tap *
  page24_i136
#ISCELL
  mstr_standard tap *
  page24_i137
#ISCELL
  mstr_standard tap *
  page24_i138
#ISCELL
  mstr_standard tap *
  page24_i139
#ISCELL
  mstr_standard tap *
  page24_i14
#ISCELL
  mstr_standard tap *
  page24_i140
#ISCELL
  mstr_standard tap *
  page24_i141
#ISCELL
  mstr_standard tap *
  page24_i142
#ISCELL
  mstr_standard tap *
  page24_i143
#ISCELL
  mstr_standard tap *
  page24_i144
#ISCELL
  mstr_standard tap *
  page24_i145
#ISCELL
  mstr_standard tap *
  page24_i146
#ISCELL
  mstr_standard offpage *
  page24_i147
#ISCELL
  mstr_standard offpage *
  page24_i148
#ISCELL
  mstr_standard offpage *
  page24_i149
#ISCELL
  mstr_standard tap *
  page24_i15
#ISCELL
  mstr_standard offpage *
  page24_i150
#ISCELL
  mstr_standard offpage *
  page24_i151
#ISCELL
  mstr_standard offpage *
  page24_i152
#ISCELL
  mstr_standard offpage *
  page24_i153
#ISCELL
  mstr_standard offpage *
  page24_i154
#ISCELL
  mstr_standard offpage *
  page24_i155
#ISCELL
  mstr_standard offpage *
  page24_i156
#ISCELL
  mstr_standard tap *
  page24_i157
#ISCELL
  mstr_standard tap *
  page24_i158
#ISCELL
  mstr_standard tap *
  page24_i159
#ISCELL
  mstr_standard tap *
  page24_i16
#ISCELL
  mstr_standard tap *
  page24_i160
#ISCELL
  mstr_standard tap *
  page24_i161
#ISCELL
  mstr_standard tap *
  page24_i162
#ISCELL
  mstr_standard tap *
  page24_i163
#ISCELL
  mstr_standard tap *
  page24_i164
#ISCELL
  mstr_standard tap *
  page24_i165
#ISCELL
  mstr_standard tap *
  page24_i166
#ISCELL
  mstr_standard tap *
  page24_i167
#ISCELL
  mstr_standard tap *
  page24_i168
#ISCELL
  mstr_standard tap *
  page24_i169
#ISCELL
  mstr_standard tap *
  page24_i17
#ISCELL
  mstr_standard tap *
  page24_i170
#ISCELL
  mstr_standard offpage *
  page24_i171
#CELL
  chpset_lib skx_ext_b *
  page24_i172
#ISCELL
  mstr_standard tap *
  page24_i18
#ISCELL
  mstr_standard tap *
  page24_i19
#ISCELL
  mstr_standard offpage *
  page24_i2
#ISCELL
  mstr_standard tap *
  page24_i20
#ISCELL
  mstr_standard tap *
  page24_i21
#ISCELL
  mstr_standard tap *
  page24_i22
#ISCELL
  mstr_standard tap *
  page24_i23
#ISCELL
  mstr_standard tap *
  page24_i24
#ISCELL
  mstr_standard tap *
  page24_i25
#ISCELL
  mstr_standard tap *
  page24_i26
#ISCELL
  mstr_standard tap *
  page24_i27
#ISCELL
  mstr_standard tap *
  page24_i28
#ISCELL
  mstr_standard tap *
  page24_i29
#ISCELL
  mstr_standard offpage *
  page24_i3
#ISCELL
  mstr_standard tap *
  page24_i31
#ISCELL
  mstr_standard tap *
  page24_i32
#ISCELL
  mstr_standard tap *
  page24_i33
#ISCELL
  mstr_standard tap *
  page24_i34
#ISCELL
  mstr_standard tap *
  page24_i35
#ISCELL
  mstr_standard tap *
  page24_i36
#ISCELL
  mstr_standard tap *
  page24_i37
#ISCELL
  mstr_standard tap *
  page24_i38
#ISCELL
  mstr_standard tap *
  page24_i39
#ISCELL
  mstr_standard offpage *
  page24_i4
#ISCELL
  mstr_standard tap *
  page24_i40
#ISCELL
  mstr_standard tap *
  page24_i41
#ISCELL
  mstr_standard tap *
  page24_i42
#ISCELL
  mstr_standard tap *
  page24_i43
#ISCELL
  mstr_standard tap *
  page24_i44
#ISCELL
  mstr_standard tap *
  page24_i45
#ISCELL
  mstr_standard tap *
  page24_i46
#ISCELL
  mstr_standard tap *
  page24_i47
#ISCELL
  mstr_standard tap *
  page24_i48
#ISCELL
  mstr_standard tap *
  page24_i49
#ISCELL
  mstr_standard tap *
  page24_i5
#ISCELL
  mstr_standard tap *
  page24_i50
#ISCELL
  mstr_standard tap *
  page24_i51
#ISCELL
  mstr_standard tap *
  page24_i52
#ISCELL
  mstr_standard tap *
  page24_i53
#ISCELL
  mstr_standard tap *
  page24_i54
#ISCELL
  mstr_standard tap *
  page24_i55
#ISCELL
  mstr_standard tap *
  page24_i56
#ISCELL
  mstr_standard tap *
  page24_i57
#ISCELL
  mstr_standard tap *
  page24_i58
#ISCELL
  mstr_standard tap *
  page24_i59
#ISCELL
  mstr_standard tap *
  page24_i6
#ISCELL
  mstr_standard tap *
  page24_i60
#ISCELL
  mstr_standard tap *
  page24_i61
#ISCELL
  mstr_standard tap *
  page24_i62
#ISCELL
  mstr_standard tap *
  page24_i63
#ISCELL
  mstr_standard tap *
  page24_i64
#ISCELL
  mstr_standard tap *
  page24_i65
#ISCELL
  mstr_standard tap *
  page24_i66
#ISCELL
  mstr_standard tap *
  page24_i67
#ISCELL
  mstr_standard tap *
  page24_i68
#ISCELL
  mstr_standard tap *
  page24_i69
#ISCELL
  mstr_standard tap *
  page24_i7
#ISCELL
  mstr_standard tap *
  page24_i70
#ISCELL
  mstr_standard tap *
  page24_i71
#ISCELL
  mstr_standard offpage *
  page24_i72
#ISCELL
  mstr_standard tap *
  page24_i73
#ISCELL
  mstr_standard tap *
  page24_i74
#ISCELL
  mstr_standard tap *
  page24_i75
#ISCELL
  mstr_standard tap *
  page24_i76
#ISCELL
  mstr_standard tap *
  page24_i77
#ISCELL
  mstr_standard tap *
  page24_i78
#ISCELL
  mstr_standard tap *
  page24_i79
#ISCELL
  mstr_standard tap *
  page24_i8
#ISCELL
  mstr_standard tap *
  page24_i80
#ISCELL
  mstr_standard tap *
  page24_i81
#ISCELL
  mstr_standard tap *
  page24_i82
#ISCELL
  mstr_standard tap *
  page24_i83
#ISCELL
  mstr_standard tap *
  page24_i84
#ISCELL
  mstr_standard tap *
  page24_i85
#ISCELL
  mstr_standard tap *
  page24_i86
#ISCELL
  mstr_standard tap *
  page24_i87
#ISCELL
  mstr_standard tap *
  page24_i88
#ISCELL
  mstr_standard tap *
  page24_i89
#ISCELL
  mstr_standard tap *
  page24_i9
#ISCELL
  mstr_standard tap *
  page24_i90
#ISCELL
  mstr_standard tap *
  page24_i91
#ISCELL
  mstr_standard tap *
  page24_i92
#ISCELL
  mstr_standard tap *
  page24_i93
#ISCELL
  mstr_standard tap *
  page24_i94
#ISCELL
  mstr_standard tap *
  page24_i95
#ISCELL
  mstr_standard tap *
  page24_i96
#ISCELL
  mstr_standard tap *
  page24_i97
#ISCELL
  mstr_standard tap *
  page24_i98
#ISCELL
  mstr_standard tap *
  page24_i99
#ISCELL
  mstr_misc prelim *
  *
#ISCELL
  mstr_symbols design_note *
  *
#ISCELL
  mstr_symbols intel_corp_bpage *
  *
#ISCELL
  mstr_standard offpage *
  page25_i1
#ISCELL
  mstr_standard tap *
  page25_i10
#ISCELL
  mstr_standard tap *
  page25_i100
#ISCELL
  mstr_standard tap *
  page25_i101
#ISCELL
  mstr_standard tap *
  page25_i102
#ISCELL
  mstr_standard tap *
  page25_i103
#ISCELL
  mstr_standard tap *
  page25_i104
#ISCELL
  mstr_standard tap *
  page25_i105
#ISCELL
  mstr_standard tap *
  page25_i106
#ISCELL
  mstr_standard tap *
  page25_i107
#ISCELL
  mstr_standard tap *
  page25_i108
#ISCELL
  mstr_standard tap *
  page25_i109
#ISCELL
  mstr_standard tap *
  page25_i11
#ISCELL
  mstr_standard tap *
  page25_i110
#ISCELL
  mstr_standard tap *
  page25_i111
#ISCELL
  mstr_standard tap *
  page25_i112
#ISCELL
  mstr_standard tap *
  page25_i113
#ISCELL
  mstr_standard tap *
  page25_i114
#ISCELL
  mstr_standard tap *
  page25_i115
#ISCELL
  mstr_standard tap *
  page25_i116
#ISCELL
  mstr_standard tap *
  page25_i117
#ISCELL
  mstr_standard tap *
  page25_i118
#ISCELL
  mstr_standard tap *
  page25_i119
#ISCELL
  mstr_standard tap *
  page25_i12
#ISCELL
  mstr_standard tap *
  page25_i120
#ISCELL
  mstr_standard tap *
  page25_i121
#ISCELL
  mstr_standard tap *
  page25_i122
#ISCELL
  mstr_standard tap *
  page25_i123
#ISCELL
  mstr_standard tap *
  page25_i124
#ISCELL
  mstr_standard tap *
  page25_i125
#ISCELL
  mstr_standard tap *
  page25_i126
#ISCELL
  mstr_standard tap *
  page25_i127
#ISCELL
  mstr_standard tap *
  page25_i128
#ISCELL
  mstr_standard tap *
  page25_i129
#ISCELL
  mstr_standard tap *
  page25_i13
#ISCELL
  mstr_standard tap *
  page25_i130
#ISCELL
  mstr_standard tap *
  page25_i131
#ISCELL
  mstr_standard tap *
  page25_i132
#ISCELL
  mstr_standard tap *
  page25_i133
#ISCELL
  mstr_standard tap *
  page25_i134
#ISCELL
  mstr_standard tap *
  page25_i135
#ISCELL
  mstr_standard tap *
  page25_i136
#ISCELL
  mstr_standard tap *
  page25_i137
#ISCELL
  mstr_standard tap *
  page25_i138
#ISCELL
  mstr_standard tap *
  page25_i139
#ISCELL
  mstr_standard tap *
  page25_i14
#ISCELL
  mstr_standard tap *
  page25_i140
#ISCELL
  mstr_standard tap *
  page25_i141
#ISCELL
  mstr_standard tap *
  page25_i142
#ISCELL
  mstr_standard tap *
  page25_i143
#ISCELL
  mstr_standard tap *
  page25_i144
#ISCELL
  mstr_standard tap *
  page25_i145
#ISCELL
  mstr_standard tap *
  page25_i146
#ISCELL
  mstr_standard offpage *
  page25_i147
#ISCELL
  mstr_standard offpage *
  page25_i148
#ISCELL
  mstr_standard offpage *
  page25_i149
#ISCELL
  mstr_standard tap *
  page25_i15
#ISCELL
  mstr_standard offpage *
  page25_i150
#ISCELL
  mstr_standard offpage *
  page25_i151
#ISCELL
  mstr_standard offpage *
  page25_i152
#ISCELL
  mstr_standard offpage *
  page25_i153
#ISCELL
  mstr_standard offpage *
  page25_i154
#ISCELL
  mstr_standard offpage *
  page25_i155
#ISCELL
  mstr_standard offpage *
  page25_i156
#ISCELL
  mstr_standard tap *
  page25_i157
#ISCELL
  mstr_standard tap *
  page25_i158
#ISCELL
  mstr_standard tap *
  page25_i159
#ISCELL
  mstr_standard tap *
  page25_i16
#ISCELL
  mstr_standard tap *
  page25_i160
#ISCELL
  mstr_standard tap *
  page25_i161
#ISCELL
  mstr_standard tap *
  page25_i162
#ISCELL
  mstr_standard tap *
  page25_i163
#ISCELL
  mstr_standard tap *
  page25_i164
#ISCELL
  mstr_standard tap *
  page25_i165
#ISCELL
  mstr_standard tap *
  page25_i166
#ISCELL
  mstr_standard tap *
  page25_i167
#ISCELL
  mstr_standard tap *
  page25_i168
#ISCELL
  mstr_standard tap *
  page25_i169
#ISCELL
  mstr_standard tap *
  page25_i17
#ISCELL
  mstr_standard tap *
  page25_i170
#ISCELL
  mstr_standard offpage *
  page25_i171
#CELL
  chpset_lib skx_ext_b *
  page25_i172
#ISCELL
  mstr_standard tap *
  page25_i18
#ISCELL
  mstr_standard tap *
  page25_i19
#ISCELL
  mstr_standard offpage *
  page25_i2
#ISCELL
  mstr_standard tap *
  page25_i20
#ISCELL
  mstr_standard tap *
  page25_i21
#ISCELL
  mstr_standard tap *
  page25_i22
#ISCELL
  mstr_standard tap *
  page25_i23
#ISCELL
  mstr_standard tap *
  page25_i24
#ISCELL
  mstr_standard tap *
  page25_i25
#ISCELL
  mstr_standard tap *
  page25_i26
#ISCELL
  mstr_standard tap *
  page25_i27
#ISCELL
  mstr_standard tap *
  page25_i28
#ISCELL
  mstr_standard tap *
  page25_i29
#ISCELL
  mstr_standard offpage *
  page25_i3
#ISCELL
  mstr_standard tap *
  page25_i31
#ISCELL
  mstr_standard tap *
  page25_i32
#ISCELL
  mstr_standard tap *
  page25_i33
#ISCELL
  mstr_standard tap *
  page25_i34
#ISCELL
  mstr_standard tap *
  page25_i35
#ISCELL
  mstr_standard tap *
  page25_i36
#ISCELL
  mstr_standard tap *
  page25_i37
#ISCELL
  mstr_standard tap *
  page25_i38
#ISCELL
  mstr_standard tap *
  page25_i39
#ISCELL
  mstr_standard offpage *
  page25_i4
#ISCELL
  mstr_standard tap *
  page25_i40
#ISCELL
  mstr_standard tap *
  page25_i41
#ISCELL
  mstr_standard tap *
  page25_i42
#ISCELL
  mstr_standard tap *
  page25_i43
#ISCELL
  mstr_standard tap *
  page25_i44
#ISCELL
  mstr_standard tap *
  page25_i45
#ISCELL
  mstr_standard tap *
  page25_i46
#ISCELL
  mstr_standard tap *
  page25_i47
#ISCELL
  mstr_standard tap *
  page25_i48
#ISCELL
  mstr_standard tap *
  page25_i49
#ISCELL
  mstr_standard tap *
  page25_i5
#ISCELL
  mstr_standard tap *
  page25_i50
#ISCELL
  mstr_standard tap *
  page25_i51
#ISCELL
  mstr_standard tap *
  page25_i52
#ISCELL
  mstr_standard tap *
  page25_i53
#ISCELL
  mstr_standard tap *
  page25_i54
#ISCELL
  mstr_standard tap *
  page25_i55
#ISCELL
  mstr_standard tap *
  page25_i56
#ISCELL
  mstr_standard tap *
  page25_i57
#ISCELL
  mstr_standard tap *
  page25_i58
#ISCELL
  mstr_standard tap *
  page25_i59
#ISCELL
  mstr_standard tap *
  page25_i6
#ISCELL
  mstr_standard tap *
  page25_i60
#ISCELL
  mstr_standard tap *
  page25_i61
#ISCELL
  mstr_standard tap *
  page25_i62
#ISCELL
  mstr_standard tap *
  page25_i63
#ISCELL
  mstr_standard tap *
  page25_i64
#ISCELL
  mstr_standard tap *
  page25_i65
#ISCELL
  mstr_standard tap *
  page25_i66
#ISCELL
  mstr_standard tap *
  page25_i67
#ISCELL
  mstr_standard tap *
  page25_i68
#ISCELL
  mstr_standard tap *
  page25_i69
#ISCELL
  mstr_standard tap *
  page25_i7
#ISCELL
  mstr_standard tap *
  page25_i70
#ISCELL
  mstr_standard tap *
  page25_i71
#ISCELL
  mstr_standard offpage *
  page25_i72
#ISCELL
  mstr_standard tap *
  page25_i73
#ISCELL
  mstr_standard tap *
  page25_i74
#ISCELL
  mstr_standard tap *
  page25_i75
#ISCELL
  mstr_standard tap *
  page25_i76
#ISCELL
  mstr_standard tap *
  page25_i77
#ISCELL
  mstr_standard tap *
  page25_i78
#ISCELL
  mstr_standard tap *
  page25_i79
#ISCELL
  mstr_standard tap *
  page25_i8
#ISCELL
  mstr_standard tap *
  page25_i80
#ISCELL
  mstr_standard tap *
  page25_i81
#ISCELL
  mstr_standard tap *
  page25_i82
#ISCELL
  mstr_standard tap *
  page25_i83
#ISCELL
  mstr_standard tap *
  page25_i84
#ISCELL
  mstr_standard tap *
  page25_i85
#ISCELL
  mstr_standard tap *
  page25_i86
#ISCELL
  mstr_standard tap *
  page25_i87
#ISCELL
  mstr_standard tap *
  page25_i88
#ISCELL
  mstr_standard tap *
  page25_i89
#ISCELL
  mstr_standard tap *
  page25_i9
#ISCELL
  mstr_standard tap *
  page25_i90
#ISCELL
  mstr_standard tap *
  page25_i91
#ISCELL
  mstr_standard tap *
  page25_i92
#ISCELL
  mstr_standard tap *
  page25_i93
#ISCELL
  mstr_standard tap *
  page25_i94
#ISCELL
  mstr_standard tap *
  page25_i95
#ISCELL
  mstr_standard tap *
  page25_i96
#ISCELL
  mstr_standard tap *
  page25_i97
#ISCELL
  mstr_standard tap *
  page25_i98
#ISCELL
  mstr_standard tap *
  page25_i99
#ISCELL
  mstr_misc prelim *
  *
#ISCELL
  mstr_symbols design_note *
  *
#ISCELL
  mstr_symbols intel_corp_bpage *
  *
#ISCELL
  mstr_standard offpage *
  page26_i1
#ISCELL
  mstr_standard tap *
  page26_i10
#ISCELL
  mstr_standard tap *
  page26_i100
#ISCELL
  mstr_standard tap *
  page26_i101
#ISCELL
  mstr_standard tap *
  page26_i102
#ISCELL
  mstr_standard tap *
  page26_i103
#ISCELL
  mstr_standard tap *
  page26_i104
#ISCELL
  mstr_standard tap *
  page26_i105
#ISCELL
  mstr_standard tap *
  page26_i106
#ISCELL
  mstr_standard tap *
  page26_i107
#ISCELL
  mstr_standard tap *
  page26_i108
#ISCELL
  mstr_standard tap *
  page26_i109
#ISCELL
  mstr_standard tap *
  page26_i11
#ISCELL
  mstr_standard tap *
  page26_i110
#ISCELL
  mstr_standard tap *
  page26_i111
#ISCELL
  mstr_standard tap *
  page26_i112
#ISCELL
  mstr_standard tap *
  page26_i113
#ISCELL
  mstr_standard tap *
  page26_i114
#ISCELL
  mstr_standard tap *
  page26_i115
#ISCELL
  mstr_standard tap *
  page26_i116
#ISCELL
  mstr_standard tap *
  page26_i117
#ISCELL
  mstr_standard tap *
  page26_i118
#ISCELL
  mstr_standard tap *
  page26_i119
#ISCELL
  mstr_standard tap *
  page26_i12
#ISCELL
  mstr_standard tap *
  page26_i120
#ISCELL
  mstr_standard tap *
  page26_i121
#ISCELL
  mstr_standard tap *
  page26_i122
#ISCELL
  mstr_standard tap *
  page26_i123
#ISCELL
  mstr_standard tap *
  page26_i124
#ISCELL
  mstr_standard tap *
  page26_i125
#ISCELL
  mstr_standard tap *
  page26_i126
#ISCELL
  mstr_standard tap *
  page26_i127
#ISCELL
  mstr_standard tap *
  page26_i128
#ISCELL
  mstr_standard tap *
  page26_i129
#ISCELL
  mstr_standard tap *
  page26_i13
#ISCELL
  mstr_standard tap *
  page26_i130
#ISCELL
  mstr_standard tap *
  page26_i131
#ISCELL
  mstr_standard tap *
  page26_i132
#ISCELL
  mstr_standard tap *
  page26_i133
#ISCELL
  mstr_standard tap *
  page26_i134
#ISCELL
  mstr_standard tap *
  page26_i135
#ISCELL
  mstr_standard tap *
  page26_i136
#ISCELL
  mstr_standard tap *
  page26_i137
#ISCELL
  mstr_standard tap *
  page26_i138
#ISCELL
  mstr_standard tap *
  page26_i139
#ISCELL
  mstr_standard tap *
  page26_i14
#ISCELL
  mstr_standard tap *
  page26_i140
#ISCELL
  mstr_standard tap *
  page26_i141
#ISCELL
  mstr_standard tap *
  page26_i142
#ISCELL
  mstr_standard tap *
  page26_i143
#ISCELL
  mstr_standard tap *
  page26_i144
#ISCELL
  mstr_standard tap *
  page26_i145
#ISCELL
  mstr_standard tap *
  page26_i146
#ISCELL
  mstr_standard offpage *
  page26_i147
#ISCELL
  mstr_standard offpage *
  page26_i148
#ISCELL
  mstr_standard offpage *
  page26_i149
#ISCELL
  mstr_standard tap *
  page26_i15
#ISCELL
  mstr_standard offpage *
  page26_i150
#ISCELL
  mstr_standard offpage *
  page26_i151
#ISCELL
  mstr_standard offpage *
  page26_i152
#ISCELL
  mstr_standard offpage *
  page26_i153
#ISCELL
  mstr_standard offpage *
  page26_i154
#ISCELL
  mstr_standard offpage *
  page26_i155
#ISCELL
  mstr_standard offpage *
  page26_i156
#ISCELL
  mstr_standard tap *
  page26_i157
#ISCELL
  mstr_standard tap *
  page26_i158
#ISCELL
  mstr_standard tap *
  page26_i159
#ISCELL
  mstr_standard tap *
  page26_i16
#ISCELL
  mstr_standard tap *
  page26_i160
#ISCELL
  mstr_standard tap *
  page26_i161
#ISCELL
  mstr_standard tap *
  page26_i162
#ISCELL
  mstr_standard tap *
  page26_i163
#ISCELL
  mstr_standard tap *
  page26_i164
#ISCELL
  mstr_standard tap *
  page26_i165
#ISCELL
  mstr_standard tap *
  page26_i166
#ISCELL
  mstr_standard tap *
  page26_i167
#ISCELL
  mstr_standard tap *
  page26_i168
#ISCELL
  mstr_standard tap *
  page26_i169
#ISCELL
  mstr_standard tap *
  page26_i17
#ISCELL
  mstr_standard tap *
  page26_i170
#ISCELL
  mstr_standard offpage *
  page26_i171
#CELL
  chpset_lib skx_ext_b *
  page26_i172
#ISCELL
  mstr_standard tap *
  page26_i18
#ISCELL
  mstr_standard tap *
  page26_i19
#ISCELL
  mstr_standard offpage *
  page26_i2
#ISCELL
  mstr_standard tap *
  page26_i20
#ISCELL
  mstr_standard tap *
  page26_i21
#ISCELL
  mstr_standard tap *
  page26_i22
#ISCELL
  mstr_standard tap *
  page26_i23
#ISCELL
  mstr_standard tap *
  page26_i24
#ISCELL
  mstr_standard tap *
  page26_i25
#ISCELL
  mstr_standard tap *
  page26_i26
#ISCELL
  mstr_standard tap *
  page26_i27
#ISCELL
  mstr_standard tap *
  page26_i28
#ISCELL
  mstr_standard tap *
  page26_i29
#ISCELL
  mstr_standard offpage *
  page26_i3
#ISCELL
  mstr_standard tap *
  page26_i31
#ISCELL
  mstr_standard tap *
  page26_i32
#ISCELL
  mstr_standard tap *
  page26_i33
#ISCELL
  mstr_standard tap *
  page26_i34
#ISCELL
  mstr_standard tap *
  page26_i35
#ISCELL
  mstr_standard tap *
  page26_i36
#ISCELL
  mstr_standard tap *
  page26_i37
#ISCELL
  mstr_standard tap *
  page26_i38
#ISCELL
  mstr_standard tap *
  page26_i39
#ISCELL
  mstr_standard offpage *
  page26_i4
#ISCELL
  mstr_standard tap *
  page26_i40
#ISCELL
  mstr_standard tap *
  page26_i41
#ISCELL
  mstr_standard tap *
  page26_i42
#ISCELL
  mstr_standard tap *
  page26_i43
#ISCELL
  mstr_standard tap *
  page26_i44
#ISCELL
  mstr_standard tap *
  page26_i45
#ISCELL
  mstr_standard tap *
  page26_i46
#ISCELL
  mstr_standard tap *
  page26_i47
#ISCELL
  mstr_standard tap *
  page26_i48
#ISCELL
  mstr_standard tap *
  page26_i49
#ISCELL
  mstr_standard tap *
  page26_i5
#ISCELL
  mstr_standard tap *
  page26_i50
#ISCELL
  mstr_standard tap *
  page26_i51
#ISCELL
  mstr_standard tap *
  page26_i52
#ISCELL
  mstr_standard tap *
  page26_i53
#ISCELL
  mstr_standard tap *
  page26_i54
#ISCELL
  mstr_standard tap *
  page26_i55
#ISCELL
  mstr_standard tap *
  page26_i56
#ISCELL
  mstr_standard tap *
  page26_i57
#ISCELL
  mstr_standard tap *
  page26_i58
#ISCELL
  mstr_standard tap *
  page26_i59
#ISCELL
  mstr_standard tap *
  page26_i6
#ISCELL
  mstr_standard tap *
  page26_i60
#ISCELL
  mstr_standard tap *
  page26_i61
#ISCELL
  mstr_standard tap *
  page26_i62
#ISCELL
  mstr_standard tap *
  page26_i63
#ISCELL
  mstr_standard tap *
  page26_i64
#ISCELL
  mstr_standard tap *
  page26_i65
#ISCELL
  mstr_standard tap *
  page26_i66
#ISCELL
  mstr_standard tap *
  page26_i67
#ISCELL
  mstr_standard tap *
  page26_i68
#ISCELL
  mstr_standard tap *
  page26_i69
#ISCELL
  mstr_standard tap *
  page26_i7
#ISCELL
  mstr_standard tap *
  page26_i70
#ISCELL
  mstr_standard tap *
  page26_i71
#ISCELL
  mstr_standard offpage *
  page26_i72
#ISCELL
  mstr_standard tap *
  page26_i73
#ISCELL
  mstr_standard tap *
  page26_i74
#ISCELL
  mstr_standard tap *
  page26_i75
#ISCELL
  mstr_standard tap *
  page26_i76
#ISCELL
  mstr_standard tap *
  page26_i77
#ISCELL
  mstr_standard tap *
  page26_i78
#ISCELL
  mstr_standard tap *
  page26_i79
#ISCELL
  mstr_standard tap *
  page26_i8
#ISCELL
  mstr_standard tap *
  page26_i80
#ISCELL
  mstr_standard tap *
  page26_i81
#ISCELL
  mstr_standard tap *
  page26_i82
#ISCELL
  mstr_standard tap *
  page26_i83
#ISCELL
  mstr_standard tap *
  page26_i84
#ISCELL
  mstr_standard tap *
  page26_i85
#ISCELL
  mstr_standard tap *
  page26_i86
#ISCELL
  mstr_standard tap *
  page26_i87
#ISCELL
  mstr_standard tap *
  page26_i88
#ISCELL
  mstr_standard tap *
  page26_i89
#ISCELL
  mstr_standard tap *
  page26_i9
#ISCELL
  mstr_standard tap *
  page26_i90
#ISCELL
  mstr_standard tap *
  page26_i91
#ISCELL
  mstr_standard tap *
  page26_i92
#ISCELL
  mstr_standard tap *
  page26_i93
#ISCELL
  mstr_standard tap *
  page26_i94
#ISCELL
  mstr_standard tap *
  page26_i95
#ISCELL
  mstr_standard tap *
  page26_i96
#ISCELL
  mstr_standard tap *
  page26_i97
#ISCELL
  mstr_standard tap *
  page26_i98
#ISCELL
  mstr_standard tap *
  page26_i99
#ISCELL
  mstr_misc prelim *
  *
#ISCELL
  mstr_symbols design_note *
  *
#ISCELL
  mstr_symbols intel_corp_bpage *
  *
#ISCELL
  mstr_standard offpage *
  page27_i1
#ISCELL
  mstr_standard tap *
  page27_i10
#ISCELL
  mstr_standard tap *
  page27_i100
#ISCELL
  mstr_standard tap *
  page27_i101
#ISCELL
  mstr_standard tap *
  page27_i102
#ISCELL
  mstr_standard tap *
  page27_i103
#ISCELL
  mstr_standard tap *
  page27_i104
#ISCELL
  mstr_standard tap *
  page27_i105
#ISCELL
  mstr_standard tap *
  page27_i106
#ISCELL
  mstr_standard tap *
  page27_i107
#ISCELL
  mstr_standard tap *
  page27_i108
#ISCELL
  mstr_standard tap *
  page27_i109
#ISCELL
  mstr_standard tap *
  page27_i11
#ISCELL
  mstr_standard tap *
  page27_i110
#ISCELL
  mstr_standard tap *
  page27_i111
#ISCELL
  mstr_standard tap *
  page27_i112
#ISCELL
  mstr_standard tap *
  page27_i113
#ISCELL
  mstr_standard tap *
  page27_i114
#ISCELL
  mstr_standard tap *
  page27_i115
#ISCELL
  mstr_standard tap *
  page27_i116
#ISCELL
  mstr_standard tap *
  page27_i117
#ISCELL
  mstr_standard tap *
  page27_i118
#ISCELL
  mstr_standard tap *
  page27_i119
#ISCELL
  mstr_standard tap *
  page27_i12
#ISCELL
  mstr_standard tap *
  page27_i120
#ISCELL
  mstr_standard tap *
  page27_i121
#ISCELL
  mstr_standard tap *
  page27_i122
#ISCELL
  mstr_standard tap *
  page27_i123
#ISCELL
  mstr_standard tap *
  page27_i124
#ISCELL
  mstr_standard tap *
  page27_i125
#ISCELL
  mstr_standard tap *
  page27_i126
#ISCELL
  mstr_standard tap *
  page27_i127
#ISCELL
  mstr_standard tap *
  page27_i128
#ISCELL
  mstr_standard tap *
  page27_i129
#ISCELL
  mstr_standard tap *
  page27_i13
#ISCELL
  mstr_standard tap *
  page27_i130
#ISCELL
  mstr_standard tap *
  page27_i131
#ISCELL
  mstr_standard tap *
  page27_i132
#ISCELL
  mstr_standard tap *
  page27_i133
#ISCELL
  mstr_standard tap *
  page27_i134
#ISCELL
  mstr_standard tap *
  page27_i135
#ISCELL
  mstr_standard tap *
  page27_i136
#ISCELL
  mstr_standard tap *
  page27_i137
#ISCELL
  mstr_standard tap *
  page27_i138
#ISCELL
  mstr_standard tap *
  page27_i139
#ISCELL
  mstr_standard tap *
  page27_i14
#ISCELL
  mstr_standard tap *
  page27_i140
#ISCELL
  mstr_standard tap *
  page27_i141
#ISCELL
  mstr_standard tap *
  page27_i142
#ISCELL
  mstr_standard tap *
  page27_i143
#ISCELL
  mstr_standard tap *
  page27_i144
#ISCELL
  mstr_standard tap *
  page27_i145
#ISCELL
  mstr_standard tap *
  page27_i146
#ISCELL
  mstr_standard tap *
  page27_i147
#ISCELL
  mstr_standard offpage *
  page27_i148
#ISCELL
  mstr_standard offpage *
  page27_i149
#ISCELL
  mstr_standard tap *
  page27_i15
#ISCELL
  mstr_standard offpage *
  page27_i150
#ISCELL
  mstr_standard offpage *
  page27_i151
#ISCELL
  mstr_standard offpage *
  page27_i152
#ISCELL
  mstr_standard offpage *
  page27_i153
#ISCELL
  mstr_standard offpage *
  page27_i154
#ISCELL
  mstr_standard offpage *
  page27_i155
#ISCELL
  mstr_standard offpage *
  page27_i156
#ISCELL
  mstr_standard offpage *
  page27_i157
#ISCELL
  mstr_standard tap *
  page27_i158
#ISCELL
  mstr_standard tap *
  page27_i159
#ISCELL
  mstr_standard tap *
  page27_i16
#ISCELL
  mstr_standard tap *
  page27_i160
#ISCELL
  mstr_standard tap *
  page27_i161
#ISCELL
  mstr_standard tap *
  page27_i162
#ISCELL
  mstr_standard tap *
  page27_i163
#ISCELL
  mstr_standard tap *
  page27_i164
#ISCELL
  mstr_standard tap *
  page27_i165
#ISCELL
  mstr_standard tap *
  page27_i166
#ISCELL
  mstr_standard tap *
  page27_i167
#ISCELL
  mstr_standard tap *
  page27_i168
#ISCELL
  mstr_standard tap *
  page27_i169
#ISCELL
  mstr_standard tap *
  page27_i17
#ISCELL
  mstr_standard tap *
  page27_i170
#ISCELL
  mstr_standard offpage *
  page27_i171
#CELL
  chpset_lib skx_ext_b *
  page27_i172
#ISCELL
  mstr_standard tap *
  page27_i18
#ISCELL
  mstr_standard tap *
  page27_i19
#ISCELL
  mstr_standard offpage *
  page27_i2
#ISCELL
  mstr_standard tap *
  page27_i20
#ISCELL
  mstr_standard tap *
  page27_i21
#ISCELL
  mstr_standard tap *
  page27_i22
#ISCELL
  mstr_standard tap *
  page27_i23
#ISCELL
  mstr_standard tap *
  page27_i24
#ISCELL
  mstr_standard tap *
  page27_i25
#ISCELL
  mstr_standard tap *
  page27_i26
#ISCELL
  mstr_standard tap *
  page27_i27
#ISCELL
  mstr_standard tap *
  page27_i28
#ISCELL
  mstr_standard tap *
  page27_i29
#ISCELL
  mstr_standard offpage *
  page27_i3
#ISCELL
  mstr_standard tap *
  page27_i30
#ISCELL
  mstr_standard tap *
  page27_i32
#ISCELL
  mstr_standard tap *
  page27_i33
#ISCELL
  mstr_standard tap *
  page27_i34
#ISCELL
  mstr_standard tap *
  page27_i35
#ISCELL
  mstr_standard tap *
  page27_i36
#ISCELL
  mstr_standard tap *
  page27_i37
#ISCELL
  mstr_standard tap *
  page27_i38
#ISCELL
  mstr_standard tap *
  page27_i39
#ISCELL
  mstr_standard offpage *
  page27_i4
#ISCELL
  mstr_standard tap *
  page27_i40
#ISCELL
  mstr_standard tap *
  page27_i41
#ISCELL
  mstr_standard tap *
  page27_i42
#ISCELL
  mstr_standard tap *
  page27_i43
#ISCELL
  mstr_standard tap *
  page27_i44
#ISCELL
  mstr_standard tap *
  page27_i45
#ISCELL
  mstr_standard tap *
  page27_i46
#ISCELL
  mstr_standard tap *
  page27_i47
#ISCELL
  mstr_standard tap *
  page27_i48
#ISCELL
  mstr_standard tap *
  page27_i49
#ISCELL
  mstr_standard tap *
  page27_i5
#ISCELL
  mstr_standard tap *
  page27_i50
#ISCELL
  mstr_standard tap *
  page27_i51
#ISCELL
  mstr_standard tap *
  page27_i52
#ISCELL
  mstr_standard tap *
  page27_i53
#ISCELL
  mstr_standard tap *
  page27_i54
#ISCELL
  mstr_standard tap *
  page27_i55
#ISCELL
  mstr_standard tap *
  page27_i56
#ISCELL
  mstr_standard tap *
  page27_i57
#ISCELL
  mstr_standard tap *
  page27_i58
#ISCELL
  mstr_standard tap *
  page27_i59
#ISCELL
  mstr_standard tap *
  page27_i6
#ISCELL
  mstr_standard tap *
  page27_i60
#ISCELL
  mstr_standard tap *
  page27_i61
#ISCELL
  mstr_standard tap *
  page27_i62
#ISCELL
  mstr_standard tap *
  page27_i63
#ISCELL
  mstr_standard tap *
  page27_i64
#ISCELL
  mstr_standard tap *
  page27_i65
#ISCELL
  mstr_standard tap *
  page27_i66
#ISCELL
  mstr_standard tap *
  page27_i67
#ISCELL
  mstr_standard tap *
  page27_i68
#ISCELL
  mstr_standard tap *
  page27_i69
#ISCELL
  mstr_standard tap *
  page27_i7
#ISCELL
  mstr_standard tap *
  page27_i70
#ISCELL
  mstr_standard tap *
  page27_i71
#ISCELL
  mstr_standard tap *
  page27_i72
#ISCELL
  mstr_standard offpage *
  page27_i73
#ISCELL
  mstr_standard tap *
  page27_i74
#ISCELL
  mstr_standard tap *
  page27_i75
#ISCELL
  mstr_standard tap *
  page27_i76
#ISCELL
  mstr_standard tap *
  page27_i77
#ISCELL
  mstr_standard tap *
  page27_i78
#ISCELL
  mstr_standard tap *
  page27_i79
#ISCELL
  mstr_standard tap *
  page27_i8
#ISCELL
  mstr_standard tap *
  page27_i80
#ISCELL
  mstr_standard tap *
  page27_i81
#ISCELL
  mstr_standard tap *
  page27_i82
#ISCELL
  mstr_standard tap *
  page27_i83
#ISCELL
  mstr_standard tap *
  page27_i84
#ISCELL
  mstr_standard tap *
  page27_i85
#ISCELL
  mstr_standard tap *
  page27_i86
#ISCELL
  mstr_standard tap *
  page27_i87
#ISCELL
  mstr_standard tap *
  page27_i88
#ISCELL
  mstr_standard tap *
  page27_i89
#ISCELL
  mstr_standard tap *
  page27_i9
#ISCELL
  mstr_standard tap *
  page27_i90
#ISCELL
  mstr_standard tap *
  page27_i91
#ISCELL
  mstr_standard tap *
  page27_i92
#ISCELL
  mstr_standard tap *
  page27_i93
#ISCELL
  mstr_standard tap *
  page27_i94
#ISCELL
  mstr_standard tap *
  page27_i95
#ISCELL
  mstr_standard tap *
  page27_i96
#ISCELL
  mstr_standard tap *
  page27_i97
#ISCELL
  mstr_standard tap *
  page27_i98
#ISCELL
  mstr_standard tap *
  page27_i99
#ISCELL
  mstr_misc prelim *
  *
#ISCELL
  mstr_symbols design_note *
  *
#ISCELL
  mstr_symbols intel_corp_bpage *
  *
#ISCELL
  mstr_standard offpage *
  page28_i1
#ISCELL
  mstr_standard tap *
  page28_i10
#ISCELL
  mstr_standard tap *
  page28_i100
#ISCELL
  mstr_standard tap *
  page28_i101
#ISCELL
  mstr_standard tap *
  page28_i102
#ISCELL
  mstr_standard tap *
  page28_i103
#ISCELL
  mstr_standard tap *
  page28_i104
#ISCELL
  mstr_standard tap *
  page28_i105
#ISCELL
  mstr_standard tap *
  page28_i106
#ISCELL
  mstr_standard tap *
  page28_i107
#ISCELL
  mstr_standard tap *
  page28_i108
#ISCELL
  mstr_standard tap *
  page28_i109
#ISCELL
  mstr_standard tap *
  page28_i11
#ISCELL
  mstr_standard tap *
  page28_i110
#ISCELL
  mstr_standard tap *
  page28_i111
#ISCELL
  mstr_standard tap *
  page28_i112
#ISCELL
  mstr_standard tap *
  page28_i113
#ISCELL
  mstr_standard tap *
  page28_i114
#ISCELL
  mstr_standard tap *
  page28_i115
#ISCELL
  mstr_standard tap *
  page28_i116
#ISCELL
  mstr_standard tap *
  page28_i117
#ISCELL
  mstr_standard tap *
  page28_i118
#ISCELL
  mstr_standard tap *
  page28_i119
#ISCELL
  mstr_standard tap *
  page28_i12
#ISCELL
  mstr_standard tap *
  page28_i120
#ISCELL
  mstr_standard tap *
  page28_i121
#ISCELL
  mstr_standard tap *
  page28_i122
#ISCELL
  mstr_standard tap *
  page28_i123
#ISCELL
  mstr_standard tap *
  page28_i124
#ISCELL
  mstr_standard tap *
  page28_i125
#ISCELL
  mstr_standard tap *
  page28_i126
#ISCELL
  mstr_standard tap *
  page28_i127
#ISCELL
  mstr_standard tap *
  page28_i128
#ISCELL
  mstr_standard tap *
  page28_i129
#ISCELL
  mstr_standard tap *
  page28_i13
#ISCELL
  mstr_standard tap *
  page28_i130
#ISCELL
  mstr_standard tap *
  page28_i131
#ISCELL
  mstr_standard tap *
  page28_i132
#ISCELL
  mstr_standard tap *
  page28_i133
#ISCELL
  mstr_standard tap *
  page28_i134
#ISCELL
  mstr_standard tap *
  page28_i135
#ISCELL
  mstr_standard tap *
  page28_i136
#ISCELL
  mstr_standard tap *
  page28_i137
#ISCELL
  mstr_standard tap *
  page28_i138
#ISCELL
  mstr_standard tap *
  page28_i139
#ISCELL
  mstr_standard tap *
  page28_i14
#ISCELL
  mstr_standard tap *
  page28_i140
#ISCELL
  mstr_standard tap *
  page28_i141
#ISCELL
  mstr_standard tap *
  page28_i142
#ISCELL
  mstr_standard tap *
  page28_i143
#ISCELL
  mstr_standard tap *
  page28_i144
#ISCELL
  mstr_standard tap *
  page28_i145
#ISCELL
  mstr_standard tap *
  page28_i146
#ISCELL
  mstr_standard tap *
  page28_i147
#ISCELL
  mstr_standard offpage *
  page28_i148
#ISCELL
  mstr_standard offpage *
  page28_i149
#ISCELL
  mstr_standard tap *
  page28_i15
#ISCELL
  mstr_standard offpage *
  page28_i150
#ISCELL
  mstr_standard offpage *
  page28_i151
#ISCELL
  mstr_standard offpage *
  page28_i152
#ISCELL
  mstr_standard offpage *
  page28_i153
#ISCELL
  mstr_standard offpage *
  page28_i154
#ISCELL
  mstr_standard offpage *
  page28_i155
#ISCELL
  mstr_standard offpage *
  page28_i156
#ISCELL
  mstr_standard offpage *
  page28_i157
#ISCELL
  mstr_standard tap *
  page28_i158
#ISCELL
  mstr_standard tap *
  page28_i159
#ISCELL
  mstr_standard tap *
  page28_i16
#ISCELL
  mstr_standard tap *
  page28_i160
#ISCELL
  mstr_standard tap *
  page28_i161
#ISCELL
  mstr_standard tap *
  page28_i162
#ISCELL
  mstr_standard tap *
  page28_i163
#ISCELL
  mstr_standard tap *
  page28_i164
#ISCELL
  mstr_standard tap *
  page28_i165
#ISCELL
  mstr_standard tap *
  page28_i166
#ISCELL
  mstr_standard tap *
  page28_i167
#ISCELL
  mstr_standard tap *
  page28_i168
#ISCELL
  mstr_standard tap *
  page28_i169
#ISCELL
  mstr_standard tap *
  page28_i17
#ISCELL
  mstr_standard tap *
  page28_i170
#ISCELL
  mstr_standard offpage *
  page28_i171
#CELL
  chpset_lib skx_ext_b *
  page28_i172
#ISCELL
  mstr_standard tap *
  page28_i18
#ISCELL
  mstr_standard tap *
  page28_i19
#ISCELL
  mstr_standard offpage *
  page28_i2
#ISCELL
  mstr_standard tap *
  page28_i20
#ISCELL
  mstr_standard tap *
  page28_i21
#ISCELL
  mstr_standard tap *
  page28_i22
#ISCELL
  mstr_standard tap *
  page28_i23
#ISCELL
  mstr_standard tap *
  page28_i24
#ISCELL
  mstr_standard tap *
  page28_i25
#ISCELL
  mstr_standard tap *
  page28_i26
#ISCELL
  mstr_standard tap *
  page28_i27
#ISCELL
  mstr_standard tap *
  page28_i28
#ISCELL
  mstr_standard tap *
  page28_i29
#ISCELL
  mstr_standard offpage *
  page28_i3
#ISCELL
  mstr_standard tap *
  page28_i30
#ISCELL
  mstr_standard tap *
  page28_i32
#ISCELL
  mstr_standard tap *
  page28_i33
#ISCELL
  mstr_standard tap *
  page28_i34
#ISCELL
  mstr_standard tap *
  page28_i35
#ISCELL
  mstr_standard tap *
  page28_i36
#ISCELL
  mstr_standard tap *
  page28_i37
#ISCELL
  mstr_standard tap *
  page28_i38
#ISCELL
  mstr_standard tap *
  page28_i39
#ISCELL
  mstr_standard offpage *
  page28_i4
#ISCELL
  mstr_standard tap *
  page28_i40
#ISCELL
  mstr_standard tap *
  page28_i41
#ISCELL
  mstr_standard tap *
  page28_i42
#ISCELL
  mstr_standard tap *
  page28_i43
#ISCELL
  mstr_standard tap *
  page28_i44
#ISCELL
  mstr_standard tap *
  page28_i45
#ISCELL
  mstr_standard tap *
  page28_i46
#ISCELL
  mstr_standard tap *
  page28_i47
#ISCELL
  mstr_standard tap *
  page28_i48
#ISCELL
  mstr_standard tap *
  page28_i49
#ISCELL
  mstr_standard tap *
  page28_i5
#ISCELL
  mstr_standard tap *
  page28_i50
#ISCELL
  mstr_standard tap *
  page28_i51
#ISCELL
  mstr_standard tap *
  page28_i52
#ISCELL
  mstr_standard tap *
  page28_i53
#ISCELL
  mstr_standard tap *
  page28_i54
#ISCELL
  mstr_standard tap *
  page28_i55
#ISCELL
  mstr_standard tap *
  page28_i56
#ISCELL
  mstr_standard tap *
  page28_i57
#ISCELL
  mstr_standard tap *
  page28_i58
#ISCELL
  mstr_standard tap *
  page28_i59
#ISCELL
  mstr_standard tap *
  page28_i6
#ISCELL
  mstr_standard tap *
  page28_i60
#ISCELL
  mstr_standard tap *
  page28_i61
#ISCELL
  mstr_standard tap *
  page28_i62
#ISCELL
  mstr_standard tap *
  page28_i63
#ISCELL
  mstr_standard tap *
  page28_i64
#ISCELL
  mstr_standard tap *
  page28_i65
#ISCELL
  mstr_standard tap *
  page28_i66
#ISCELL
  mstr_standard tap *
  page28_i67
#ISCELL
  mstr_standard tap *
  page28_i68
#ISCELL
  mstr_standard tap *
  page28_i69
#ISCELL
  mstr_standard tap *
  page28_i7
#ISCELL
  mstr_standard tap *
  page28_i70
#ISCELL
  mstr_standard tap *
  page28_i71
#ISCELL
  mstr_standard tap *
  page28_i72
#ISCELL
  mstr_standard offpage *
  page28_i73
#ISCELL
  mstr_standard tap *
  page28_i74
#ISCELL
  mstr_standard tap *
  page28_i75
#ISCELL
  mstr_standard tap *
  page28_i76
#ISCELL
  mstr_standard tap *
  page28_i77
#ISCELL
  mstr_standard tap *
  page28_i78
#ISCELL
  mstr_standard tap *
  page28_i79
#ISCELL
  mstr_standard tap *
  page28_i8
#ISCELL
  mstr_standard tap *
  page28_i80
#ISCELL
  mstr_standard tap *
  page28_i81
#ISCELL
  mstr_standard tap *
  page28_i82
#ISCELL
  mstr_standard tap *
  page28_i83
#ISCELL
  mstr_standard tap *
  page28_i84
#ISCELL
  mstr_standard tap *
  page28_i85
#ISCELL
  mstr_standard tap *
  page28_i86
#ISCELL
  mstr_standard tap *
  page28_i87
#ISCELL
  mstr_standard tap *
  page28_i88
#ISCELL
  mstr_standard tap *
  page28_i89
#ISCELL
  mstr_standard tap *
  page28_i9
#ISCELL
  mstr_standard tap *
  page28_i90
#ISCELL
  mstr_standard tap *
  page28_i91
#ISCELL
  mstr_standard tap *
  page28_i92
#ISCELL
  mstr_standard tap *
  page28_i93
#ISCELL
  mstr_standard tap *
  page28_i94
#ISCELL
  mstr_standard tap *
  page28_i95
#ISCELL
  mstr_standard tap *
  page28_i96
#ISCELL
  mstr_standard tap *
  page28_i97
#ISCELL
  mstr_standard tap *
  page28_i98
#ISCELL
  mstr_standard tap *
  page28_i99
#ISCELL
  mstr_misc prelim *
  *
#ISCELL
  mstr_symbols design_note *
  *
#ISCELL
  mstr_symbols intel_corp_bpage *
  *
#ISCELL
  mstr_standard tap *
  page29_i10
#ISCELL
  mstr_standard tap *
  page29_i11
#ISCELL
  mstr_standard tap *
  page29_i12
#ISCELL
  mstr_standard tap *
  page29_i13
#ISCELL
  mstr_standard tap *
  page29_i14
#ISCELL
  mstr_standard tap *
  page29_i16
#ISCELL
  mstr_standard tap *
  page29_i17
#ISCELL
  mstr_standard tap *
  page29_i18
#ISCELL
  mstr_standard tap *
  page29_i19
#ISCELL
  mstr_standard tap *
  page29_i20
#ISCELL
  mstr_standard tap *
  page29_i21
#ISCELL
  mstr_standard tap *
  page29_i22
#ISCELL
  mstr_standard tap *
  page29_i23
#ISCELL
  mstr_standard offpage *
  page29_i25
#ISCELL
  mstr_standard offpage *
  page29_i26
#ISCELL
  mstr_standard offpage *
  page29_i27
#ISCELL
  mstr_standard offpage *
  page29_i28
#ISCELL
  mstr_standard offpage *
  page29_i29
#ISCELL
  mstr_standard offpage *
  page29_i31
#ISCELL
  mstr_standard offpage *
  page29_i35
#ISCELL
  mstr_standard offpage *
  page29_i36
#ISCELL
  mstr_standard offpage *
  page29_i40
#ISCELL
  mstr_standard offpage *
  page29_i41
#ISCELL
  mstr_standard offpage *
  page29_i42
#ISCELL
  mstr_standard offpage *
  page29_i43
#ISCELL
  mstr_standard offpage *
  page29_i44
#ISCELL
  mstr_standard offpage *
  page29_i45
#ISCELL
  mstr_standard offpage *
  page29_i46
#ISCELL
  mstr_standard offpage *
  page29_i47
#ISCELL
  mstr_standard offpage *
  page29_i48
#ISCELL
  mstr_standard offpage *
  page29_i49
#ISCELL
  mstr_standard offpage *
  page29_i5
#ISCELL
  mstr_standard offpage *
  page29_i50
#ISCELL
  mstr_standard offpage *
  page29_i51
#ISCELL
  mstr_standard offpage *
  page29_i52
#ISCELL
  mstr_standard offpage *
  page29_i53
#ISCELL
  mstr_standard offpage *
  page29_i54
#ISCELL
  mstr_standard offpage *
  page29_i58
#ISCELL
  mstr_standard offpage *
  page29_i6
#ISCELL
  mstr_symbols vcc_core *
  page29_i60
#CELL
  chpset_lib skx_ext_b *
  page29_i61
#ISCELL
  mstr_standard tap *
  page29_i7
#ISCELL
  mstr_standard tap *
  page29_i8
#ISCELL
  mstr_standard tap *
  page29_i9
#ISCELL
  mstr_misc prelim *
  *
#ISCELL
  mstr_symbols design_note *
  *
#ISCELL
  mstr_symbols intel_corp_bpage *
  *
#ISCELL
  mstr_standard tap *
  page30_i1
#ISCELL
  mstr_standard tap *
  page30_i10
#ISCELL
  mstr_standard tap *
  page30_i11
#ISCELL
  mstr_standard tap *
  page30_i12
#ISCELL
  mstr_standard tap *
  page30_i13
#ISCELL
  mstr_standard tap *
  page30_i14
#ISCELL
  mstr_standard tap *
  page30_i15
#ISCELL
  mstr_standard tap *
  page30_i16
#ISCELL
  mstr_standard tap *
  page30_i17
#ISCELL
  mstr_standard tap *
  page30_i18
#ISCELL
  mstr_standard tap *
  page30_i19
#ISCELL
  mstr_standard tap *
  page30_i2
#ISCELL
  mstr_standard tap *
  page30_i20
#ISCELL
  mstr_standard tap *
  page30_i21
#ISCELL
  mstr_standard tap *
  page30_i22
#ISCELL
  mstr_standard tap *
  page30_i24
#ISCELL
  mstr_standard tap *
  page30_i25
#ISCELL
  mstr_standard tap *
  page30_i26
#ISCELL
  mstr_standard tap *
  page30_i27
#ISCELL
  mstr_standard tap *
  page30_i28
#ISCELL
  mstr_standard tap *
  page30_i29
#ISCELL
  mstr_standard tap *
  page30_i3
#ISCELL
  mstr_standard tap *
  page30_i30
#ISCELL
  mstr_standard tap *
  page30_i31
#ISCELL
  mstr_standard tap *
  page30_i32
#ISCELL
  mstr_standard tap *
  page30_i33
#ISCELL
  mstr_standard tap *
  page30_i34
#ISCELL
  mstr_standard tap *
  page30_i35
#ISCELL
  mstr_standard tap *
  page30_i36
#ISCELL
  mstr_standard tap *
  page30_i37
#ISCELL
  mstr_standard tap *
  page30_i38
#ISCELL
  mstr_standard tap *
  page30_i39
#ISCELL
  mstr_standard tap *
  page30_i40
#ISCELL
  mstr_standard tap *
  page30_i41
#ISCELL
  mstr_standard tap *
  page30_i42
#ISCELL
  mstr_standard tap *
  page30_i43
#ISCELL
  mstr_standard tap *
  page30_i44
#ISCELL
  mstr_standard tap *
  page30_i45
#ISCELL
  mstr_standard tap *
  page30_i46
#ISCELL
  mstr_standard tap *
  page30_i47
#ISCELL
  mstr_standard tap *
  page30_i48
#ISCELL
  mstr_standard tap *
  page30_i49
#ISCELL
  mstr_standard tap *
  page30_i51
#ISCELL
  mstr_standard tap *
  page30_i52
#ISCELL
  mstr_standard tap *
  page30_i53
#ISCELL
  mstr_standard tap *
  page30_i54
#ISCELL
  mstr_standard tap *
  page30_i55
#ISCELL
  mstr_standard tap *
  page30_i56
#ISCELL
  mstr_standard tap *
  page30_i57
#ISCELL
  mstr_standard tap *
  page30_i58
#ISCELL
  mstr_standard tap *
  page30_i59
#ISCELL
  mstr_standard tap *
  page30_i6
#ISCELL
  mstr_standard tap *
  page30_i60
#ISCELL
  mstr_standard tap *
  page30_i61
#ISCELL
  mstr_standard tap *
  page30_i62
#ISCELL
  mstr_standard tap *
  page30_i64
#ISCELL
  mstr_standard tap *
  page30_i65
#ISCELL
  mstr_standard tap *
  page30_i66
#ISCELL
  mstr_standard tap *
  page30_i67
#ISCELL
  mstr_standard tap *
  page30_i7
#ISCELL
  mstr_standard offpage *
  page30_i70
#ISCELL
  mstr_standard offpage *
  page30_i71
#ISCELL
  mstr_standard offpage *
  page30_i74
#ISCELL
  mstr_standard offpage *
  page30_i75
#ISCELL
  mstr_standard tap *
  page30_i78
#ISCELL
  mstr_standard tap *
  page30_i79
#ISCELL
  mstr_standard tap *
  page30_i8
#ISCELL
  mstr_standard offpage *
  page30_i80
#ISCELL
  mstr_standard offpage *
  page30_i81
#ISCELL
  mstr_standard offpage *
  page30_i82
#ISCELL
  mstr_standard offpage *
  page30_i83
#CELL
  chpset_lib skx_ext_b *
  page30_i84
#ISCELL
  mstr_standard tap *
  page30_i9
#ISCELL
  mstr_misc prelim *
  *
#ISCELL
  mstr_symbols design_note *
  *
#ISCELL
  mstr_symbols intel_corp_bpage *
  *
#ISCELL
  mstr_standard tap *
  page31_i10
#ISCELL
  mstr_standard tap *
  page31_i100
#ISCELL
  mstr_standard tap *
  page31_i101
#ISCELL
  mstr_standard tap *
  page31_i102
#ISCELL
  mstr_standard tap *
  page31_i103
#ISCELL
  mstr_standard offpage *
  page31_i104
#ISCELL
  mstr_standard offpage *
  page31_i105
#CELL
  chpset_lib skx_ext_b *
  page31_i106
#ISCELL
  mstr_standard tap *
  page31_i11
#ISCELL
  mstr_standard tap *
  page31_i12
#ISCELL
  mstr_standard tap *
  page31_i13
#ISCELL
  mstr_standard tap *
  page31_i14
#ISCELL
  mstr_standard tap *
  page31_i15
#ISCELL
  mstr_standard tap *
  page31_i16
#ISCELL
  mstr_standard tap *
  page31_i17
#ISCELL
  mstr_standard tap *
  page31_i18
#ISCELL
  mstr_standard tap *
  page31_i19
#ISCELL
  mstr_standard tap *
  page31_i3
#ISCELL
  mstr_standard tap *
  page31_i36
#ISCELL
  mstr_standard tap *
  page31_i37
#ISCELL
  mstr_standard tap *
  page31_i38
#ISCELL
  mstr_standard tap *
  page31_i39
#ISCELL
  mstr_standard tap *
  page31_i4
#ISCELL
  mstr_standard tap *
  page31_i40
#ISCELL
  mstr_standard tap *
  page31_i41
#ISCELL
  mstr_standard tap *
  page31_i42
#ISCELL
  mstr_standard tap *
  page31_i43
#ISCELL
  mstr_standard tap *
  page31_i44
#ISCELL
  mstr_standard tap *
  page31_i45
#ISCELL
  mstr_standard tap *
  page31_i46
#ISCELL
  mstr_standard tap *
  page31_i47
#ISCELL
  mstr_standard tap *
  page31_i48
#ISCELL
  mstr_standard tap *
  page31_i49
#ISCELL
  mstr_standard tap *
  page31_i5
#ISCELL
  mstr_standard tap *
  page31_i50
#ISCELL
  mstr_standard tap *
  page31_i51
#ISCELL
  mstr_standard tap *
  page31_i6
#ISCELL
  mstr_standard tap *
  page31_i7
#ISCELL
  mstr_standard offpage *
  page31_i70
#ISCELL
  mstr_standard offpage *
  page31_i71
#ISCELL
  mstr_standard tap *
  page31_i72
#ISCELL
  mstr_standard tap *
  page31_i73
#ISCELL
  mstr_standard tap *
  page31_i74
#ISCELL
  mstr_standard tap *
  page31_i75
#ISCELL
  mstr_standard tap *
  page31_i76
#ISCELL
  mstr_standard tap *
  page31_i77
#ISCELL
  mstr_standard tap *
  page31_i78
#ISCELL
  mstr_standard tap *
  page31_i79
#ISCELL
  mstr_standard tap *
  page31_i80
#ISCELL
  mstr_standard tap *
  page31_i81
#ISCELL
  mstr_standard tap *
  page31_i82
#ISCELL
  mstr_standard tap *
  page31_i83
#ISCELL
  mstr_standard tap *
  page31_i84
#ISCELL
  mstr_standard tap *
  page31_i85
#ISCELL
  mstr_standard tap *
  page31_i86
#ISCELL
  mstr_standard tap *
  page31_i87
#ISCELL
  mstr_standard tap *
  page31_i88
#ISCELL
  mstr_standard tap *
  page31_i89
#ISCELL
  mstr_standard tap *
  page31_i9
#ISCELL
  mstr_standard tap *
  page31_i90
#ISCELL
  mstr_standard tap *
  page31_i91
#ISCELL
  mstr_standard tap *
  page31_i92
#ISCELL
  mstr_standard tap *
  page31_i93
#ISCELL
  mstr_standard tap *
  page31_i94
#ISCELL
  mstr_standard tap *
  page31_i95
#ISCELL
  mstr_standard tap *
  page31_i96
#ISCELL
  mstr_standard tap *
  page31_i97
#ISCELL
  mstr_standard tap *
  page31_i98
#ISCELL
  mstr_standard tap *
  page31_i99
#ISCELL
  mstr_misc prelim *
  *
#ISCELL
  mstr_symbols design_note *
  *
#ISCELL
  mstr_symbols intel_corp_bpage *
  *
#ISCELL
  mstr_standard offpage *
  page32_i1
#ISCELL
  mstr_standard tap *
  page32_i15
#ISCELL
  mstr_standard offpage *
  page32_i2
#ISCELL
  mstr_standard tap *
  page32_i20
#ISCELL
  mstr_standard tap *
  page32_i21
#ISCELL
  mstr_standard tap *
  page32_i22
#ISCELL
  mstr_standard tap *
  page32_i23
#ISCELL
  mstr_standard tap *
  page32_i24
#ISCELL
  mstr_standard tap *
  page32_i25
#ISCELL
  mstr_standard tap *
  page32_i26
#ISCELL
  mstr_standard tap *
  page32_i27
#ISCELL
  mstr_standard tap *
  page32_i28
#ISCELL
  mstr_standard tap *
  page32_i29
#ISCELL
  mstr_standard tap *
  page32_i3
#ISCELL
  mstr_standard tap *
  page32_i30
#ISCELL
  mstr_standard tap *
  page32_i31
#ISCELL
  mstr_standard tap *
  page32_i32
#ISCELL
  mstr_standard tap *
  page32_i33
#ISCELL
  mstr_standard tap *
  page32_i34
#ISCELL
  mstr_standard tap *
  page32_i35
#ISCELL
  mstr_standard tap *
  page32_i36
#ISCELL
  mstr_standard tap *
  page32_i37
#ISCELL
  mstr_standard tap *
  page32_i38
#ISCELL
  mstr_standard tap *
  page32_i39
#ISCELL
  mstr_standard tap *
  page32_i4
#ISCELL
  mstr_standard tap *
  page32_i40
#ISCELL
  mstr_standard tap *
  page32_i41
#ISCELL
  mstr_standard tap *
  page32_i42
#ISCELL
  mstr_standard tap *
  page32_i43
#ISCELL
  mstr_standard tap *
  page32_i44
#ISCELL
  mstr_standard tap *
  page32_i45
#ISCELL
  mstr_standard tap *
  page32_i46
#ISCELL
  mstr_standard tap *
  page32_i47
#ISCELL
  mstr_standard tap *
  page32_i48
#ISCELL
  mstr_standard tap *
  page32_i49
#ISCELL
  mstr_standard tap *
  page32_i5
#ISCELL
  mstr_standard tap *
  page32_i50
#ISCELL
  mstr_standard tap *
  page32_i51
#ISCELL
  mstr_standard tap *
  page32_i52
#ISCELL
  mstr_standard tap *
  page32_i53
#ISCELL
  mstr_standard tap *
  page32_i54
#ISCELL
  mstr_standard tap *
  page32_i55
#ISCELL
  mstr_standard tap *
  page32_i56
#ISCELL
  mstr_standard tap *
  page32_i57
#ISCELL
  mstr_standard tap *
  page32_i58
#ISCELL
  mstr_standard tap *
  page32_i59
#ISCELL
  mstr_standard tap *
  page32_i6
#ISCELL
  mstr_standard tap *
  page32_i60
#ISCELL
  mstr_standard tap *
  page32_i61
#ISCELL
  mstr_standard tap *
  page32_i62
#ISCELL
  mstr_standard tap *
  page32_i63
#ISCELL
  mstr_standard tap *
  page32_i64
#ISCELL
  mstr_standard tap *
  page32_i65
#ISCELL
  mstr_standard tap *
  page32_i66
#ISCELL
  mstr_standard tap *
  page32_i67
#ISCELL
  mstr_standard offpage *
  page32_i68
#ISCELL
  mstr_standard offpage *
  page32_i69
#ISCELL
  mstr_standard tap *
  page32_i7
#ISCELL
  mstr_standard tap *
  page32_i8
#ISCELL
  mstr_standard tap *
  page32_i81
#ISCELL
  mstr_standard tap *
  page32_i82
#ISCELL
  mstr_standard tap *
  page32_i83
#ISCELL
  mstr_standard tap *
  page32_i84
#ISCELL
  mstr_standard tap *
  page32_i85
#ISCELL
  mstr_standard tap *
  page32_i86
#ISCELL
  mstr_standard tap *
  page32_i87
#ISCELL
  mstr_standard tap *
  page32_i88
#CELL
  chpset_lib skx_ext_b *
  page32_i89
#ISCELL
  mstr_standard tap *
  page32_i9
#ISCELL
  mstr_misc prelim *
  *
#ISCELL
  mstr_symbols design_note *
  *
#ISCELL
  mstr_symbols intel_corp_bpage *
  *
#ISCELL
  mstr_standard offpage *
  page33_i1
#ISCELL
  mstr_standard tap *
  page33_i10
#ISCELL
  mstr_standard tap *
  page33_i11
#ISCELL
  mstr_standard tap *
  page33_i13
#ISCELL
  mstr_standard tap *
  page33_i14
#ISCELL
  mstr_standard tap *
  page33_i15
#ISCELL
  mstr_standard tap *
  page33_i16
#ISCELL
  mstr_standard tap *
  page33_i17
#ISCELL
  mstr_standard tap *
  page33_i18
#ISCELL
  mstr_standard tap *
  page33_i19
#ISCELL
  mstr_standard offpage *
  page33_i2
#ISCELL
  mstr_standard tap *
  page33_i20
#ISCELL
  mstr_standard tap *
  page33_i21
#ISCELL
  mstr_standard tap *
  page33_i22
#ISCELL
  mstr_standard tap *
  page33_i23
#ISCELL
  mstr_standard tap *
  page33_i24
#ISCELL
  mstr_standard tap *
  page33_i25
#ISCELL
  mstr_standard tap *
  page33_i26
#ISCELL
  mstr_standard tap *
  page33_i27
#ISCELL
  mstr_standard tap *
  page33_i28
#ISCELL
  mstr_standard tap *
  page33_i29
#ISCELL
  mstr_standard tap *
  page33_i3
#ISCELL
  mstr_standard tap *
  page33_i30
#ISCELL
  mstr_standard tap *
  page33_i31
#ISCELL
  mstr_standard tap *
  page33_i32
#ISCELL
  mstr_standard tap *
  page33_i33
#ISCELL
  mstr_standard tap *
  page33_i34
#ISCELL
  mstr_standard tap *
  page33_i35
#ISCELL
  mstr_standard tap *
  page33_i36
#ISCELL
  mstr_standard tap *
  page33_i37
#ISCELL
  mstr_standard tap *
  page33_i38
#ISCELL
  mstr_standard tap *
  page33_i39
#ISCELL
  mstr_standard tap *
  page33_i4
#ISCELL
  mstr_standard tap *
  page33_i40
#ISCELL
  mstr_standard tap *
  page33_i41
#ISCELL
  mstr_standard tap *
  page33_i42
#ISCELL
  mstr_standard tap *
  page33_i43
#ISCELL
  mstr_standard tap *
  page33_i44
#ISCELL
  mstr_standard tap *
  page33_i45
#ISCELL
  mstr_standard tap *
  page33_i46
#ISCELL
  mstr_standard tap *
  page33_i47
#ISCELL
  mstr_standard tap *
  page33_i48
#ISCELL
  mstr_standard tap *
  page33_i49
#ISCELL
  mstr_standard tap *
  page33_i5
#ISCELL
  mstr_standard tap *
  page33_i50
#ISCELL
  mstr_standard tap *
  page33_i51
#ISCELL
  mstr_standard tap *
  page33_i52
#ISCELL
  mstr_standard tap *
  page33_i53
#ISCELL
  mstr_standard tap *
  page33_i54
#ISCELL
  mstr_standard tap *
  page33_i55
#ISCELL
  mstr_standard tap *
  page33_i56
#ISCELL
  mstr_standard tap *
  page33_i57
#ISCELL
  mstr_standard tap *
  page33_i58
#ISCELL
  mstr_standard tap *
  page33_i59
#ISCELL
  mstr_standard tap *
  page33_i6
#ISCELL
  mstr_standard tap *
  page33_i60
#ISCELL
  mstr_standard tap *
  page33_i61
#ISCELL
  mstr_standard tap *
  page33_i62
#ISCELL
  mstr_standard tap *
  page33_i63
#ISCELL
  mstr_standard tap *
  page33_i64
#ISCELL
  mstr_standard tap *
  page33_i65
#ISCELL
  mstr_standard tap *
  page33_i66
#ISCELL
  mstr_standard tap *
  page33_i67
#ISCELL
  mstr_standard tap *
  page33_i68
#ISCELL
  mstr_standard tap *
  page33_i69
#ISCELL
  mstr_standard tap *
  page33_i7
#ISCELL
  mstr_standard tap *
  page33_i70
#ISCELL
  mstr_standard tap *
  page33_i71
#ISCELL
  mstr_standard tap *
  page33_i72
#ISCELL
  mstr_standard tap *
  page33_i73
#ISCELL
  mstr_standard tap *
  page33_i74
#ISCELL
  mstr_standard tap *
  page33_i75
#ISCELL
  mstr_standard tap *
  page33_i76
#ISCELL
  mstr_standard tap *
  page33_i77
#ISCELL
  mstr_standard tap *
  page33_i78
#ISCELL
  mstr_standard tap *
  page33_i79
#ISCELL
  mstr_standard tap *
  page33_i8
#ISCELL
  mstr_standard tap *
  page33_i80
#ISCELL
  mstr_standard tap *
  page33_i81
#ISCELL
  mstr_standard tap *
  page33_i82
#ISCELL
  mstr_standard tap *
  page33_i83
#ISCELL
  mstr_standard offpage *
  page33_i84
#ISCELL
  mstr_standard offpage *
  page33_i85
#CELL
  chpset_lib skx_ext_b *
  page33_i86
#ISCELL
  mstr_standard tap *
  page33_i9
#ISCELL
  mstr_misc prelim *
  *
#ISCELL
  mstr_symbols design_note *
  *
#ISCELL
  mstr_symbols intel_corp_bpage *
  *
#ISCELL
  mstr_standard offpage *
  page34_i1
#ISCELL
  mstr_standard tap *
  page34_i10
#ISCELL
  mstr_standard tap *
  page34_i11
#ISCELL
  mstr_standard tap *
  page34_i12
#ISCELL
  mstr_standard tap *
  page34_i13
#ISCELL
  mstr_standard tap *
  page34_i14
#ISCELL
  mstr_standard tap *
  page34_i15
#ISCELL
  mstr_standard tap *
  page34_i16
#ISCELL
  mstr_standard tap *
  page34_i17
#ISCELL
  mstr_standard tap *
  page34_i18
#ISCELL
  mstr_standard tap *
  page34_i19
#ISCELL
  mstr_standard offpage *
  page34_i2
#ISCELL
  mstr_standard tap *
  page34_i20
#ISCELL
  mstr_standard tap *
  page34_i21
#ISCELL
  mstr_standard tap *
  page34_i22
#ISCELL
  mstr_standard tap *
  page34_i23
#ISCELL
  mstr_standard tap *
  page34_i24
#ISCELL
  mstr_standard tap *
  page34_i25
#ISCELL
  mstr_standard tap *
  page34_i26
#ISCELL
  mstr_standard tap *
  page34_i27
#ISCELL
  mstr_standard tap *
  page34_i28
#ISCELL
  mstr_standard tap *
  page34_i29
#ISCELL
  mstr_standard tap *
  page34_i3
#ISCELL
  mstr_standard tap *
  page34_i30
#ISCELL
  mstr_standard tap *
  page34_i31
#ISCELL
  mstr_standard tap *
  page34_i32
#ISCELL
  mstr_standard tap *
  page34_i33
#ISCELL
  mstr_standard tap *
  page34_i34
#ISCELL
  mstr_standard tap *
  page34_i35
#ISCELL
  mstr_standard tap *
  page34_i36
#ISCELL
  mstr_standard tap *
  page34_i37
#ISCELL
  mstr_standard tap *
  page34_i38
#ISCELL
  mstr_standard tap *
  page34_i39
#ISCELL
  mstr_standard tap *
  page34_i4
#ISCELL
  mstr_standard tap *
  page34_i40
#ISCELL
  mstr_standard tap *
  page34_i41
#ISCELL
  mstr_standard tap *
  page34_i42
#ISCELL
  mstr_standard tap *
  page34_i43
#ISCELL
  mstr_standard tap *
  page34_i44
#ISCELL
  mstr_standard tap *
  page34_i45
#ISCELL
  mstr_standard tap *
  page34_i46
#ISCELL
  mstr_standard tap *
  page34_i47
#ISCELL
  mstr_standard tap *
  page34_i48
#ISCELL
  mstr_standard tap *
  page34_i49
#ISCELL
  mstr_standard tap *
  page34_i5
#ISCELL
  mstr_standard tap *
  page34_i50
#ISCELL
  mstr_standard tap *
  page34_i51
#ISCELL
  mstr_standard tap *
  page34_i52
#ISCELL
  mstr_standard tap *
  page34_i53
#ISCELL
  mstr_standard tap *
  page34_i54
#ISCELL
  mstr_standard tap *
  page34_i55
#ISCELL
  mstr_standard tap *
  page34_i56
#ISCELL
  mstr_standard tap *
  page34_i57
#ISCELL
  mstr_standard tap *
  page34_i58
#ISCELL
  mstr_standard tap *
  page34_i59
#ISCELL
  mstr_standard tap *
  page34_i6
#ISCELL
  mstr_standard tap *
  page34_i60
#ISCELL
  mstr_standard tap *
  page34_i61
#ISCELL
  mstr_standard tap *
  page34_i62
#ISCELL
  mstr_standard tap *
  page34_i63
#ISCELL
  mstr_standard tap *
  page34_i64
#ISCELL
  mstr_standard tap *
  page34_i65
#ISCELL
  mstr_standard tap *
  page34_i66
#ISCELL
  mstr_standard tap *
  page34_i67
#ISCELL
  mstr_standard tap *
  page34_i68
#ISCELL
  mstr_standard tap *
  page34_i69
#ISCELL
  mstr_standard tap *
  page34_i7
#ISCELL
  mstr_standard tap *
  page34_i70
#ISCELL
  mstr_standard tap *
  page34_i71
#ISCELL
  mstr_standard tap *
  page34_i72
#ISCELL
  mstr_standard tap *
  page34_i73
#ISCELL
  mstr_standard tap *
  page34_i74
#ISCELL
  mstr_standard tap *
  page34_i75
#ISCELL
  mstr_standard tap *
  page34_i76
#ISCELL
  mstr_standard tap *
  page34_i77
#ISCELL
  mstr_standard tap *
  page34_i78
#ISCELL
  mstr_standard tap *
  page34_i79
#ISCELL
  mstr_standard tap *
  page34_i80
#ISCELL
  mstr_standard tap *
  page34_i81
#ISCELL
  mstr_standard tap *
  page34_i82
#ISCELL
  mstr_standard tap *
  page34_i83
#ISCELL
  mstr_standard offpage *
  page34_i84
#ISCELL
  mstr_standard offpage *
  page34_i85
#CELL
  chpset_lib skx_ext_b *
  page34_i86
#ISCELL
  mstr_standard tap *
  page34_i9
#ISCELL
  mstr_symbols design_note *
  *
#ISCELL
  mstr_symbols intel_corp_bpage *
  *
#ISCELL
  mstr_symbols gnd *
  page35_i2
#CELL
  chpset_lib skx_ext_b *
  page35_i3
#ISCELL
  mstr_symbols design_note *
  *
#ISCELL
  mstr_symbols intel_corp_bpage *
  *
#ISCELL
  mstr_symbols vcc_core *
  page36_i12
#ISCELL
  mstr_symbols vcc_core *
  page36_i13
#ISCELL
  mstr_symbols vcc_core *
  page36_i14
#CELL
  chpset_lib skx_ext_b *
  page36_i15
#CELL
  chpset_lib skx_ext_b *
  page36_i16
#ISCELL
  mstr_standard offpage *
  page36_i5
#ISCELL
  mstr_standard offpage *
  page36_i8
#ISCELL
  mstr_misc dns *
  *
#ISCELL
  mstr_misc prelim *
  *
#ISCELL
  mstr_symbols design_note *
  *
#ISCELL
  mstr_symbols intel_corp_bpage *
  *
#ISCELL
  mstr_symbols pvccin_cpu0 *
  page37_i295
#ISCELL
  mstr_symbols pvccin_cpu0 *
  page37_i296
#ISCELL
  mstr_standard offpage *
  page37_i298
#ISCELL
  mstr_standard offpage *
  page37_i299
#ISCELL
  mstr_symbols pvccin_cpu0 *
  page37_i300
#ISCELL
  mstr_symbols pvccin_cpu0 *
  page37_i301
#ISCELL
  mstr_symbols gnd *
  page37_i302
#CELL
  mstr_discrete res *
  page37_i303
#ISCELL
  mstr_symbols pvccin_cpu0 *
  page37_i305
#CELL
  mstr_discrete res *
  page37_i309
#CELL
  chpset_lib skx_ext_b *
  page37_i310
#CELL
  chpset_lib skx_ext_b *
  page37_i311
#CELL
  mstr_discrete res *
  page37_i312
#ISCELL
  mstr_symbols pvccio_cpu0 *
  page37_i313
#ISCELL
  mstr_symbols design_note *
  *
#ISCELL
  mstr_symbols intel_corp_bpage *
  *
#ISCELL
  mstr_symbols pvddq_abc *
  page38_i11
#ISCELL
  mstr_symbols pvddq_def *
  page38_i12
#ISCELL
  mstr_symbols pvccio_cpu0 *
  page38_i14
#ISCELL
  mstr_symbols gnd *
  page38_i16
#ISCELL
  mstr_symbols pvccio_cpu0 *
  page38_i17
#CELL
  mstr_discrete cap *
  page38_i19
#ISCELL
  mstr_symbols pvsa_cpu0 *
  page38_i24
#ISCELL
  mstr_symbols vcc_core *
  page38_i25
#ISCELL
  mstr_symbols vcc_core *
  page38_i26
#ISCELL
  mstr_symbols pvpp_abc *
  page38_i31
#CELL
  chpset_lib skx_ext_b *
  page38_i33
#CELL
  chpset_lib skx_ext_b *
  page38_i34
#ISCELL
  mstr_symbols vcc_core *
  page38_i35
#ISCELL
  mstr_symbols p3v3_stby *
  page38_i36
#ISCELL
  mstr_misc prelim *
  *
#ISCELL
  mstr_symbols design_note *
  *
#ISCELL
  mstr_symbols intel_corp_bpage *
  *
#ISCELL
  mstr_standard offpage *
  page39_i122
#ISCELL
  mstr_symbols vcc_core *
  page39_i123
#ISCELL
  mstr_symbols vcc_core *
  page39_i125
#ISCELL
  mstr_symbols vcc_core *
  page39_i126
#CELL
  chpset_lib skx_ext_b *
  page39_i127
#ISCELL
  mstr_symbols pvccio_cpu0 *
  page39_i23
#ISCELL
  mstr_standard offpage *
  page39_i33
#ISCELL
  mstr_standard offpage *
  page39_i34
#ISCELL
  mstr_standard offpage *
  page39_i35
#ISCELL
  mstr_standard offpage *
  page39_i36
#ISCELL
  mstr_standard offpage *
  page39_i37
#ISCELL
  mstr_standard offpage *
  page39_i38
#ISCELL
  mstr_standard offpage *
  page39_i39
#ISCELL
  mstr_standard offpage *
  page39_i40
#ISCELL
  mstr_misc prelim *
  *
#ISCELL
  mstr_symbols design_note *
  *
#ISCELL
  mstr_symbols intel_corp_bpage *
  *
#ISCELL
  mstr_symbols gnd *
  page40_i11
#ISCELL
  mstr_symbols gnd *
  page40_i13
#ISCELL
  mstr_symbols gnd *
  page40_i14
#CELL
  chpset_lib skx_ext_b *
  page40_i20
#CELL
  chpset_lib skx_ext_b *
  page40_i21
#CELL
  chpset_lib skx_ext_b *
  page40_i22
#CELL
  chpset_lib skx_ext_b *
  page40_i23
#ISCELL
  mstr_symbols gnd *
  page40_i3
#ISCELL
  mstr_symbols gnd *
  page40_i4
#ISCELL
  mstr_symbols gnd *
  page40_i5
#ISCELL
  mstr_symbols gnd *
  page40_i6
#ISCELL
  mstr_symbols gnd *
  page40_i9
#ISCELL
  mstr_symbols design_note *
  *
#ISCELL
  mstr_symbols intel_corp_bpage *
  *
#ISCELL
  mstr_symbols gnd *
  page41_i275
#ISCELL
  mstr_symbols gnd *
  page41_i276
#ISCELL
  mstr_symbols gnd *
  page41_i277
#ISCELL
  mstr_symbols gnd *
  page41_i278
#ISCELL
  mstr_symbols gnd *
  page41_i279
#ISCELL
  mstr_symbols gnd *
  page41_i280
#ISCELL
  mstr_symbols gnd *
  page41_i281
#ISCELL
  mstr_symbols gnd *
  page41_i282
#CELL
  chpset_lib skx_ext_b *
  page41_i283
#CELL
  chpset_lib skx_ext_b *
  page41_i284
#CELL
  chpset_lib skx_ext_b *
  page41_i285
#CELL
  chpset_lib skx_ext_b *
  page41_i286
#ISCELL
  mstr_symbols design_note *
  *
#ISCELL
  mstr_symbols intel_corp_bpage *
  *
#CELL
  mstr_discrete cap *
  page42_i10
#CELL
  dev_discrete cap_a *
  page42_i100
#ISCELL
  mstr_symbols gnd *
  page42_i101
#CELL
  dev_discrete cap_a *
  page42_i102
#CELL
  dev_discrete cap_a *
  page42_i103
#CELL
  dev_discrete cap_a *
  page42_i104
#ISCELL
  mstr_symbols gnd *
  page42_i105
#CELL
  dev_discrete cap_a *
  page42_i106
#CELL
  dev_discrete cap_a *
  page42_i107
#CELL
  mstr_discrete cap *
  page42_i108
#CELL
  dev_discrete cap_a *
  page42_i109
#ISCELL
  mstr_symbols gnd *
  page42_i110
#CELL
  dev_discrete cap_a *
  page42_i111
#CELL
  dev_discrete cap_a *
  page42_i112
#CELL
  dev_discrete cap_a *
  page42_i113
#CELL
  dev_discrete cap_a *
  page42_i114
#CELL
  dev_discrete cap_a *
  page42_i115
#ISCELL
  mstr_symbols pvccin_cpu0 *
  page42_i116
#CELL
  dev_discrete cap_a *
  page42_i117
#CELL
  dev_discrete cap_a *
  page42_i118
#ISCELL
  mstr_symbols pvccin_cpu0 *
  page42_i119
#CELL
  mstr_discrete cap *
  page42_i12
#CELL
  dev_discrete cap_a *
  page42_i120
#ISCELL
  mstr_symbols pvccin_cpu0 *
  page42_i121
#ISCELL
  mstr_symbols gnd *
  page42_i122
#CELL
  dev_discrete cap_a *
  page42_i123
#ISCELL
  mstr_symbols gnd *
  page42_i124
#CELL
  dev_discrete cap_a *
  page42_i125
#CELL
  dev_discrete cap_a *
  page42_i126
#CELL
  dev_discrete cap_a *
  page42_i127
#CELL
  dev_discrete cap_a *
  page42_i128
#CELL
  dev_discrete cap_a *
  page42_i129
#CELL
  mstr_discrete cap *
  page42_i13
#CELL
  dev_discrete cap_a *
  page42_i130
#CELL
  dev_discrete cap_a *
  page42_i131
#CELL
  dev_discrete cap_a *
  page42_i132
#ISCELL
  mstr_symbols gnd *
  page42_i133
#CELL
  dev_discrete cap_a *
  page42_i134
#CELL
  dev_discrete cap_a *
  page42_i135
#CELL
  dev_discrete cap_a *
  page42_i136
#ISCELL
  mstr_symbols pvccin_cpu0 *
  page42_i137
#CELL
  dev_discrete cap_a *
  page42_i138
#ISCELL
  mstr_symbols pvccin_cpu0 *
  page42_i139
#CELL
  mstr_discrete cap *
  page42_i14
#CELL
  dev_discrete cap_a *
  page42_i140
#ISCELL
  mstr_symbols pvccin_cpu0 *
  page42_i141
#CELL
  dev_discrete cap_a *
  page42_i142
#ISCELL
  mstr_symbols vcc_core *
  page42_i144
#CELL
  dev_discrete cap_a *
  page42_i145
#CELL
  dev_discrete cap_a *
  page42_i147
#CELL
  mstr_discrete cap *
  page42_i148
#CELL
  mstr_discrete cap *
  page42_i149
#CELL
  dev_discrete cap_a *
  page42_i151
#CELL
  dev_discrete cap_a *
  page42_i152
#CELL
  dev_discrete cap_a *
  page42_i153
#CELL
  dev_discrete cap_a *
  page42_i154
#CELL
  dev_discrete cap_a *
  page42_i155
#CELL
  dev_discrete cap_a *
  page42_i156
#ISCELL
  mstr_symbols vcc_core *
  page42_i159
#ISCELL
  mstr_symbols pvccio_cpu0 *
  page42_i16
#CELL
  mstr_discrete cap *
  page42_i162
#CELL
  mstr_discrete cap *
  page42_i163
#CELL
  dev_discrete cap_a *
  page42_i164
#CELL
  mstr_discrete cap *
  page42_i17
#CELL
  mstr_discrete cap *
  page42_i172
#CELL
  dev_discrete cap_a *
  page42_i173
#CELL
  dev_discrete cap_a *
  page42_i174
#CELL
  dev_discrete cap_a *
  page42_i175
#CELL
  dev_discrete cap_a *
  page42_i176
#CELL
  dev_discrete cap_a *
  page42_i178
#CELL
  dev_discrete cap_a *
  page42_i179
#CELL
  mstr_discrete cap *
  page42_i18
#CELL
  dev_discrete cap_a *
  page42_i180
#ISCELL
  mstr_symbols vcc_core *
  page42_i181
#ISCELL
  mstr_symbols gnd *
  page42_i182
#CELL
  mstr_discrete cap *
  page42_i183
#CELL
  mstr_discrete cap *
  page42_i184
#CELL
  mstr_discrete cap *
  page42_i185
#CELL
  mstr_discrete cap *
  page42_i186
#CELL
  mstr_discrete cap *
  page42_i187
#CELL
  mstr_discrete cap *
  page42_i188
#CELL
  mstr_discrete cap *
  page42_i189
#CELL
  mstr_discrete cap *
  page42_i19
#CELL
  mstr_discrete cap *
  page42_i190
#CELL
  mstr_discrete cap *
  page42_i2
#ISCELL
  mstr_symbols gnd *
  page42_i20
#ISCELL
  mstr_symbols gnd *
  page42_i21
#ISCELL
  mstr_symbols pvsa_cpu0 *
  page42_i24
#CELL
  mstr_discrete cap *
  page42_i25
#CELL
  mstr_discrete cap *
  page42_i27
#CELL
  mstr_discrete cap *
  page42_i28
#ISCELL
  mstr_symbols gnd *
  page42_i29
#CELL
  mstr_discrete cap *
  page42_i3
#ISCELL
  mstr_symbols gnd *
  page42_i32
#CELL
  mstr_discrete cap *
  page42_i33
#ISCELL
  mstr_symbols gnd *
  page42_i35
#CELL
  mstr_discrete cap *
  page42_i37
#CELL
  mstr_discrete cap *
  page42_i38
#ISCELL
  mstr_symbols pvccin_cpu0 *
  page42_i39
#CELL
  mstr_discrete cap *
  page42_i4
#CELL
  mstr_discrete cap *
  page42_i40
#CELL
  mstr_discrete cap *
  page42_i41
#CELL
  mstr_discrete cap *
  page42_i42
#ISCELL
  mstr_symbols pvccin_cpu0 *
  page42_i43
#CELL
  mstr_discrete cap *
  page42_i44
#ISCELL
  mstr_symbols pvccin_cpu0 *
  page42_i45
#ISCELL
  mstr_symbols gnd *
  page42_i46
#ISCELL
  mstr_symbols gnd *
  page42_i48
#ISCELL
  mstr_symbols gnd *
  page42_i5
#CELL
  mstr_discrete cap *
  page42_i50
#CELL
  mstr_discrete cap *
  page42_i51
#CELL
  mstr_discrete cap *
  page42_i53
#CELL
  mstr_discrete cap *
  page42_i54
#CELL
  mstr_discrete cap *
  page42_i55
#CELL
  mstr_discrete cap *
  page42_i56
#CELL
  mstr_discrete cap *
  page42_i57
#ISCELL
  mstr_symbols gnd *
  page42_i58
#CELL
  mstr_discrete cap *
  page42_i59
#CELL
  mstr_discrete cap *
  page42_i6
#CELL
  mstr_discrete cap *
  page42_i60
#CELL
  mstr_discrete cap *
  page42_i61
#ISCELL
  mstr_symbols pvccin_cpu0 *
  page42_i62
#CELL
  mstr_discrete cap *
  page42_i63
#ISCELL
  mstr_symbols pvccin_cpu0 *
  page42_i64
#CELL
  mstr_discrete cap *
  page42_i65
#ISCELL
  mstr_symbols pvccin_cpu0 *
  page42_i66
#CELL
  dev_discrete cap_a *
  page42_i68
#CELL
  dev_discrete cap_a *
  page42_i69
#CELL
  dev_discrete cap_a *
  page42_i70
#ISCELL
  mstr_symbols gnd *
  page42_i71
#CELL
  dev_discrete cap_a *
  page42_i72
#ISCELL
  mstr_symbols gnd *
  page42_i73
#CELL
  dev_discrete cap_a *
  page42_i74
#CELL
  dev_discrete cap_a *
  page42_i75
#CELL
  dev_discrete cap_a *
  page42_i77
#ISCELL
  mstr_symbols pvccio_cpu0 *
  page42_i79
#CELL
  mstr_discrete cap *
  page42_i8
#CELL
  dev_discrete cap_a *
  page42_i80
#CELL
  dev_discrete cap_a *
  page42_i81
#CELL
  dev_discrete cap_a *
  page42_i83
#CELL
  dev_discrete cap_a *
  page42_i88
#CELL
  dev_discrete cap_a *
  page42_i89
#CELL
  mstr_discrete cap *
  page42_i9
#CELL
  dev_discrete cap_a *
  page42_i90
#CELL
  mstr_discrete cap *
  page42_i91
#ISCELL
  mstr_symbols gnd *
  page42_i92
#CELL
  mstr_discrete cap *
  page42_i93
#CELL
  mstr_discrete cap *
  page42_i94
#CELL
  dev_discrete cap_a *
  page42_i98
#ISCELL
  mstr_symbols pvsa_cpu0 *
  page42_i99
#ISCELL
  mstr_symbols bom_note *
  *
#ISCELL
  mstr_symbols intel_corp_bpage *
  *
#CELL
  mstr_sconn sconn288_h44441004 *
  page43_i1
#ISCELL
  mstr_standard tap *
  page43_i127
#ISCELL
  mstr_standard tap *
  page43_i128
#ISCELL
  mstr_standard tap *
  page43_i129
#ISCELL
  mstr_standard tap *
  page43_i130
#ISCELL
  mstr_standard tap *
  page43_i131
#ISCELL
  mstr_standard tap *
  page43_i132
#ISCELL
  mstr_standard tap *
  page43_i133
#ISCELL
  mstr_standard tap *
  page43_i134
#ISCELL
  mstr_standard tap *
  page43_i135
#ISCELL
  mstr_standard tap *
  page43_i136
#ISCELL
  mstr_standard tap *
  page43_i137
#ISCELL
  mstr_standard tap *
  page43_i138
#ISCELL
  mstr_standard tap *
  page43_i139
#ISCELL
  mstr_standard tap *
  page43_i140
#ISCELL
  mstr_standard tap *
  page43_i141
#ISCELL
  mstr_standard tap *
  page43_i142
#ISCELL
  mstr_standard tap *
  page43_i143
#ISCELL
  mstr_standard tap *
  page43_i144
#ISCELL
  mstr_standard tap *
  page43_i145
#ISCELL
  mstr_standard tap *
  page43_i146
#ISCELL
  mstr_standard tap *
  page43_i147
#ISCELL
  mstr_standard tap *
  page43_i148
#ISCELL
  mstr_standard tap *
  page43_i149
#ISCELL
  mstr_standard tap *
  page43_i150
#ISCELL
  mstr_standard tap *
  page43_i151
#ISCELL
  mstr_standard tap *
  page43_i152
#ISCELL
  mstr_standard tap *
  page43_i153
#ISCELL
  mstr_standard tap *
  page43_i154
#ISCELL
  mstr_standard tap *
  page43_i155
#ISCELL
  mstr_standard tap *
  page43_i156
#ISCELL
  mstr_standard tap *
  page43_i157
#ISCELL
  mstr_standard tap *
  page43_i158
#ISCELL
  mstr_standard tap *
  page43_i159
#ISCELL
  mstr_standard tap *
  page43_i160
#ISCELL
  mstr_standard tap *
  page43_i161
#ISCELL
  mstr_standard tap *
  page43_i162
#ISCELL
  mstr_standard tap *
  page43_i163
#ISCELL
  mstr_standard tap *
  page43_i164
#ISCELL
  mstr_standard tap *
  page43_i165
#ISCELL
  mstr_standard tap *
  page43_i166
#ISCELL
  mstr_standard tap *
  page43_i167
#ISCELL
  mstr_standard tap *
  page43_i168
#ISCELL
  mstr_standard tap *
  page43_i169
#ISCELL
  mstr_standard tap *
  page43_i170
#ISCELL
  mstr_standard tap *
  page43_i171
#ISCELL
  mstr_standard tap *
  page43_i172
#ISCELL
  mstr_standard tap *
  page43_i173
#ISCELL
  mstr_standard tap *
  page43_i174
#ISCELL
  mstr_standard tap *
  page43_i175
#ISCELL
  mstr_standard tap *
  page43_i176
#ISCELL
  mstr_standard tap *
  page43_i177
#ISCELL
  mstr_standard tap *
  page43_i178
#ISCELL
  mstr_standard tap *
  page43_i179
#ISCELL
  mstr_standard tap *
  page43_i180
#ISCELL
  mstr_standard tap *
  page43_i181
#ISCELL
  mstr_standard tap *
  page43_i182
#ISCELL
  mstr_standard tap *
  page43_i183
#ISCELL
  mstr_standard tap *
  page43_i184
#ISCELL
  mstr_standard tap *
  page43_i185
#ISCELL
  mstr_standard tap *
  page43_i186
#ISCELL
  mstr_standard tap *
  page43_i187
#ISCELL
  mstr_standard tap *
  page43_i188
#ISCELL
  mstr_standard tap *
  page43_i189
#ISCELL
  mstr_standard tap *
  page43_i190
#ISCELL
  mstr_standard offpage *
  page43_i191
#ISCELL
  mstr_standard tap *
  page43_i192
#ISCELL
  mstr_standard tap *
  page43_i193
#ISCELL
  mstr_standard tap *
  page43_i194
#ISCELL
  mstr_standard tap *
  page43_i195
#ISCELL
  mstr_standard tap *
  page43_i196
#ISCELL
  mstr_standard tap *
  page43_i197
#ISCELL
  mstr_standard tap *
  page43_i198
#ISCELL
  mstr_standard tap *
  page43_i199
#CELL
  mstr_sconn sconn288_h44441004 *
  page43_i2
#ISCELL
  mstr_standard tap *
  page43_i200
#ISCELL
  mstr_standard tap *
  page43_i201
#ISCELL
  mstr_standard tap *
  page43_i202
#ISCELL
  mstr_standard tap *
  page43_i203
#ISCELL
  mstr_standard offpage *
  page43_i204
#ISCELL
  mstr_standard tap *
  page43_i205
#ISCELL
  mstr_standard tap *
  page43_i206
#ISCELL
  mstr_standard tap *
  page43_i207
#ISCELL
  mstr_standard tap *
  page43_i208
#ISCELL
  mstr_standard tap *
  page43_i209
#ISCELL
  mstr_standard tap *
  page43_i210
#ISCELL
  mstr_standard offpage *
  page43_i211
#ISCELL
  mstr_standard tap *
  page43_i212
#ISCELL
  mstr_standard tap *
  page43_i213
#ISCELL
  mstr_standard tap *
  page43_i214
#ISCELL
  mstr_standard tap *
  page43_i215
#ISCELL
  mstr_standard tap *
  page43_i216
#ISCELL
  mstr_standard tap *
  page43_i217
#ISCELL
  mstr_standard tap *
  page43_i218
#ISCELL
  mstr_standard tap *
  page43_i219
#ISCELL
  mstr_standard tap *
  page43_i22
#ISCELL
  mstr_standard tap *
  page43_i220
#ISCELL
  mstr_standard tap *
  page43_i221
#ISCELL
  mstr_standard tap *
  page43_i222
#ISCELL
  mstr_standard tap *
  page43_i223
#ISCELL
  mstr_standard tap *
  page43_i224
#ISCELL
  mstr_standard tap *
  page43_i225
#ISCELL
  mstr_standard tap *
  page43_i226
#ISCELL
  mstr_standard tap *
  page43_i227
#ISCELL
  mstr_standard tap *
  page43_i228
#ISCELL
  mstr_standard tap *
  page43_i229
#ISCELL
  mstr_standard tap *
  page43_i23
#ISCELL
  mstr_standard tap *
  page43_i235
#ISCELL
  mstr_standard tap *
  page43_i236
#ISCELL
  mstr_standard offpage *
  page43_i237
#ISCELL
  mstr_standard tap *
  page43_i238
#ISCELL
  mstr_standard tap *
  page43_i239
#ISCELL
  mstr_standard tap *
  page43_i24
#ISCELL
  mstr_standard offpage *
  page43_i240
#ISCELL
  mstr_standard tap *
  page43_i241
#ISCELL
  mstr_standard tap *
  page43_i242
#ISCELL
  mstr_standard tap *
  page43_i243
#ISCELL
  mstr_standard tap *
  page43_i244
#ISCELL
  mstr_standard offpage *
  page43_i245
#ISCELL
  mstr_standard tap *
  page43_i247
#ISCELL
  mstr_standard tap *
  page43_i25
#ISCELL
  mstr_standard tap *
  page43_i250
#ISCELL
  mstr_standard tap *
  page43_i252
#ISCELL
  mstr_standard tap *
  page43_i254
#ISCELL
  mstr_standard offpage *
  page43_i255
#ISCELL
  mstr_standard offpage *
  page43_i256
#ISCELL
  mstr_standard offpage *
  page43_i257
#ISCELL
  mstr_standard offpage *
  page43_i258
#CELL
  mstr_sconn sconn288_h44441004 *
  page43_i259
#ISCELL
  mstr_standard tap *
  page43_i26
#CELL
  mstr_sconn sconn288_h44441004 *
  page43_i260
#ISCELL
  mstr_symbols pvddq_abc *
  page43_i263
#ISCELL
  mstr_symbols gnd *
  page43_i264
#ISCELL
  mstr_symbols gnd *
  page43_i265
#ISCELL
  mstr_symbols gnd *
  page43_i267
#ISCELL
  mstr_standard offpage *
  page43_i269
#ISCELL
  mstr_standard tap *
  page43_i27
#ISCELL
  mstr_standard offpage *
  page43_i270
#ISCELL
  mstr_symbols gnd *
  page43_i271
#CELL
  dev_discrete cap_a *
  page43_i272
#ISCELL
  mstr_symbols pvpp_abc *
  page43_i273
#ISCELL
  mstr_symbols pvpp_abc *
  page43_i274
#ISCELL
  mstr_symbols pvtt_abc *
  page43_i275
#ISCELL
  mstr_standard offpage *
  page43_i276
#ISCELL
  mstr_standard tap *
  page43_i28
#ISCELL
  mstr_symbols p12v_nvdimm_abc *
  page43_i289
#ISCELL
  mstr_standard tap *
  page43_i29
#ISCELL
  mstr_standard tap *
  page43_i30
#ISCELL
  mstr_standard tap *
  page43_i31
#ISCELL
  mstr_standard tap *
  page43_i32
#ISCELL
  mstr_standard tap *
  page43_i33
#ISCELL
  mstr_standard tap *
  page43_i34
#ISCELL
  mstr_standard tap *
  page43_i35
#ISCELL
  mstr_standard tap *
  page43_i36
#ISCELL
  mstr_standard tap *
  page43_i37
#ISCELL
  mstr_standard tap *
  page43_i38
#ISCELL
  mstr_standard tap *
  page43_i39
#ISCELL
  mstr_standard offpage *
  page43_i40
#ISCELL
  mstr_standard offpage *
  page43_i41
#ISCELL
  mstr_standard offpage *
  page43_i42
#ISCELL
  mstr_standard tap *
  page43_i43
#ISCELL
  mstr_standard tap *
  page43_i44
#ISCELL
  mstr_standard tap *
  page43_i45
#ISCELL
  mstr_standard tap *
  page43_i46
#ISCELL
  mstr_standard offpage *
  page43_i47
#ISCELL
  mstr_standard offpage *
  page43_i48
#ISCELL
  mstr_standard tap *
  page43_i49
#ISCELL
  mstr_standard tap *
  page43_i50
#ISCELL
  mstr_standard tap *
  page43_i51
#ISCELL
  mstr_standard tap *
  page43_i52
#ISCELL
  mstr_standard tap *
  page43_i53
#ISCELL
  mstr_standard tap *
  page43_i54
#ISCELL
  mstr_standard tap *
  page43_i55
#ISCELL
  mstr_standard tap *
  page43_i56
#ISCELL
  mstr_standard offpage *
  page43_i57
#ISCELL
  mstr_standard offpage *
  page43_i59
#ISCELL
  mstr_standard offpage *
  page43_i60
#ISCELL
  mstr_standard offpage *
  page43_i61
#ISCELL
  mstr_symbols bom_note *
  *
#ISCELL
  mstr_symbols intel_corp_bpage *
  *
#ISCELL
  mstr_symbols gnd *
  page44_i1
#ISCELL
  mstr_standard offpage *
  page44_i10
#ISCELL
  mstr_standard tap *
  page44_i100
#ISCELL
  mstr_standard tap *
  page44_i101
#ISCELL
  mstr_standard tap *
  page44_i102
#ISCELL
  mstr_standard tap *
  page44_i103
#ISCELL
  mstr_standard tap *
  page44_i104
#ISCELL
  mstr_standard tap *
  page44_i105
#ISCELL
  mstr_standard tap *
  page44_i106
#ISCELL
  mstr_standard tap *
  page44_i107
#ISCELL
  mstr_standard tap *
  page44_i108
#ISCELL
  mstr_standard tap *
  page44_i109
#ISCELL
  mstr_standard offpage *
  page44_i11
#ISCELL
  mstr_standard tap *
  page44_i110
#ISCELL
  mstr_standard tap *
  page44_i111
#ISCELL
  mstr_standard tap *
  page44_i112
#ISCELL
  mstr_standard tap *
  page44_i113
#ISCELL
  mstr_standard tap *
  page44_i114
#ISCELL
  mstr_standard tap *
  page44_i115
#ISCELL
  mstr_standard tap *
  page44_i116
#ISCELL
  mstr_standard tap *
  page44_i117
#ISCELL
  mstr_symbols pvtt_abc *
  page44_i118
#ISCELL
  mstr_symbols pvpp_abc *
  page44_i119
#ISCELL
  mstr_standard tap *
  page44_i12
#CELL
  mstr_sconn sconn288_h44441003 *
  page44_i120
#ISCELL
  mstr_standard offpage *
  page44_i121
#ISCELL
  mstr_standard tap *
  page44_i122
#ISCELL
  mstr_standard tap *
  page44_i123
#ISCELL
  mstr_standard tap *
  page44_i124
#ISCELL
  mstr_standard tap *
  page44_i125
#ISCELL
  mstr_standard tap *
  page44_i126
#ISCELL
  mstr_standard tap *
  page44_i127
#ISCELL
  mstr_standard tap *
  page44_i128
#ISCELL
  mstr_standard tap *
  page44_i129
#CELL
  mstr_sconn sconn288_h44441003 *
  page44_i13
#ISCELL
  mstr_standard tap *
  page44_i130
#ISCELL
  mstr_standard tap *
  page44_i131
#ISCELL
  mstr_standard tap *
  page44_i132
#ISCELL
  mstr_standard tap *
  page44_i133
#ISCELL
  mstr_standard tap *
  page44_i134
#ISCELL
  mstr_standard tap *
  page44_i135
#ISCELL
  mstr_standard offpage *
  page44_i136
#ISCELL
  mstr_symbols gnd *
  page44_i138
#CELL
  mstr_sconn sconn288_h44441003 *
  page44_i139
#ISCELL
  mstr_standard offpage *
  page44_i14
#ISCELL
  mstr_standard tap *
  page44_i142
#ISCELL
  mstr_standard tap *
  page44_i143
#ISCELL
  mstr_standard tap *
  page44_i144
#ISCELL
  mstr_standard tap *
  page44_i145
#ISCELL
  mstr_standard tap *
  page44_i146
#ISCELL
  mstr_standard tap *
  page44_i147
#ISCELL
  mstr_standard tap *
  page44_i148
#ISCELL
  mstr_standard tap *
  page44_i149
#ISCELL
  mstr_standard offpage *
  page44_i15
#ISCELL
  mstr_standard tap *
  page44_i150
#ISCELL
  mstr_standard tap *
  page44_i151
#ISCELL
  mstr_standard tap *
  page44_i152
#ISCELL
  mstr_standard tap *
  page44_i153
#ISCELL
  mstr_standard tap *
  page44_i154
#ISCELL
  mstr_standard tap *
  page44_i155
#ISCELL
  mstr_standard tap *
  page44_i156
#ISCELL
  mstr_standard tap *
  page44_i157
#ISCELL
  mstr_standard tap *
  page44_i158
#ISCELL
  mstr_standard tap *
  page44_i159
#ISCELL
  mstr_standard offpage *
  page44_i16
#ISCELL
  mstr_standard tap *
  page44_i160
#ISCELL
  mstr_symbols gnd *
  page44_i162
#ISCELL
  mstr_standard tap *
  page44_i163
#ISCELL
  mstr_standard tap *
  page44_i164
#ISCELL
  mstr_standard tap *
  page44_i165
#ISCELL
  mstr_standard tap *
  page44_i166
#ISCELL
  mstr_standard tap *
  page44_i167
#ISCELL
  mstr_standard tap *
  page44_i168
#ISCELL
  mstr_standard tap *
  page44_i169
#ISCELL
  mstr_standard offpage *
  page44_i17
#ISCELL
  mstr_standard tap *
  page44_i170
#ISCELL
  mstr_standard tap *
  page44_i171
#ISCELL
  mstr_standard tap *
  page44_i172
#ISCELL
  mstr_standard tap *
  page44_i173
#ISCELL
  mstr_standard tap *
  page44_i174
#ISCELL
  mstr_standard tap *
  page44_i175
#ISCELL
  mstr_standard tap *
  page44_i176
#ISCELL
  mstr_standard tap *
  page44_i177
#ISCELL
  mstr_standard tap *
  page44_i178
#ISCELL
  mstr_standard tap *
  page44_i179
#ISCELL
  mstr_standard offpage *
  page44_i18
#ISCELL
  mstr_standard offpage *
  page44_i182
#ISCELL
  mstr_standard offpage *
  page44_i183
#ISCELL
  mstr_symbols p12v_nvdimm_abc *
  page44_i184
#ISCELL
  mstr_standard offpage *
  page44_i19
#CELL
  dev_discrete cap_a *
  page44_i2
#ISCELL
  mstr_standard offpage *
  page44_i20
#ISCELL
  mstr_standard tap *
  page44_i21
#ISCELL
  mstr_standard tap *
  page44_i22
#ISCELL
  mstr_standard tap *
  page44_i23
#ISCELL
  mstr_standard tap *
  page44_i24
#ISCELL
  mstr_standard tap *
  page44_i25
#ISCELL
  mstr_standard tap *
  page44_i26
#ISCELL
  mstr_standard tap *
  page44_i27
#ISCELL
  mstr_standard tap *
  page44_i28
#ISCELL
  mstr_standard tap *
  page44_i29
#ISCELL
  mstr_symbols gnd *
  page44_i3
#ISCELL
  mstr_standard tap *
  page44_i30
#ISCELL
  mstr_standard tap *
  page44_i31
#ISCELL
  mstr_standard tap *
  page44_i32
#ISCELL
  mstr_standard tap *
  page44_i33
#ISCELL
  mstr_standard tap *
  page44_i34
#ISCELL
  mstr_standard tap *
  page44_i35
#ISCELL
  mstr_standard tap *
  page44_i36
#ISCELL
  mstr_standard offpage *
  page44_i37
#ISCELL
  mstr_standard offpage *
  page44_i38
#ISCELL
  mstr_standard offpage *
  page44_i39
#ISCELL
  mstr_standard offpage *
  page44_i4
#ISCELL
  mstr_standard offpage *
  page44_i40
#ISCELL
  mstr_standard tap *
  page44_i41
#ISCELL
  mstr_standard tap *
  page44_i42
#ISCELL
  mstr_standard tap *
  page44_i43
#ISCELL
  mstr_standard tap *
  page44_i44
#ISCELL
  mstr_standard tap *
  page44_i45
#ISCELL
  mstr_standard tap *
  page44_i46
#ISCELL
  mstr_standard tap *
  page44_i47
#ISCELL
  mstr_standard tap *
  page44_i48
#ISCELL
  mstr_standard tap *
  page44_i49
#ISCELL
  mstr_symbols pvpp_abc *
  page44_i5
#ISCELL
  mstr_standard tap *
  page44_i50
#ISCELL
  mstr_standard tap *
  page44_i51
#ISCELL
  mstr_standard tap *
  page44_i52
#ISCELL
  mstr_standard tap *
  page44_i53
#ISCELL
  mstr_standard tap *
  page44_i54
#ISCELL
  mstr_standard tap *
  page44_i55
#ISCELL
  mstr_standard tap *
  page44_i56
#ISCELL
  mstr_standard tap *
  page44_i57
#ISCELL
  mstr_standard tap *
  page44_i58
#ISCELL
  mstr_standard tap *
  page44_i59
#ISCELL
  mstr_standard offpage *
  page44_i6
#ISCELL
  mstr_standard tap *
  page44_i60
#ISCELL
  mstr_standard tap *
  page44_i61
#ISCELL
  mstr_standard tap *
  page44_i62
#ISCELL
  mstr_standard tap *
  page44_i63
#ISCELL
  mstr_standard tap *
  page44_i64
#ISCELL
  mstr_standard tap *
  page44_i65
#ISCELL
  mstr_standard tap *
  page44_i66
#ISCELL
  mstr_standard tap *
  page44_i67
#ISCELL
  mstr_standard tap *
  page44_i68
#ISCELL
  mstr_standard tap *
  page44_i69
#ISCELL
  mstr_standard offpage *
  page44_i7
#ISCELL
  mstr_standard tap *
  page44_i70
#ISCELL
  mstr_standard tap *
  page44_i71
#ISCELL
  mstr_standard tap *
  page44_i72
#ISCELL
  mstr_standard tap *
  page44_i73
#ISCELL
  mstr_standard tap *
  page44_i74
#CELL
  mstr_sconn sconn288_h44441003 *
  page44_i75
#ISCELL
  mstr_standard tap *
  page44_i76
#ISCELL
  mstr_standard tap *
  page44_i77
#ISCELL
  mstr_standard tap *
  page44_i78
#ISCELL
  mstr_standard tap *
  page44_i79
#ISCELL
  mstr_standard offpage *
  page44_i8
#ISCELL
  mstr_standard tap *
  page44_i80
#ISCELL
  mstr_standard tap *
  page44_i81
#ISCELL
  mstr_standard tap *
  page44_i82
#ISCELL
  mstr_standard tap *
  page44_i83
#ISCELL
  mstr_standard tap *
  page44_i84
#ISCELL
  mstr_standard tap *
  page44_i85
#ISCELL
  mstr_standard tap *
  page44_i86
#ISCELL
  mstr_standard tap *
  page44_i87
#ISCELL
  mstr_standard tap *
  page44_i88
#ISCELL
  mstr_standard tap *
  page44_i89
#ISCELL
  mstr_standard offpage *
  page44_i9
#ISCELL
  mstr_standard tap *
  page44_i90
#ISCELL
  mstr_standard tap *
  page44_i91
#ISCELL
  mstr_standard tap *
  page44_i92
#ISCELL
  mstr_standard tap *
  page44_i93
#ISCELL
  mstr_standard tap *
  page44_i94
#ISCELL
  mstr_standard tap *
  page44_i95
#ISCELL
  mstr_standard tap *
  page44_i96
#ISCELL
  mstr_symbols pvddq_abc *
  page44_i97
#ISCELL
  mstr_standard tap *
  page44_i98
#ISCELL
  mstr_standard tap *
  page44_i99
#ISCELL
  mstr_symbols bom_note *
  *
#ISCELL
  mstr_symbols intel_corp_bpage *
  *
#ISCELL
  mstr_standard offpage *
  page45_i1
#ISCELL
  mstr_standard tap *
  page45_i10
#ISCELL
  mstr_standard tap *
  page45_i100
#ISCELL
  mstr_standard tap *
  page45_i101
#ISCELL
  mstr_standard tap *
  page45_i102
#ISCELL
  mstr_standard tap *
  page45_i103
#ISCELL
  mstr_standard tap *
  page45_i104
#ISCELL
  mstr_standard tap *
  page45_i105
#ISCELL
  mstr_standard tap *
  page45_i106
#ISCELL
  mstr_standard tap *
  page45_i107
#ISCELL
  mstr_standard tap *
  page45_i108
#ISCELL
  mstr_standard tap *
  page45_i109
#ISCELL
  mstr_standard tap *
  page45_i110
#CELL
  mstr_sconn sconn288_h44441004 *
  page45_i111
#ISCELL
  mstr_standard tap *
  page45_i112
#ISCELL
  mstr_standard tap *
  page45_i113
#ISCELL
  mstr_standard tap *
  page45_i114
#ISCELL
  mstr_standard tap *
  page45_i115
#ISCELL
  mstr_standard tap *
  page45_i116
#ISCELL
  mstr_standard tap *
  page45_i117
#ISCELL
  mstr_standard tap *
  page45_i118
#ISCELL
  mstr_standard tap *
  page45_i119
#ISCELL
  mstr_symbols pvtt_abc *
  page45_i12
#ISCELL
  mstr_standard tap *
  page45_i120
#ISCELL
  mstr_standard tap *
  page45_i121
#ISCELL
  mstr_standard tap *
  page45_i122
#ISCELL
  mstr_standard tap *
  page45_i123
#ISCELL
  mstr_standard tap *
  page45_i124
#ISCELL
  mstr_standard tap *
  page45_i125
#ISCELL
  mstr_standard tap *
  page45_i126
#ISCELL
  mstr_standard offpage *
  page45_i127
#ISCELL
  mstr_standard tap *
  page45_i128
#ISCELL
  mstr_standard tap *
  page45_i129
#ISCELL
  mstr_symbols pvddq_abc *
  page45_i13
#ISCELL
  mstr_standard tap *
  page45_i130
#ISCELL
  mstr_standard tap *
  page45_i131
#ISCELL
  mstr_standard tap *
  page45_i132
#ISCELL
  mstr_standard tap *
  page45_i133
#ISCELL
  mstr_standard tap *
  page45_i134
#ISCELL
  mstr_standard offpage *
  page45_i135
#ISCELL
  mstr_standard offpage *
  page45_i136
#ISCELL
  mstr_standard offpage *
  page45_i137
#ISCELL
  mstr_standard tap *
  page45_i138
#ISCELL
  mstr_standard tap *
  page45_i139
#ISCELL
  mstr_standard tap *
  page45_i14
#ISCELL
  mstr_standard tap *
  page45_i140
#ISCELL
  mstr_standard tap *
  page45_i141
#ISCELL
  mstr_standard tap *
  page45_i142
#ISCELL
  mstr_standard tap *
  page45_i143
#ISCELL
  mstr_standard tap *
  page45_i144
#ISCELL
  mstr_standard tap *
  page45_i145
#ISCELL
  mstr_standard offpage *
  page45_i146
#ISCELL
  mstr_standard offpage *
  page45_i147
#ISCELL
  mstr_standard offpage *
  page45_i148
#ISCELL
  mstr_standard offpage *
  page45_i149
#ISCELL
  mstr_standard tap *
  page45_i15
#ISCELL
  mstr_standard offpage *
  page45_i150
#ISCELL
  mstr_standard offpage *
  page45_i151
#ISCELL
  mstr_standard tap *
  page45_i152
#ISCELL
  mstr_standard tap *
  page45_i153
#ISCELL
  mstr_standard offpage *
  page45_i154
#ISCELL
  mstr_standard tap *
  page45_i155
#ISCELL
  mstr_standard tap *
  page45_i156
#ISCELL
  mstr_standard offpage *
  page45_i157
#ISCELL
  mstr_standard tap *
  page45_i158
#ISCELL
  mstr_standard offpage *
  page45_i159
#ISCELL
  mstr_standard tap *
  page45_i16
#ISCELL
  mstr_standard tap *
  page45_i160
#ISCELL
  mstr_standard tap *
  page45_i161
#ISCELL
  mstr_standard tap *
  page45_i162
#ISCELL
  mstr_standard tap *
  page45_i163
#ISCELL
  mstr_standard tap *
  page45_i164
#ISCELL
  mstr_standard tap *
  page45_i165
#ISCELL
  mstr_standard tap *
  page45_i166
#ISCELL
  mstr_standard offpage *
  page45_i167
#ISCELL
  mstr_standard offpage *
  page45_i168
#CELL
  mstr_sconn sconn288_h44441004 *
  page45_i169
#ISCELL
  mstr_standard tap *
  page45_i17
#ISCELL
  mstr_symbols gnd *
  page45_i174
#ISCELL
  mstr_standard offpage *
  page45_i175
#ISCELL
  mstr_standard offpage *
  page45_i176
#ISCELL
  mstr_standard offpage *
  page45_i177
#ISCELL
  mstr_symbols gnd *
  page45_i178
#CELL
  dev_discrete cap_a *
  page45_i179
#ISCELL
  mstr_standard tap *
  page45_i18
#ISCELL
  mstr_symbols pvpp_abc *
  page45_i180
#ISCELL
  mstr_symbols pvpp_abc *
  page45_i181
#ISCELL
  mstr_standard offpage *
  page45_i182
#ISCELL
  mstr_symbols p12v_nvdimm_abc *
  page45_i183
#ISCELL
  mstr_standard tap *
  page45_i19
#ISCELL
  mstr_standard offpage *
  page45_i2
#ISCELL
  mstr_standard tap *
  page45_i20
#ISCELL
  mstr_standard tap *
  page45_i21
#ISCELL
  mstr_standard tap *
  page45_i22
#ISCELL
  mstr_standard tap *
  page45_i23
#ISCELL
  mstr_standard tap *
  page45_i24
#ISCELL
  mstr_standard tap *
  page45_i25
#ISCELL
  mstr_standard tap *
  page45_i26
#ISCELL
  mstr_standard tap *
  page45_i27
#ISCELL
  mstr_standard tap *
  page45_i28
#ISCELL
  mstr_standard tap *
  page45_i29
#ISCELL
  mstr_standard tap *
  page45_i3
#ISCELL
  mstr_standard tap *
  page45_i30
#ISCELL
  mstr_standard tap *
  page45_i31
#ISCELL
  mstr_standard tap *
  page45_i32
#ISCELL
  mstr_standard tap *
  page45_i33
#ISCELL
  mstr_standard tap *
  page45_i34
#ISCELL
  mstr_standard tap *
  page45_i35
#ISCELL
  mstr_standard tap *
  page45_i36
#ISCELL
  mstr_standard tap *
  page45_i37
#ISCELL
  mstr_standard tap *
  page45_i38
#ISCELL
  mstr_standard tap *
  page45_i39
#ISCELL
  mstr_standard tap *
  page45_i4
#ISCELL
  mstr_standard tap *
  page45_i40
#ISCELL
  mstr_standard tap *
  page45_i41
#ISCELL
  mstr_symbols gnd *
  page45_i42
#CELL
  mstr_sconn sconn288_h44441004 *
  page45_i43
#ISCELL
  mstr_symbols gnd *
  page45_i44
#ISCELL
  mstr_standard offpage *
  page45_i45
#ISCELL
  mstr_standard tap *
  page45_i46
#ISCELL
  mstr_standard tap *
  page45_i47
#ISCELL
  mstr_standard tap *
  page45_i48
#ISCELL
  mstr_standard tap *
  page45_i49
#ISCELL
  mstr_standard tap *
  page45_i5
#ISCELL
  mstr_standard tap *
  page45_i50
#ISCELL
  mstr_standard tap *
  page45_i51
#ISCELL
  mstr_standard tap *
  page45_i52
#ISCELL
  mstr_standard tap *
  page45_i53
#ISCELL
  mstr_standard tap *
  page45_i54
#ISCELL
  mstr_standard tap *
  page45_i55
#ISCELL
  mstr_standard tap *
  page45_i56
#ISCELL
  mstr_standard tap *
  page45_i57
#ISCELL
  mstr_standard tap *
  page45_i58
#ISCELL
  mstr_standard tap *
  page45_i59
#ISCELL
  mstr_standard tap *
  page45_i6
#ISCELL
  mstr_standard tap *
  page45_i60
#CELL
  mstr_sconn sconn288_h44441004 *
  page45_i61
#ISCELL
  mstr_standard tap *
  page45_i62
#ISCELL
  mstr_standard tap *
  page45_i63
#ISCELL
  mstr_standard tap *
  page45_i64
#ISCELL
  mstr_standard tap *
  page45_i65
#ISCELL
  mstr_standard tap *
  page45_i66
#ISCELL
  mstr_standard tap *
  page45_i67
#ISCELL
  mstr_standard tap *
  page45_i68
#ISCELL
  mstr_standard tap *
  page45_i69
#ISCELL
  mstr_standard tap *
  page45_i7
#ISCELL
  mstr_standard tap *
  page45_i70
#ISCELL
  mstr_standard tap *
  page45_i71
#ISCELL
  mstr_standard tap *
  page45_i72
#ISCELL
  mstr_standard tap *
  page45_i73
#ISCELL
  mstr_standard tap *
  page45_i74
#ISCELL
  mstr_standard tap *
  page45_i75
#ISCELL
  mstr_standard tap *
  page45_i76
#ISCELL
  mstr_standard tap *
  page45_i77
#ISCELL
  mstr_standard tap *
  page45_i78
#ISCELL
  mstr_standard tap *
  page45_i79
#ISCELL
  mstr_standard tap *
  page45_i8
#ISCELL
  mstr_standard tap *
  page45_i80
#ISCELL
  mstr_standard tap *
  page45_i81
#ISCELL
  mstr_standard tap *
  page45_i82
#ISCELL
  mstr_standard tap *
  page45_i83
#ISCELL
  mstr_standard tap *
  page45_i84
#ISCELL
  mstr_standard tap *
  page45_i85
#ISCELL
  mstr_standard tap *
  page45_i86
#ISCELL
  mstr_standard tap *
  page45_i87
#ISCELL
  mstr_standard tap *
  page45_i88
#ISCELL
  mstr_standard tap *
  page45_i89
#ISCELL
  mstr_standard tap *
  page45_i9
#ISCELL
  mstr_standard tap *
  page45_i90
#ISCELL
  mstr_standard tap *
  page45_i91
#ISCELL
  mstr_standard tap *
  page45_i92
#ISCELL
  mstr_standard tap *
  page45_i93
#ISCELL
  mstr_standard tap *
  page45_i94
#ISCELL
  mstr_standard tap *
  page45_i95
#ISCELL
  mstr_standard tap *
  page45_i96
#ISCELL
  mstr_standard tap *
  page45_i97
#ISCELL
  mstr_standard tap *
  page45_i98
#ISCELL
  mstr_standard tap *
  page45_i99
#ISCELL
  mstr_symbols bom_note *
  *
#ISCELL
  mstr_symbols intel_corp_bpage *
  *
#ISCELL
  mstr_symbols gnd *
  page46_i1
#ISCELL
  mstr_standard offpage *
  page46_i10
#ISCELL
  mstr_standard tap *
  page46_i100
#ISCELL
  mstr_standard tap *
  page46_i101
#ISCELL
  mstr_standard tap *
  page46_i102
#ISCELL
  mstr_standard tap *
  page46_i103
#ISCELL
  mstr_standard tap *
  page46_i104
#ISCELL
  mstr_standard tap *
  page46_i105
#ISCELL
  mstr_standard tap *
  page46_i106
#ISCELL
  mstr_standard tap *
  page46_i107
#ISCELL
  mstr_standard tap *
  page46_i108
#ISCELL
  mstr_symbols pvddq_abc *
  page46_i109
#ISCELL
  mstr_standard offpage *
  page46_i11
#ISCELL
  mstr_symbols pvtt_abc *
  page46_i110
#ISCELL
  mstr_symbols pvpp_abc *
  page46_i111
#CELL
  mstr_sconn sconn288_h44441003 *
  page46_i112
#ISCELL
  mstr_standard offpage *
  page46_i113
#ISCELL
  mstr_standard tap *
  page46_i114
#ISCELL
  mstr_standard tap *
  page46_i115
#ISCELL
  mstr_standard tap *
  page46_i116
#ISCELL
  mstr_standard tap *
  page46_i117
#ISCELL
  mstr_standard tap *
  page46_i118
#ISCELL
  mstr_standard tap *
  page46_i119
#ISCELL
  mstr_standard offpage *
  page46_i12
#ISCELL
  mstr_standard tap *
  page46_i120
#ISCELL
  mstr_standard tap *
  page46_i121
#ISCELL
  mstr_standard tap *
  page46_i122
#ISCELL
  mstr_standard tap *
  page46_i123
#ISCELL
  mstr_standard tap *
  page46_i124
#ISCELL
  mstr_standard tap *
  page46_i125
#ISCELL
  mstr_standard tap *
  page46_i126
#ISCELL
  mstr_standard tap *
  page46_i127
#ISCELL
  mstr_standard tap *
  page46_i128
#ISCELL
  mstr_standard tap *
  page46_i129
#ISCELL
  mstr_standard offpage *
  page46_i13
#ISCELL
  mstr_standard tap *
  page46_i130
#ISCELL
  mstr_standard tap *
  page46_i131
#ISCELL
  mstr_standard tap *
  page46_i132
#ISCELL
  mstr_standard tap *
  page46_i133
#ISCELL
  mstr_standard tap *
  page46_i134
#ISCELL
  mstr_standard tap *
  page46_i135
#ISCELL
  mstr_standard offpage *
  page46_i136
#ISCELL
  mstr_symbols gnd *
  page46_i137
#CELL
  mstr_sconn sconn288_h44441003 *
  page46_i138
#CELL
  mstr_sconn sconn288_h44441003 *
  page46_i14
#ISCELL
  mstr_standard tap *
  page46_i142
#ISCELL
  mstr_standard tap *
  page46_i143
#ISCELL
  mstr_standard tap *
  page46_i144
#ISCELL
  mstr_standard tap *
  page46_i145
#ISCELL
  mstr_standard tap *
  page46_i146
#ISCELL
  mstr_standard tap *
  page46_i147
#ISCELL
  mstr_standard tap *
  page46_i148
#ISCELL
  mstr_standard tap *
  page46_i149
#ISCELL
  mstr_standard offpage *
  page46_i15
#ISCELL
  mstr_standard tap *
  page46_i150
#ISCELL
  mstr_standard tap *
  page46_i151
#ISCELL
  mstr_standard tap *
  page46_i152
#ISCELL
  mstr_standard tap *
  page46_i153
#ISCELL
  mstr_standard tap *
  page46_i154
#ISCELL
  mstr_standard tap *
  page46_i155
#ISCELL
  mstr_symbols gnd *
  page46_i156
#ISCELL
  mstr_standard tap *
  page46_i157
#ISCELL
  mstr_standard tap *
  page46_i158
#ISCELL
  mstr_standard tap *
  page46_i159
#ISCELL
  mstr_standard offpage *
  page46_i16
#ISCELL
  mstr_standard tap *
  page46_i160
#ISCELL
  mstr_standard tap *
  page46_i161
#ISCELL
  mstr_standard tap *
  page46_i162
#ISCELL
  mstr_standard tap *
  page46_i163
#ISCELL
  mstr_standard tap *
  page46_i164
#ISCELL
  mstr_standard tap *
  page46_i165
#ISCELL
  mstr_standard tap *
  page46_i166
#ISCELL
  mstr_standard tap *
  page46_i167
#ISCELL
  mstr_standard tap *
  page46_i168
#ISCELL
  mstr_standard tap *
  page46_i169
#ISCELL
  mstr_standard offpage *
  page46_i17
#ISCELL
  mstr_standard tap *
  page46_i170
#ISCELL
  mstr_standard tap *
  page46_i171
#ISCELL
  mstr_standard tap *
  page46_i172
#ISCELL
  mstr_standard tap *
  page46_i173
#ISCELL
  mstr_standard tap *
  page46_i174
#ISCELL
  mstr_standard tap *
  page46_i175
#ISCELL
  mstr_standard tap *
  page46_i176
#ISCELL
  mstr_standard tap *
  page46_i177
#ISCELL
  mstr_standard tap *
  page46_i178
#ISCELL
  mstr_standard offpage *
  page46_i179
#ISCELL
  mstr_standard offpage *
  page46_i18
#ISCELL
  mstr_standard offpage *
  page46_i180
#ISCELL
  mstr_symbols p12v_nvdimm_abc *
  page46_i181
#ISCELL
  mstr_standard offpage *
  page46_i19
#ISCELL
  mstr_standard offpage *
  page46_i2
#ISCELL
  mstr_standard tap *
  page46_i20
#ISCELL
  mstr_standard tap *
  page46_i21
#ISCELL
  mstr_standard tap *
  page46_i22
#ISCELL
  mstr_standard tap *
  page46_i23
#ISCELL
  mstr_standard tap *
  page46_i24
#ISCELL
  mstr_standard tap *
  page46_i25
#ISCELL
  mstr_standard tap *
  page46_i26
#ISCELL
  mstr_standard tap *
  page46_i27
#ISCELL
  mstr_standard tap *
  page46_i28
#ISCELL
  mstr_standard tap *
  page46_i29
#ISCELL
  mstr_symbols gnd *
  page46_i3
#ISCELL
  mstr_standard tap *
  page46_i30
#ISCELL
  mstr_standard tap *
  page46_i31
#ISCELL
  mstr_standard tap *
  page46_i32
#ISCELL
  mstr_standard tap *
  page46_i33
#ISCELL
  mstr_standard tap *
  page46_i34
#ISCELL
  mstr_standard offpage *
  page46_i35
#ISCELL
  mstr_standard offpage *
  page46_i36
#ISCELL
  mstr_standard offpage *
  page46_i37
#ISCELL
  mstr_standard offpage *
  page46_i38
#ISCELL
  mstr_standard tap *
  page46_i39
#ISCELL
  mstr_symbols pvpp_abc *
  page46_i4
#ISCELL
  mstr_standard tap *
  page46_i40
#ISCELL
  mstr_standard tap *
  page46_i41
#ISCELL
  mstr_standard tap *
  page46_i42
#ISCELL
  mstr_standard tap *
  page46_i43
#ISCELL
  mstr_standard tap *
  page46_i44
#ISCELL
  mstr_standard tap *
  page46_i45
#ISCELL
  mstr_standard tap *
  page46_i46
#ISCELL
  mstr_standard tap *
  page46_i47
#ISCELL
  mstr_standard tap *
  page46_i48
#ISCELL
  mstr_standard tap *
  page46_i49
#CELL
  dev_discrete cap_a *
  page46_i5
#ISCELL
  mstr_standard tap *
  page46_i50
#ISCELL
  mstr_standard tap *
  page46_i51
#ISCELL
  mstr_standard tap *
  page46_i52
#ISCELL
  mstr_standard tap *
  page46_i53
#ISCELL
  mstr_standard tap *
  page46_i54
#ISCELL
  mstr_standard tap *
  page46_i55
#ISCELL
  mstr_standard tap *
  page46_i56
#ISCELL
  mstr_standard tap *
  page46_i57
#ISCELL
  mstr_standard tap *
  page46_i58
#ISCELL
  mstr_standard tap *
  page46_i59
#ISCELL
  mstr_standard offpage *
  page46_i6
#ISCELL
  mstr_standard tap *
  page46_i60
#ISCELL
  mstr_standard tap *
  page46_i61
#ISCELL
  mstr_standard tap *
  page46_i62
#ISCELL
  mstr_standard tap *
  page46_i63
#ISCELL
  mstr_standard tap *
  page46_i64
#ISCELL
  mstr_standard tap *
  page46_i65
#ISCELL
  mstr_standard tap *
  page46_i66
#CELL
  mstr_sconn sconn288_h44441003 *
  page46_i67
#ISCELL
  mstr_standard tap *
  page46_i68
#ISCELL
  mstr_standard tap *
  page46_i69
#ISCELL
  mstr_standard offpage *
  page46_i7
#ISCELL
  mstr_standard tap *
  page46_i70
#ISCELL
  mstr_standard tap *
  page46_i71
#ISCELL
  mstr_standard tap *
  page46_i72
#ISCELL
  mstr_standard tap *
  page46_i73
#ISCELL
  mstr_standard tap *
  page46_i74
#ISCELL
  mstr_standard tap *
  page46_i75
#ISCELL
  mstr_standard tap *
  page46_i76
#ISCELL
  mstr_standard tap *
  page46_i77
#ISCELL
  mstr_standard tap *
  page46_i78
#ISCELL
  mstr_standard tap *
  page46_i79
#ISCELL
  mstr_standard offpage *
  page46_i8
#ISCELL
  mstr_standard tap *
  page46_i80
#ISCELL
  mstr_standard tap *
  page46_i81
#ISCELL
  mstr_standard tap *
  page46_i82
#ISCELL
  mstr_standard tap *
  page46_i83
#ISCELL
  mstr_standard tap *
  page46_i84
#ISCELL
  mstr_standard tap *
  page46_i85
#ISCELL
  mstr_standard tap *
  page46_i86
#ISCELL
  mstr_standard tap *
  page46_i87
#ISCELL
  mstr_standard tap *
  page46_i88
#ISCELL
  mstr_standard tap *
  page46_i89
#ISCELL
  mstr_standard offpage *
  page46_i9
#ISCELL
  mstr_standard tap *
  page46_i90
#ISCELL
  mstr_standard tap *
  page46_i91
#ISCELL
  mstr_standard tap *
  page46_i92
#ISCELL
  mstr_standard tap *
  page46_i93
#ISCELL
  mstr_standard tap *
  page46_i94
#ISCELL
  mstr_standard tap *
  page46_i95
#ISCELL
  mstr_standard tap *
  page46_i96
#ISCELL
  mstr_standard tap *
  page46_i97
#ISCELL
  mstr_standard tap *
  page46_i98
#ISCELL
  mstr_standard tap *
  page46_i99
#ISCELL
  mstr_symbols bom_note *
  *
#ISCELL
  mstr_symbols intel_corp_bpage *
  *
#ISCELL
  mstr_standard offpage *
  page47_i1
#ISCELL
  mstr_standard tap *
  page47_i10
#ISCELL
  mstr_standard tap *
  page47_i100
#ISCELL
  mstr_standard tap *
  page47_i101
#ISCELL
  mstr_standard tap *
  page47_i102
#ISCELL
  mstr_standard tap *
  page47_i103
#ISCELL
  mstr_standard tap *
  page47_i104
#ISCELL
  mstr_standard tap *
  page47_i105
#ISCELL
  mstr_standard tap *
  page47_i106
#ISCELL
  mstr_standard tap *
  page47_i107
#ISCELL
  mstr_standard tap *
  page47_i108
#ISCELL
  mstr_standard tap *
  page47_i109
#ISCELL
  mstr_standard tap *
  page47_i110
#CELL
  mstr_sconn sconn288_h44441004 *
  page47_i111
#ISCELL
  mstr_standard tap *
  page47_i112
#ISCELL
  mstr_standard tap *
  page47_i113
#ISCELL
  mstr_standard tap *
  page47_i114
#ISCELL
  mstr_standard tap *
  page47_i115
#ISCELL
  mstr_standard tap *
  page47_i116
#ISCELL
  mstr_standard tap *
  page47_i117
#ISCELL
  mstr_standard tap *
  page47_i118
#ISCELL
  mstr_standard tap *
  page47_i119
#ISCELL
  mstr_symbols pvtt_abc *
  page47_i12
#ISCELL
  mstr_standard tap *
  page47_i120
#ISCELL
  mstr_standard tap *
  page47_i121
#ISCELL
  mstr_standard tap *
  page47_i122
#ISCELL
  mstr_standard tap *
  page47_i123
#ISCELL
  mstr_standard tap *
  page47_i124
#ISCELL
  mstr_standard tap *
  page47_i125
#ISCELL
  mstr_standard tap *
  page47_i126
#ISCELL
  mstr_standard offpage *
  page47_i127
#ISCELL
  mstr_standard tap *
  page47_i128
#ISCELL
  mstr_standard tap *
  page47_i129
#ISCELL
  mstr_symbols pvddq_abc *
  page47_i13
#ISCELL
  mstr_standard tap *
  page47_i130
#ISCELL
  mstr_standard tap *
  page47_i131
#ISCELL
  mstr_standard tap *
  page47_i132
#ISCELL
  mstr_standard tap *
  page47_i133
#ISCELL
  mstr_standard tap *
  page47_i134
#ISCELL
  mstr_standard offpage *
  page47_i135
#ISCELL
  mstr_standard offpage *
  page47_i136
#ISCELL
  mstr_standard offpage *
  page47_i137
#ISCELL
  mstr_standard tap *
  page47_i138
#ISCELL
  mstr_standard tap *
  page47_i139
#ISCELL
  mstr_standard tap *
  page47_i14
#ISCELL
  mstr_standard tap *
  page47_i140
#ISCELL
  mstr_standard tap *
  page47_i141
#ISCELL
  mstr_standard tap *
  page47_i142
#ISCELL
  mstr_standard tap *
  page47_i143
#ISCELL
  mstr_standard tap *
  page47_i144
#ISCELL
  mstr_standard tap *
  page47_i145
#ISCELL
  mstr_standard offpage *
  page47_i146
#ISCELL
  mstr_standard offpage *
  page47_i147
#ISCELL
  mstr_standard offpage *
  page47_i148
#ISCELL
  mstr_standard offpage *
  page47_i149
#ISCELL
  mstr_standard tap *
  page47_i15
#ISCELL
  mstr_standard offpage *
  page47_i150
#ISCELL
  mstr_standard offpage *
  page47_i151
#ISCELL
  mstr_standard tap *
  page47_i152
#ISCELL
  mstr_standard tap *
  page47_i153
#ISCELL
  mstr_standard offpage *
  page47_i154
#ISCELL
  mstr_standard tap *
  page47_i155
#ISCELL
  mstr_standard tap *
  page47_i156
#ISCELL
  mstr_standard offpage *
  page47_i157
#ISCELL
  mstr_standard tap *
  page47_i158
#ISCELL
  mstr_standard offpage *
  page47_i159
#ISCELL
  mstr_standard tap *
  page47_i16
#ISCELL
  mstr_standard tap *
  page47_i160
#ISCELL
  mstr_standard tap *
  page47_i161
#ISCELL
  mstr_standard tap *
  page47_i162
#ISCELL
  mstr_standard tap *
  page47_i17
#ISCELL
  mstr_standard tap *
  page47_i174
#ISCELL
  mstr_standard tap *
  page47_i175
#ISCELL
  mstr_standard offpage *
  page47_i177
#ISCELL
  mstr_standard offpage *
  page47_i178
#CELL
  mstr_sconn sconn288_h44441004 *
  page47_i179
#ISCELL
  mstr_standard tap *
  page47_i18
#ISCELL
  mstr_symbols gnd *
  page47_i180
#ISCELL
  mstr_standard offpage *
  page47_i183
#ISCELL
  mstr_symbols gnd *
  page47_i184
#ISCELL
  mstr_standard offpage *
  page47_i186
#ISCELL
  mstr_standard offpage *
  page47_i187
#CELL
  dev_discrete cap_a *
  page47_i188
#ISCELL
  mstr_symbols gnd *
  page47_i189
#ISCELL
  mstr_standard tap *
  page47_i19
#ISCELL
  mstr_symbols pvpp_abc *
  page47_i190
#ISCELL
  mstr_symbols pvpp_abc *
  page47_i191
#ISCELL
  mstr_standard offpage *
  page47_i192
#ISCELL
  mstr_standard tap *
  page47_i196
#ISCELL
  mstr_standard tap *
  page47_i197
#ISCELL
  mstr_symbols p12v_nvdimm_abc *
  page47_i198
#ISCELL
  mstr_standard offpage *
  page47_i2
#ISCELL
  mstr_standard tap *
  page47_i20
#ISCELL
  mstr_standard tap *
  page47_i21
#ISCELL
  mstr_standard tap *
  page47_i22
#ISCELL
  mstr_standard tap *
  page47_i23
#ISCELL
  mstr_standard tap *
  page47_i24
#ISCELL
  mstr_standard tap *
  page47_i25
#ISCELL
  mstr_standard tap *
  page47_i26
#ISCELL
  mstr_standard tap *
  page47_i27
#ISCELL
  mstr_standard tap *
  page47_i28
#ISCELL
  mstr_standard tap *
  page47_i29
#ISCELL
  mstr_standard tap *
  page47_i3
#ISCELL
  mstr_standard tap *
  page47_i30
#ISCELL
  mstr_standard tap *
  page47_i31
#ISCELL
  mstr_standard tap *
  page47_i32
#ISCELL
  mstr_standard tap *
  page47_i33
#ISCELL
  mstr_standard tap *
  page47_i34
#ISCELL
  mstr_standard tap *
  page47_i35
#ISCELL
  mstr_standard tap *
  page47_i36
#ISCELL
  mstr_standard tap *
  page47_i37
#ISCELL
  mstr_standard tap *
  page47_i38
#ISCELL
  mstr_standard tap *
  page47_i39
#ISCELL
  mstr_standard tap *
  page47_i4
#ISCELL
  mstr_standard tap *
  page47_i40
#ISCELL
  mstr_standard tap *
  page47_i41
#CELL
  mstr_sconn sconn288_h44441004 *
  page47_i43
#ISCELL
  mstr_symbols gnd *
  page47_i44
#ISCELL
  mstr_standard offpage *
  page47_i45
#ISCELL
  mstr_standard tap *
  page47_i46
#ISCELL
  mstr_standard tap *
  page47_i47
#ISCELL
  mstr_standard tap *
  page47_i48
#ISCELL
  mstr_standard tap *
  page47_i49
#ISCELL
  mstr_standard tap *
  page47_i5
#ISCELL
  mstr_standard tap *
  page47_i50
#ISCELL
  mstr_standard tap *
  page47_i51
#ISCELL
  mstr_standard tap *
  page47_i52
#ISCELL
  mstr_standard tap *
  page47_i53
#ISCELL
  mstr_standard tap *
  page47_i54
#ISCELL
  mstr_standard tap *
  page47_i55
#ISCELL
  mstr_standard tap *
  page47_i56
#ISCELL
  mstr_standard tap *
  page47_i57
#ISCELL
  mstr_standard tap *
  page47_i58
#ISCELL
  mstr_standard tap *
  page47_i59
#ISCELL
  mstr_standard tap *
  page47_i6
#ISCELL
  mstr_standard tap *
  page47_i60
#CELL
  mstr_sconn sconn288_h44441004 *
  page47_i61
#ISCELL
  mstr_standard tap *
  page47_i62
#ISCELL
  mstr_standard tap *
  page47_i63
#ISCELL
  mstr_standard tap *
  page47_i64
#ISCELL
  mstr_standard tap *
  page47_i65
#ISCELL
  mstr_standard tap *
  page47_i66
#ISCELL
  mstr_standard tap *
  page47_i67
#ISCELL
  mstr_standard tap *
  page47_i68
#ISCELL
  mstr_standard tap *
  page47_i69
#ISCELL
  mstr_standard tap *
  page47_i7
#ISCELL
  mstr_standard tap *
  page47_i70
#ISCELL
  mstr_standard tap *
  page47_i71
#ISCELL
  mstr_standard tap *
  page47_i72
#ISCELL
  mstr_standard tap *
  page47_i73
#ISCELL
  mstr_standard tap *
  page47_i74
#ISCELL
  mstr_standard tap *
  page47_i75
#ISCELL
  mstr_standard tap *
  page47_i76
#ISCELL
  mstr_standard tap *
  page47_i77
#ISCELL
  mstr_standard tap *
  page47_i78
#ISCELL
  mstr_standard tap *
  page47_i79
#ISCELL
  mstr_standard tap *
  page47_i8
#ISCELL
  mstr_standard tap *
  page47_i80
#ISCELL
  mstr_standard tap *
  page47_i81
#ISCELL
  mstr_standard tap *
  page47_i82
#ISCELL
  mstr_standard tap *
  page47_i83
#ISCELL
  mstr_standard tap *
  page47_i84
#ISCELL
  mstr_standard tap *
  page47_i85
#ISCELL
  mstr_standard tap *
  page47_i86
#ISCELL
  mstr_standard tap *
  page47_i87
#ISCELL
  mstr_standard tap *
  page47_i88
#ISCELL
  mstr_standard tap *
  page47_i89
#ISCELL
  mstr_standard tap *
  page47_i9
#ISCELL
  mstr_standard tap *
  page47_i90
#ISCELL
  mstr_standard tap *
  page47_i91
#ISCELL
  mstr_standard tap *
  page47_i92
#ISCELL
  mstr_standard tap *
  page47_i93
#ISCELL
  mstr_standard tap *
  page47_i94
#ISCELL
  mstr_standard tap *
  page47_i95
#ISCELL
  mstr_standard tap *
  page47_i96
#ISCELL
  mstr_standard tap *
  page47_i97
#ISCELL
  mstr_standard tap *
  page47_i98
#ISCELL
  mstr_standard tap *
  page47_i99
#ISCELL
  mstr_symbols bom_note *
  *
#ISCELL
  mstr_symbols intel_corp_bpage *
  *
#ISCELL
  mstr_standard offpage *
  page48_i1
#ISCELL
  mstr_standard tap *
  page48_i10
#ISCELL
  mstr_standard tap *
  page48_i100
#ISCELL
  mstr_standard tap *
  page48_i101
#ISCELL
  mstr_standard tap *
  page48_i102
#ISCELL
  mstr_standard tap *
  page48_i103
#ISCELL
  mstr_standard tap *
  page48_i104
#ISCELL
  mstr_standard tap *
  page48_i105
#ISCELL
  mstr_standard tap *
  page48_i106
#ISCELL
  mstr_standard tap *
  page48_i107
#ISCELL
  mstr_standard tap *
  page48_i108
#ISCELL
  mstr_standard tap *
  page48_i109
#ISCELL
  mstr_standard tap *
  page48_i110
#CELL
  mstr_sconn sconn288_h44441003 *
  page48_i111
#ISCELL
  mstr_standard tap *
  page48_i112
#ISCELL
  mstr_standard tap *
  page48_i113
#ISCELL
  mstr_standard tap *
  page48_i114
#ISCELL
  mstr_standard tap *
  page48_i115
#ISCELL
  mstr_standard tap *
  page48_i116
#ISCELL
  mstr_standard tap *
  page48_i117
#ISCELL
  mstr_standard tap *
  page48_i118
#ISCELL
  mstr_standard tap *
  page48_i119
#ISCELL
  mstr_symbols pvtt_abc *
  page48_i12
#ISCELL
  mstr_standard tap *
  page48_i120
#ISCELL
  mstr_standard tap *
  page48_i121
#ISCELL
  mstr_standard tap *
  page48_i122
#ISCELL
  mstr_standard tap *
  page48_i123
#ISCELL
  mstr_standard tap *
  page48_i124
#ISCELL
  mstr_standard tap *
  page48_i125
#ISCELL
  mstr_standard tap *
  page48_i126
#ISCELL
  mstr_standard offpage *
  page48_i127
#ISCELL
  mstr_standard tap *
  page48_i128
#ISCELL
  mstr_standard tap *
  page48_i129
#ISCELL
  mstr_symbols pvddq_abc *
  page48_i13
#ISCELL
  mstr_standard tap *
  page48_i130
#ISCELL
  mstr_standard tap *
  page48_i131
#ISCELL
  mstr_standard tap *
  page48_i132
#ISCELL
  mstr_standard tap *
  page48_i133
#ISCELL
  mstr_standard tap *
  page48_i134
#ISCELL
  mstr_standard offpage *
  page48_i135
#ISCELL
  mstr_standard offpage *
  page48_i136
#ISCELL
  mstr_standard offpage *
  page48_i137
#ISCELL
  mstr_standard tap *
  page48_i138
#ISCELL
  mstr_standard tap *
  page48_i139
#ISCELL
  mstr_standard tap *
  page48_i14
#ISCELL
  mstr_standard tap *
  page48_i140
#ISCELL
  mstr_standard tap *
  page48_i141
#ISCELL
  mstr_standard tap *
  page48_i142
#ISCELL
  mstr_standard tap *
  page48_i143
#ISCELL
  mstr_standard tap *
  page48_i144
#ISCELL
  mstr_standard tap *
  page48_i145
#ISCELL
  mstr_standard offpage *
  page48_i146
#ISCELL
  mstr_standard offpage *
  page48_i147
#ISCELL
  mstr_standard offpage *
  page48_i148
#ISCELL
  mstr_standard offpage *
  page48_i149
#ISCELL
  mstr_standard tap *
  page48_i15
#ISCELL
  mstr_standard offpage *
  page48_i150
#ISCELL
  mstr_standard offpage *
  page48_i151
#ISCELL
  mstr_standard tap *
  page48_i152
#ISCELL
  mstr_standard offpage *
  page48_i153
#ISCELL
  mstr_standard tap *
  page48_i154
#ISCELL
  mstr_standard tap *
  page48_i155
#ISCELL
  mstr_standard offpage *
  page48_i156
#ISCELL
  mstr_standard tap *
  page48_i157
#ISCELL
  mstr_standard tap *
  page48_i158
#ISCELL
  mstr_standard tap *
  page48_i159
#ISCELL
  mstr_standard tap *
  page48_i16
#ISCELL
  mstr_standard tap *
  page48_i160
#ISCELL
  mstr_standard tap *
  page48_i161
#ISCELL
  mstr_standard offpage *
  page48_i162
#ISCELL
  mstr_standard tap *
  page48_i163
#ISCELL
  mstr_standard tap *
  page48_i164
#ISCELL
  mstr_standard tap *
  page48_i165
#ISCELL
  mstr_standard tap *
  page48_i166
#ISCELL
  mstr_standard offpage *
  page48_i167
#ISCELL
  mstr_standard offpage *
  page48_i168
#ISCELL
  mstr_standard offpage *
  page48_i169
#ISCELL
  mstr_standard tap *
  page48_i17
#ISCELL
  mstr_standard offpage *
  page48_i170
#CELL
  mstr_sconn sconn288_h44441003 *
  page48_i171
#ISCELL
  mstr_symbols gnd *
  page48_i172
#ISCELL
  mstr_standard offpage *
  page48_i173
#CELL
  dev_discrete cap_a *
  page48_i176
#ISCELL
  mstr_symbols gnd *
  page48_i177
#ISCELL
  mstr_symbols pvpp_abc *
  page48_i178
#ISCELL
  mstr_symbols pvpp_abc *
  page48_i179
#ISCELL
  mstr_standard tap *
  page48_i18
#ISCELL
  mstr_standard offpage *
  page48_i180
#ISCELL
  mstr_symbols gnd *
  page48_i184
#ISCELL
  mstr_symbols p12v_nvdimm_abc *
  page48_i185
#ISCELL
  mstr_standard tap *
  page48_i19
#ISCELL
  mstr_standard offpage *
  page48_i2
#ISCELL
  mstr_standard tap *
  page48_i20
#ISCELL
  mstr_standard tap *
  page48_i21
#ISCELL
  mstr_standard tap *
  page48_i22
#ISCELL
  mstr_standard tap *
  page48_i23
#ISCELL
  mstr_standard tap *
  page48_i24
#ISCELL
  mstr_standard tap *
  page48_i25
#ISCELL
  mstr_standard tap *
  page48_i26
#ISCELL
  mstr_standard tap *
  page48_i27
#ISCELL
  mstr_standard tap *
  page48_i28
#ISCELL
  mstr_standard tap *
  page48_i29
#ISCELL
  mstr_standard tap *
  page48_i3
#ISCELL
  mstr_standard tap *
  page48_i30
#ISCELL
  mstr_standard tap *
  page48_i31
#ISCELL
  mstr_standard tap *
  page48_i32
#ISCELL
  mstr_standard tap *
  page48_i33
#ISCELL
  mstr_standard tap *
  page48_i34
#ISCELL
  mstr_standard tap *
  page48_i35
#ISCELL
  mstr_standard tap *
  page48_i36
#ISCELL
  mstr_standard tap *
  page48_i37
#ISCELL
  mstr_standard tap *
  page48_i38
#ISCELL
  mstr_standard tap *
  page48_i39
#ISCELL
  mstr_standard tap *
  page48_i4
#ISCELL
  mstr_standard tap *
  page48_i40
#ISCELL
  mstr_standard tap *
  page48_i41
#CELL
  mstr_sconn sconn288_h44441003 *
  page48_i43
#ISCELL
  mstr_symbols gnd *
  page48_i44
#ISCELL
  mstr_standard offpage *
  page48_i45
#ISCELL
  mstr_standard tap *
  page48_i46
#ISCELL
  mstr_standard tap *
  page48_i47
#ISCELL
  mstr_standard tap *
  page48_i48
#ISCELL
  mstr_standard tap *
  page48_i49
#ISCELL
  mstr_standard tap *
  page48_i5
#ISCELL
  mstr_standard tap *
  page48_i50
#ISCELL
  mstr_standard tap *
  page48_i51
#ISCELL
  mstr_standard tap *
  page48_i52
#ISCELL
  mstr_standard tap *
  page48_i53
#ISCELL
  mstr_standard tap *
  page48_i54
#ISCELL
  mstr_standard tap *
  page48_i55
#ISCELL
  mstr_standard tap *
  page48_i56
#ISCELL
  mstr_standard tap *
  page48_i57
#ISCELL
  mstr_standard tap *
  page48_i58
#ISCELL
  mstr_standard tap *
  page48_i59
#ISCELL
  mstr_standard tap *
  page48_i6
#ISCELL
  mstr_standard tap *
  page48_i60
#CELL
  mstr_sconn sconn288_h44441003 *
  page48_i61
#ISCELL
  mstr_standard tap *
  page48_i62
#ISCELL
  mstr_standard tap *
  page48_i63
#ISCELL
  mstr_standard tap *
  page48_i64
#ISCELL
  mstr_standard tap *
  page48_i65
#ISCELL
  mstr_standard tap *
  page48_i66
#ISCELL
  mstr_standard tap *
  page48_i67
#ISCELL
  mstr_standard tap *
  page48_i68
#ISCELL
  mstr_standard tap *
  page48_i69
#ISCELL
  mstr_standard tap *
  page48_i7
#ISCELL
  mstr_standard tap *
  page48_i70
#ISCELL
  mstr_standard tap *
  page48_i71
#ISCELL
  mstr_standard tap *
  page48_i72
#ISCELL
  mstr_standard tap *
  page48_i73
#ISCELL
  mstr_standard tap *
  page48_i74
#ISCELL
  mstr_standard tap *
  page48_i75
#ISCELL
  mstr_standard tap *
  page48_i76
#ISCELL
  mstr_standard tap *
  page48_i77
#ISCELL
  mstr_standard tap *
  page48_i78
#ISCELL
  mstr_standard tap *
  page48_i79
#ISCELL
  mstr_standard tap *
  page48_i8
#ISCELL
  mstr_standard tap *
  page48_i80
#ISCELL
  mstr_standard tap *
  page48_i81
#ISCELL
  mstr_standard tap *
  page48_i82
#ISCELL
  mstr_standard tap *
  page48_i83
#ISCELL
  mstr_standard tap *
  page48_i84
#ISCELL
  mstr_standard tap *
  page48_i85
#ISCELL
  mstr_standard tap *
  page48_i86
#ISCELL
  mstr_standard tap *
  page48_i87
#ISCELL
  mstr_standard tap *
  page48_i88
#ISCELL
  mstr_standard tap *
  page48_i89
#ISCELL
  mstr_standard tap *
  page48_i9
#ISCELL
  mstr_standard tap *
  page48_i90
#ISCELL
  mstr_standard tap *
  page48_i91
#ISCELL
  mstr_standard tap *
  page48_i92
#ISCELL
  mstr_standard tap *
  page48_i93
#ISCELL
  mstr_standard tap *
  page48_i94
#ISCELL
  mstr_standard tap *
  page48_i95
#ISCELL
  mstr_standard tap *
  page48_i96
#ISCELL
  mstr_standard tap *
  page48_i97
#ISCELL
  mstr_standard tap *
  page48_i98
#ISCELL
  mstr_standard tap *
  page48_i99
#ISCELL
  mstr_symbols bom_note *
  *
#ISCELL
  mstr_symbols intel_corp_bpage *
  *
#ISCELL
  mstr_standard offpage *
  page49_i1
#ISCELL
  mstr_standard tap *
  page49_i10
#ISCELL
  mstr_standard tap *
  page49_i100
#ISCELL
  mstr_standard tap *
  page49_i101
#ISCELL
  mstr_standard tap *
  page49_i102
#ISCELL
  mstr_standard tap *
  page49_i103
#ISCELL
  mstr_standard tap *
  page49_i104
#ISCELL
  mstr_standard tap *
  page49_i105
#ISCELL
  mstr_standard tap *
  page49_i106
#ISCELL
  mstr_standard tap *
  page49_i107
#ISCELL
  mstr_standard tap *
  page49_i108
#ISCELL
  mstr_standard tap *
  page49_i109
#ISCELL
  mstr_standard tap *
  page49_i11
#ISCELL
  mstr_standard tap *
  page49_i110
#CELL
  mstr_sconn sconn288_h44441004 *
  page49_i111
#ISCELL
  mstr_standard tap *
  page49_i112
#ISCELL
  mstr_standard tap *
  page49_i113
#ISCELL
  mstr_standard tap *
  page49_i114
#ISCELL
  mstr_standard tap *
  page49_i115
#ISCELL
  mstr_standard tap *
  page49_i116
#ISCELL
  mstr_standard tap *
  page49_i117
#ISCELL
  mstr_standard tap *
  page49_i118
#ISCELL
  mstr_standard tap *
  page49_i119
#ISCELL
  mstr_standard tap *
  page49_i12
#ISCELL
  mstr_standard tap *
  page49_i120
#ISCELL
  mstr_standard tap *
  page49_i121
#ISCELL
  mstr_standard tap *
  page49_i122
#ISCELL
  mstr_standard tap *
  page49_i123
#ISCELL
  mstr_standard tap *
  page49_i124
#ISCELL
  mstr_standard tap *
  page49_i125
#ISCELL
  mstr_standard tap *
  page49_i126
#ISCELL
  mstr_standard tap *
  page49_i127
#ISCELL
  mstr_standard tap *
  page49_i128
#ISCELL
  mstr_standard tap *
  page49_i129
#ISCELL
  mstr_standard tap *
  page49_i13
#ISCELL
  mstr_standard tap *
  page49_i130
#ISCELL
  mstr_standard offpage *
  page49_i131
#ISCELL
  mstr_standard offpage *
  page49_i132
#ISCELL
  mstr_standard tap *
  page49_i133
#ISCELL
  mstr_standard tap *
  page49_i134
#ISCELL
  mstr_standard tap *
  page49_i135
#ISCELL
  mstr_standard offpage *
  page49_i136
#ISCELL
  mstr_standard offpage *
  page49_i137
#ISCELL
  mstr_standard tap *
  page49_i138
#ISCELL
  mstr_standard tap *
  page49_i139
#ISCELL
  mstr_standard tap *
  page49_i14
#ISCELL
  mstr_standard tap *
  page49_i140
#ISCELL
  mstr_standard tap *
  page49_i141
#ISCELL
  mstr_standard tap *
  page49_i142
#ISCELL
  mstr_standard tap *
  page49_i143
#ISCELL
  mstr_standard tap *
  page49_i144
#ISCELL
  mstr_standard tap *
  page49_i145
#ISCELL
  mstr_standard offpage *
  page49_i146
#ISCELL
  mstr_standard offpage *
  page49_i147
#ISCELL
  mstr_standard offpage *
  page49_i148
#ISCELL
  mstr_standard offpage *
  page49_i149
#ISCELL
  mstr_standard tap *
  page49_i15
#ISCELL
  mstr_standard offpage *
  page49_i150
#ISCELL
  mstr_standard offpage *
  page49_i151
#ISCELL
  mstr_standard tap *
  page49_i152
#ISCELL
  mstr_standard tap *
  page49_i153
#ISCELL
  mstr_standard tap *
  page49_i154
#ISCELL
  mstr_standard tap *
  page49_i155
#ISCELL
  mstr_standard offpage *
  page49_i156
#ISCELL
  mstr_standard offpage *
  page49_i157
#ISCELL
  mstr_standard tap *
  page49_i158
#ISCELL
  mstr_standard tap *
  page49_i159
#ISCELL
  mstr_symbols pvddq_def *
  page49_i16
#ISCELL
  mstr_standard tap *
  page49_i160
#ISCELL
  mstr_standard tap *
  page49_i161
#ISCELL
  mstr_standard tap *
  page49_i162
#ISCELL
  mstr_standard tap *
  page49_i163
#ISCELL
  mstr_standard offpage *
  page49_i164
#ISCELL
  mstr_standard offpage *
  page49_i165
#ISCELL
  mstr_standard offpage *
  page49_i166
#ISCELL
  mstr_standard tap *
  page49_i167
#ISCELL
  mstr_standard tap *
  page49_i168
#CELL
  mstr_sconn sconn288_h44441004 *
  page49_i169
#ISCELL
  mstr_symbols pvtt_def *
  page49_i170
#ISCELL
  mstr_symbols gnd *
  page49_i171
#ISCELL
  mstr_standard offpage *
  page49_i174
#ISCELL
  mstr_standard offpage *
  page49_i175
#ISCELL
  mstr_standard offpage *
  page49_i176
#ISCELL
  mstr_symbols gnd *
  page49_i178
#CELL
  dev_discrete cap_a *
  page49_i179
#ISCELL
  mstr_symbols gnd *
  page49_i180
#ISCELL
  mstr_symbols pvpp_def *
  page49_i181
#ISCELL
  mstr_symbols pvpp_def *
  page49_i182
#ISCELL
  mstr_standard offpage *
  page49_i183
#ISCELL
  mstr_symbols p12v_nvdimm_def *
  page49_i184
#ISCELL
  mstr_standard tap *
  page49_i19
#ISCELL
  mstr_standard offpage *
  page49_i2
#ISCELL
  mstr_standard tap *
  page49_i20
#ISCELL
  mstr_standard tap *
  page49_i21
#ISCELL
  mstr_standard tap *
  page49_i22
#ISCELL
  mstr_standard tap *
  page49_i23
#ISCELL
  mstr_standard tap *
  page49_i24
#ISCELL
  mstr_standard tap *
  page49_i25
#ISCELL
  mstr_standard tap *
  page49_i26
#ISCELL
  mstr_standard tap *
  page49_i27
#ISCELL
  mstr_standard tap *
  page49_i28
#ISCELL
  mstr_standard tap *
  page49_i29
#ISCELL
  mstr_standard tap *
  page49_i3
#ISCELL
  mstr_standard tap *
  page49_i30
#ISCELL
  mstr_standard tap *
  page49_i31
#ISCELL
  mstr_standard tap *
  page49_i32
#ISCELL
  mstr_standard tap *
  page49_i33
#ISCELL
  mstr_standard tap *
  page49_i34
#ISCELL
  mstr_standard tap *
  page49_i35
#ISCELL
  mstr_standard tap *
  page49_i36
#ISCELL
  mstr_standard tap *
  page49_i37
#ISCELL
  mstr_standard tap *
  page49_i38
#ISCELL
  mstr_standard tap *
  page49_i39
#ISCELL
  mstr_standard tap *
  page49_i4
#ISCELL
  mstr_standard tap *
  page49_i40
#ISCELL
  mstr_standard tap *
  page49_i41
#CELL
  mstr_sconn sconn288_h44441004 *
  page49_i43
#ISCELL
  mstr_symbols gnd *
  page49_i44
#ISCELL
  mstr_standard offpage *
  page49_i45
#ISCELL
  mstr_standard tap *
  page49_i46
#ISCELL
  mstr_standard tap *
  page49_i47
#ISCELL
  mstr_standard tap *
  page49_i48
#ISCELL
  mstr_standard tap *
  page49_i49
#ISCELL
  mstr_standard tap *
  page49_i5
#ISCELL
  mstr_standard tap *
  page49_i50
#ISCELL
  mstr_standard tap *
  page49_i51
#ISCELL
  mstr_standard tap *
  page49_i52
#ISCELL
  mstr_standard tap *
  page49_i53
#ISCELL
  mstr_standard tap *
  page49_i54
#ISCELL
  mstr_standard tap *
  page49_i55
#ISCELL
  mstr_standard tap *
  page49_i56
#ISCELL
  mstr_standard tap *
  page49_i57
#ISCELL
  mstr_standard tap *
  page49_i58
#ISCELL
  mstr_standard tap *
  page49_i59
#ISCELL
  mstr_standard tap *
  page49_i6
#ISCELL
  mstr_standard tap *
  page49_i60
#ISCELL
  mstr_standard tap *
  page49_i61
#ISCELL
  mstr_standard tap *
  page49_i62
#ISCELL
  mstr_standard tap *
  page49_i63
#ISCELL
  mstr_standard tap *
  page49_i64
#ISCELL
  mstr_standard tap *
  page49_i65
#CELL
  mstr_sconn sconn288_h44441004 *
  page49_i66
#ISCELL
  mstr_standard tap *
  page49_i67
#ISCELL
  mstr_standard tap *
  page49_i68
#ISCELL
  mstr_standard tap *
  page49_i69
#ISCELL
  mstr_standard tap *
  page49_i7
#ISCELL
  mstr_standard tap *
  page49_i70
#ISCELL
  mstr_standard tap *
  page49_i71
#ISCELL
  mstr_standard tap *
  page49_i72
#ISCELL
  mstr_standard tap *
  page49_i73
#ISCELL
  mstr_standard tap *
  page49_i74
#ISCELL
  mstr_standard tap *
  page49_i75
#ISCELL
  mstr_standard tap *
  page49_i76
#ISCELL
  mstr_standard tap *
  page49_i77
#ISCELL
  mstr_standard tap *
  page49_i78
#ISCELL
  mstr_standard tap *
  page49_i79
#ISCELL
  mstr_standard tap *
  page49_i8
#ISCELL
  mstr_standard tap *
  page49_i80
#ISCELL
  mstr_standard tap *
  page49_i81
#ISCELL
  mstr_standard tap *
  page49_i82
#ISCELL
  mstr_standard tap *
  page49_i83
#ISCELL
  mstr_standard tap *
  page49_i84
#ISCELL
  mstr_standard tap *
  page49_i85
#ISCELL
  mstr_standard tap *
  page49_i86
#ISCELL
  mstr_standard tap *
  page49_i87
#ISCELL
  mstr_standard tap *
  page49_i88
#ISCELL
  mstr_standard tap *
  page49_i89
#ISCELL
  mstr_standard tap *
  page49_i9
#ISCELL
  mstr_standard tap *
  page49_i90
#ISCELL
  mstr_standard tap *
  page49_i91
#ISCELL
  mstr_standard tap *
  page49_i92
#ISCELL
  mstr_standard tap *
  page49_i93
#ISCELL
  mstr_standard tap *
  page49_i94
#ISCELL
  mstr_standard tap *
  page49_i95
#ISCELL
  mstr_standard tap *
  page49_i96
#ISCELL
  mstr_standard tap *
  page49_i97
#ISCELL
  mstr_standard tap *
  page49_i98
#ISCELL
  mstr_standard tap *
  page49_i99
#ISCELL
  mstr_symbols bom_note *
  *
#ISCELL
  mstr_symbols intel_corp_bpage *
  *
#ISCELL
  mstr_symbols gnd *
  page50_i1
#ISCELL
  mstr_standard tap *
  page50_i10
#ISCELL
  mstr_standard tap *
  page50_i100
#ISCELL
  mstr_standard tap *
  page50_i101
#ISCELL
  mstr_standard tap *
  page50_i102
#ISCELL
  mstr_standard tap *
  page50_i103
#ISCELL
  mstr_standard tap *
  page50_i104
#ISCELL
  mstr_standard tap *
  page50_i105
#ISCELL
  mstr_standard tap *
  page50_i106
#ISCELL
  mstr_standard tap *
  page50_i107
#ISCELL
  mstr_standard tap *
  page50_i108
#ISCELL
  mstr_standard tap *
  page50_i109
#ISCELL
  mstr_standard tap *
  page50_i11
#ISCELL
  mstr_standard tap *
  page50_i110
#ISCELL
  mstr_standard tap *
  page50_i111
#ISCELL
  mstr_standard tap *
  page50_i112
#ISCELL
  mstr_standard tap *
  page50_i113
#ISCELL
  mstr_standard tap *
  page50_i114
#ISCELL
  mstr_standard tap *
  page50_i115
#ISCELL
  mstr_standard tap *
  page50_i116
#ISCELL
  mstr_standard tap *
  page50_i117
#ISCELL
  mstr_standard tap *
  page50_i118
#ISCELL
  mstr_standard tap *
  page50_i119
#ISCELL
  mstr_standard tap *
  page50_i12
#ISCELL
  mstr_standard tap *
  page50_i120
#ISCELL
  mstr_standard tap *
  page50_i121
#ISCELL
  mstr_standard tap *
  page50_i122
#ISCELL
  mstr_standard tap *
  page50_i123
#ISCELL
  mstr_standard tap *
  page50_i124
#ISCELL
  mstr_standard tap *
  page50_i125
#ISCELL
  mstr_standard tap *
  page50_i126
#ISCELL
  mstr_standard tap *
  page50_i127
#ISCELL
  mstr_standard tap *
  page50_i128
#ISCELL
  mstr_standard tap *
  page50_i129
#ISCELL
  mstr_standard tap *
  page50_i13
#ISCELL
  mstr_standard tap *
  page50_i130
#ISCELL
  mstr_standard tap *
  page50_i131
#ISCELL
  mstr_standard tap *
  page50_i132
#ISCELL
  mstr_standard tap *
  page50_i133
#ISCELL
  mstr_standard tap *
  page50_i134
#ISCELL
  mstr_standard tap *
  page50_i135
#ISCELL
  mstr_standard tap *
  page50_i136
#ISCELL
  mstr_standard tap *
  page50_i137
#ISCELL
  mstr_standard tap *
  page50_i138
#ISCELL
  mstr_standard tap *
  page50_i139
#ISCELL
  mstr_standard tap *
  page50_i14
#ISCELL
  mstr_standard tap *
  page50_i140
#ISCELL
  mstr_standard tap *
  page50_i141
#ISCELL
  mstr_standard tap *
  page50_i142
#ISCELL
  mstr_standard tap *
  page50_i143
#ISCELL
  mstr_standard tap *
  page50_i144
#ISCELL
  mstr_standard tap *
  page50_i145
#ISCELL
  mstr_standard tap *
  page50_i146
#ISCELL
  mstr_standard tap *
  page50_i147
#ISCELL
  mstr_standard tap *
  page50_i148
#ISCELL
  mstr_standard tap *
  page50_i149
#ISCELL
  mstr_standard tap *
  page50_i15
#ISCELL
  mstr_standard tap *
  page50_i150
#ISCELL
  mstr_standard tap *
  page50_i151
#ISCELL
  mstr_standard tap *
  page50_i152
#ISCELL
  mstr_standard tap *
  page50_i153
#ISCELL
  mstr_standard tap *
  page50_i154
#ISCELL
  mstr_standard tap *
  page50_i155
#ISCELL
  mstr_standard tap *
  page50_i156
#ISCELL
  mstr_standard tap *
  page50_i157
#CELL
  mstr_sconn sconn288_h44441003 *
  page50_i158
#ISCELL
  mstr_standard offpage *
  page50_i159
#ISCELL
  mstr_standard tap *
  page50_i16
#ISCELL
  mstr_standard offpage *
  page50_i160
#ISCELL
  mstr_standard offpage *
  page50_i161
#ISCELL
  mstr_standard offpage *
  page50_i162
#ISCELL
  mstr_standard offpage *
  page50_i163
#ISCELL
  mstr_standard offpage *
  page50_i164
#ISCELL
  mstr_standard offpage *
  page50_i165
#ISCELL
  mstr_standard offpage *
  page50_i166
#ISCELL
  mstr_standard offpage *
  page50_i167
#ISCELL
  mstr_standard offpage *
  page50_i168
#ISCELL
  mstr_standard offpage *
  page50_i169
#ISCELL
  mstr_standard tap *
  page50_i17
#ISCELL
  mstr_standard offpage *
  page50_i170
#ISCELL
  mstr_standard offpage *
  page50_i171
#ISCELL
  mstr_symbols pvpp_def *
  page50_i172
#ISCELL
  mstr_standard offpage *
  page50_i173
#ISCELL
  mstr_standard offpage *
  page50_i174
#ISCELL
  mstr_standard offpage *
  page50_i175
#ISCELL
  mstr_standard offpage *
  page50_i176
#CELL
  dev_discrete cap_a *
  page50_i177
#ISCELL
  mstr_symbols gnd *
  page50_i178
#ISCELL
  mstr_standard offpage *
  page50_i179
#ISCELL
  mstr_standard tap *
  page50_i18
#ISCELL
  mstr_symbols gnd *
  page50_i180
#ISCELL
  mstr_symbols p12v_nvdimm_def *
  page50_i181
#ISCELL
  mstr_standard offpage *
  page50_i19
#ISCELL
  mstr_standard offpage *
  page50_i2
#ISCELL
  mstr_standard tap *
  page50_i20
#ISCELL
  mstr_standard tap *
  page50_i21
#ISCELL
  mstr_standard tap *
  page50_i22
#ISCELL
  mstr_standard tap *
  page50_i23
#ISCELL
  mstr_standard tap *
  page50_i24
#ISCELL
  mstr_standard tap *
  page50_i25
#ISCELL
  mstr_standard tap *
  page50_i26
#ISCELL
  mstr_standard tap *
  page50_i27
#ISCELL
  mstr_standard tap *
  page50_i28
#ISCELL
  mstr_standard tap *
  page50_i29
#ISCELL
  mstr_standard offpage *
  page50_i3
#ISCELL
  mstr_standard tap *
  page50_i30
#ISCELL
  mstr_standard tap *
  page50_i31
#ISCELL
  mstr_standard tap *
  page50_i32
#ISCELL
  mstr_standard tap *
  page50_i33
#ISCELL
  mstr_standard tap *
  page50_i34
#ISCELL
  mstr_standard tap *
  page50_i35
#ISCELL
  mstr_standard tap *
  page50_i36
#ISCELL
  mstr_standard tap *
  page50_i37
#ISCELL
  mstr_standard tap *
  page50_i38
#ISCELL
  mstr_standard tap *
  page50_i39
#ISCELL
  mstr_standard tap *
  page50_i4
#ISCELL
  mstr_standard tap *
  page50_i40
#CELL
  mstr_sconn sconn288_h44441003 *
  page50_i44
#ISCELL
  mstr_symbols gnd *
  page50_i45
#CELL
  mstr_sconn sconn288_h44441003 *
  page50_i46
#ISCELL
  mstr_symbols pvpp_def *
  page50_i47
#ISCELL
  mstr_symbols pvtt_def *
  page50_i48
#ISCELL
  mstr_symbols pvddq_def *
  page50_i49
#ISCELL
  mstr_standard tap *
  page50_i5
#CELL
  mstr_sconn sconn288_h44441003 *
  page50_i50
#ISCELL
  mstr_standard tap *
  page50_i51
#ISCELL
  mstr_standard tap *
  page50_i52
#ISCELL
  mstr_standard tap *
  page50_i53
#ISCELL
  mstr_standard tap *
  page50_i54
#ISCELL
  mstr_standard tap *
  page50_i55
#ISCELL
  mstr_standard tap *
  page50_i56
#ISCELL
  mstr_standard tap *
  page50_i57
#ISCELL
  mstr_standard tap *
  page50_i58
#ISCELL
  mstr_standard tap *
  page50_i59
#ISCELL
  mstr_standard tap *
  page50_i6
#ISCELL
  mstr_standard tap *
  page50_i60
#ISCELL
  mstr_standard tap *
  page50_i61
#ISCELL
  mstr_standard tap *
  page50_i62
#ISCELL
  mstr_standard tap *
  page50_i63
#ISCELL
  mstr_standard tap *
  page50_i64
#ISCELL
  mstr_standard tap *
  page50_i65
#ISCELL
  mstr_standard tap *
  page50_i66
#ISCELL
  mstr_standard tap *
  page50_i67
#ISCELL
  mstr_standard tap *
  page50_i68
#ISCELL
  mstr_standard tap *
  page50_i69
#ISCELL
  mstr_standard tap *
  page50_i7
#ISCELL
  mstr_standard tap *
  page50_i70
#ISCELL
  mstr_standard tap *
  page50_i71
#ISCELL
  mstr_standard tap *
  page50_i72
#ISCELL
  mstr_standard tap *
  page50_i73
#ISCELL
  mstr_standard tap *
  page50_i74
#ISCELL
  mstr_standard tap *
  page50_i75
#ISCELL
  mstr_standard tap *
  page50_i76
#ISCELL
  mstr_standard tap *
  page50_i77
#ISCELL
  mstr_standard tap *
  page50_i78
#ISCELL
  mstr_standard offpage *
  page50_i79
#ISCELL
  mstr_standard tap *
  page50_i8
#ISCELL
  mstr_standard tap *
  page50_i80
#ISCELL
  mstr_standard tap *
  page50_i81
#ISCELL
  mstr_standard tap *
  page50_i82
#ISCELL
  mstr_standard tap *
  page50_i83
#ISCELL
  mstr_standard tap *
  page50_i84
#ISCELL
  mstr_standard tap *
  page50_i85
#ISCELL
  mstr_standard tap *
  page50_i86
#ISCELL
  mstr_standard tap *
  page50_i87
#ISCELL
  mstr_standard tap *
  page50_i88
#ISCELL
  mstr_standard tap *
  page50_i89
#ISCELL
  mstr_standard tap *
  page50_i9
#ISCELL
  mstr_standard tap *
  page50_i90
#ISCELL
  mstr_standard tap *
  page50_i91
#ISCELL
  mstr_standard tap *
  page50_i92
#ISCELL
  mstr_standard tap *
  page50_i93
#ISCELL
  mstr_standard tap *
  page50_i94
#ISCELL
  mstr_standard tap *
  page50_i95
#ISCELL
  mstr_standard tap *
  page50_i96
#ISCELL
  mstr_standard tap *
  page50_i97
#ISCELL
  mstr_standard tap *
  page50_i98
#ISCELL
  mstr_standard tap *
  page50_i99
#ISCELL
  mstr_symbols bom_note *
  *
#ISCELL
  mstr_symbols intel_corp_bpage *
  *
#ISCELL
  mstr_standard offpage *
  page51_i1
#ISCELL
  mstr_standard tap *
  page51_i10
#ISCELL
  mstr_standard tap *
  page51_i100
#ISCELL
  mstr_standard tap *
  page51_i101
#ISCELL
  mstr_standard tap *
  page51_i102
#ISCELL
  mstr_standard tap *
  page51_i103
#ISCELL
  mstr_standard tap *
  page51_i104
#ISCELL
  mstr_standard tap *
  page51_i105
#ISCELL
  mstr_standard tap *
  page51_i106
#ISCELL
  mstr_standard tap *
  page51_i107
#ISCELL
  mstr_standard tap *
  page51_i108
#ISCELL
  mstr_standard tap *
  page51_i109
#ISCELL
  mstr_standard tap *
  page51_i11
#ISCELL
  mstr_standard tap *
  page51_i110
#CELL
  mstr_sconn sconn288_h44441004 *
  page51_i111
#ISCELL
  mstr_standard tap *
  page51_i112
#ISCELL
  mstr_standard tap *
  page51_i113
#ISCELL
  mstr_standard tap *
  page51_i114
#ISCELL
  mstr_standard tap *
  page51_i115
#ISCELL
  mstr_standard tap *
  page51_i116
#ISCELL
  mstr_standard tap *
  page51_i117
#ISCELL
  mstr_standard tap *
  page51_i118
#ISCELL
  mstr_standard tap *
  page51_i119
#ISCELL
  mstr_standard tap *
  page51_i12
#ISCELL
  mstr_standard tap *
  page51_i120
#ISCELL
  mstr_standard tap *
  page51_i121
#ISCELL
  mstr_standard tap *
  page51_i122
#ISCELL
  mstr_standard tap *
  page51_i123
#ISCELL
  mstr_standard tap *
  page51_i124
#ISCELL
  mstr_standard tap *
  page51_i125
#ISCELL
  mstr_standard tap *
  page51_i126
#ISCELL
  mstr_standard tap *
  page51_i127
#ISCELL
  mstr_standard tap *
  page51_i128
#ISCELL
  mstr_standard tap *
  page51_i129
#ISCELL
  mstr_standard tap *
  page51_i13
#ISCELL
  mstr_standard tap *
  page51_i130
#ISCELL
  mstr_standard offpage *
  page51_i131
#ISCELL
  mstr_standard offpage *
  page51_i132
#ISCELL
  mstr_standard tap *
  page51_i133
#ISCELL
  mstr_standard tap *
  page51_i134
#ISCELL
  mstr_standard tap *
  page51_i135
#ISCELL
  mstr_standard offpage *
  page51_i136
#ISCELL
  mstr_standard offpage *
  page51_i137
#ISCELL
  mstr_standard tap *
  page51_i138
#ISCELL
  mstr_standard tap *
  page51_i139
#ISCELL
  mstr_standard tap *
  page51_i14
#ISCELL
  mstr_standard tap *
  page51_i140
#ISCELL
  mstr_standard tap *
  page51_i141
#ISCELL
  mstr_standard tap *
  page51_i142
#ISCELL
  mstr_standard tap *
  page51_i143
#ISCELL
  mstr_standard tap *
  page51_i144
#ISCELL
  mstr_standard tap *
  page51_i145
#ISCELL
  mstr_standard offpage *
  page51_i146
#ISCELL
  mstr_standard offpage *
  page51_i147
#ISCELL
  mstr_standard offpage *
  page51_i148
#ISCELL
  mstr_standard offpage *
  page51_i149
#ISCELL
  mstr_standard tap *
  page51_i15
#ISCELL
  mstr_standard offpage *
  page51_i150
#ISCELL
  mstr_standard offpage *
  page51_i151
#ISCELL
  mstr_standard tap *
  page51_i152
#ISCELL
  mstr_standard tap *
  page51_i153
#ISCELL
  mstr_standard offpage *
  page51_i154
#ISCELL
  mstr_standard offpage *
  page51_i155
#ISCELL
  mstr_standard tap *
  page51_i156
#ISCELL
  mstr_standard tap *
  page51_i157
#ISCELL
  mstr_standard tap *
  page51_i158
#ISCELL
  mstr_standard tap *
  page51_i159
#ISCELL
  mstr_symbols pvddq_def *
  page51_i16
#ISCELL
  mstr_standard tap *
  page51_i160
#ISCELL
  mstr_standard offpage *
  page51_i161
#ISCELL
  mstr_standard offpage *
  page51_i162
#ISCELL
  mstr_standard tap *
  page51_i163
#ISCELL
  mstr_standard tap *
  page51_i164
#ISCELL
  mstr_standard offpage *
  page51_i165
#ISCELL
  mstr_standard tap *
  page51_i166
#CELL
  mstr_sconn sconn288_h44441004 *
  page51_i167
#ISCELL
  mstr_symbols gnd *
  page51_i168
#ISCELL
  mstr_standard offpage *
  page51_i169
#ISCELL
  mstr_symbols pvtt_def *
  page51_i17
#ISCELL
  mstr_standard offpage *
  page51_i171
#ISCELL
  mstr_standard offpage *
  page51_i172
#ISCELL
  mstr_symbols gnd *
  page51_i174
#CELL
  dev_discrete cap_a *
  page51_i175
#ISCELL
  mstr_symbols gnd *
  page51_i176
#ISCELL
  mstr_symbols pvpp_def *
  page51_i177
#ISCELL
  mstr_symbols pvpp_def *
  page51_i178
#ISCELL
  mstr_standard offpage *
  page51_i179
#ISCELL
  mstr_standard tap *
  page51_i183
#ISCELL
  mstr_standard tap *
  page51_i184
#ISCELL
  mstr_symbols p12v_nvdimm_def *
  page51_i185
#ISCELL
  mstr_standard tap *
  page51_i19
#ISCELL
  mstr_standard offpage *
  page51_i2
#ISCELL
  mstr_standard tap *
  page51_i20
#ISCELL
  mstr_standard tap *
  page51_i21
#ISCELL
  mstr_standard tap *
  page51_i22
#ISCELL
  mstr_standard tap *
  page51_i23
#ISCELL
  mstr_standard tap *
  page51_i24
#ISCELL
  mstr_standard tap *
  page51_i25
#ISCELL
  mstr_standard tap *
  page51_i26
#ISCELL
  mstr_standard tap *
  page51_i27
#ISCELL
  mstr_standard tap *
  page51_i28
#ISCELL
  mstr_standard tap *
  page51_i29
#ISCELL
  mstr_standard tap *
  page51_i3
#ISCELL
  mstr_standard tap *
  page51_i30
#ISCELL
  mstr_standard tap *
  page51_i31
#ISCELL
  mstr_standard tap *
  page51_i32
#ISCELL
  mstr_standard tap *
  page51_i33
#ISCELL
  mstr_standard tap *
  page51_i34
#ISCELL
  mstr_standard tap *
  page51_i35
#ISCELL
  mstr_standard tap *
  page51_i36
#ISCELL
  mstr_standard tap *
  page51_i37
#ISCELL
  mstr_standard tap *
  page51_i38
#ISCELL
  mstr_standard tap *
  page51_i39
#ISCELL
  mstr_standard tap *
  page51_i4
#ISCELL
  mstr_standard tap *
  page51_i40
#ISCELL
  mstr_standard tap *
  page51_i41
#CELL
  mstr_sconn sconn288_h44441004 *
  page51_i43
#ISCELL
  mstr_symbols gnd *
  page51_i44
#ISCELL
  mstr_standard offpage *
  page51_i45
#ISCELL
  mstr_standard tap *
  page51_i46
#ISCELL
  mstr_standard tap *
  page51_i47
#ISCELL
  mstr_standard tap *
  page51_i48
#ISCELL
  mstr_standard tap *
  page51_i49
#ISCELL
  mstr_standard tap *
  page51_i5
#ISCELL
  mstr_standard tap *
  page51_i50
#ISCELL
  mstr_standard tap *
  page51_i51
#ISCELL
  mstr_standard tap *
  page51_i52
#ISCELL
  mstr_standard tap *
  page51_i53
#ISCELL
  mstr_standard tap *
  page51_i54
#ISCELL
  mstr_standard tap *
  page51_i55
#ISCELL
  mstr_standard tap *
  page51_i56
#ISCELL
  mstr_standard tap *
  page51_i57
#ISCELL
  mstr_standard tap *
  page51_i58
#ISCELL
  mstr_standard tap *
  page51_i59
#ISCELL
  mstr_standard tap *
  page51_i6
#ISCELL
  mstr_standard tap *
  page51_i60
#ISCELL
  mstr_standard tap *
  page51_i61
#ISCELL
  mstr_standard tap *
  page51_i62
#ISCELL
  mstr_standard tap *
  page51_i63
#ISCELL
  mstr_standard tap *
  page51_i64
#ISCELL
  mstr_standard tap *
  page51_i65
#CELL
  mstr_sconn sconn288_h44441004 *
  page51_i66
#ISCELL
  mstr_standard tap *
  page51_i67
#ISCELL
  mstr_standard tap *
  page51_i68
#ISCELL
  mstr_standard tap *
  page51_i69
#ISCELL
  mstr_standard tap *
  page51_i7
#ISCELL
  mstr_standard tap *
  page51_i70
#ISCELL
  mstr_standard tap *
  page51_i71
#ISCELL
  mstr_standard tap *
  page51_i72
#ISCELL
  mstr_standard tap *
  page51_i73
#ISCELL
  mstr_standard tap *
  page51_i74
#ISCELL
  mstr_standard tap *
  page51_i75
#ISCELL
  mstr_standard tap *
  page51_i76
#ISCELL
  mstr_standard tap *
  page51_i77
#ISCELL
  mstr_standard tap *
  page51_i78
#ISCELL
  mstr_standard tap *
  page51_i79
#ISCELL
  mstr_standard tap *
  page51_i8
#ISCELL
  mstr_standard tap *
  page51_i80
#ISCELL
  mstr_standard tap *
  page51_i81
#ISCELL
  mstr_standard tap *
  page51_i82
#ISCELL
  mstr_standard tap *
  page51_i83
#ISCELL
  mstr_standard tap *
  page51_i84
#ISCELL
  mstr_standard tap *
  page51_i85
#ISCELL
  mstr_standard tap *
  page51_i86
#ISCELL
  mstr_standard tap *
  page51_i87
#ISCELL
  mstr_standard tap *
  page51_i88
#ISCELL
  mstr_standard tap *
  page51_i89
#ISCELL
  mstr_standard tap *
  page51_i9
#ISCELL
  mstr_standard tap *
  page51_i90
#ISCELL
  mstr_standard tap *
  page51_i91
#ISCELL
  mstr_standard tap *
  page51_i92
#ISCELL
  mstr_standard tap *
  page51_i93
#ISCELL
  mstr_standard tap *
  page51_i94
#ISCELL
  mstr_standard tap *
  page51_i95
#ISCELL
  mstr_standard tap *
  page51_i96
#ISCELL
  mstr_standard tap *
  page51_i97
#ISCELL
  mstr_standard tap *
  page51_i98
#ISCELL
  mstr_standard tap *
  page51_i99
#ISCELL
  mstr_symbols bom_note *
  *
#ISCELL
  mstr_symbols intel_corp_bpage *
  *
#ISCELL
  mstr_symbols gnd *
  page52_i1
#ISCELL
  mstr_standard offpage *
  page52_i10
#CELL
  mstr_sconn sconn288_h44441003 *
  page52_i100
#ISCELL
  mstr_standard offpage *
  page52_i101
#ISCELL
  mstr_standard tap *
  page52_i102
#ISCELL
  mstr_standard tap *
  page52_i103
#ISCELL
  mstr_standard tap *
  page52_i104
#ISCELL
  mstr_standard tap *
  page52_i105
#ISCELL
  mstr_standard tap *
  page52_i106
#ISCELL
  mstr_standard tap *
  page52_i107
#ISCELL
  mstr_standard tap *
  page52_i108
#ISCELL
  mstr_standard tap *
  page52_i109
#ISCELL
  mstr_standard offpage *
  page52_i11
#ISCELL
  mstr_standard tap *
  page52_i110
#ISCELL
  mstr_standard tap *
  page52_i111
#ISCELL
  mstr_standard tap *
  page52_i112
#ISCELL
  mstr_standard tap *
  page52_i113
#ISCELL
  mstr_standard tap *
  page52_i114
#ISCELL
  mstr_standard tap *
  page52_i115
#ISCELL
  mstr_standard tap *
  page52_i116
#ISCELL
  mstr_standard tap *
  page52_i117
#ISCELL
  mstr_standard tap *
  page52_i118
#ISCELL
  mstr_standard tap *
  page52_i119
#CELL
  mstr_sconn sconn288_h44441003 *
  page52_i12
#ISCELL
  mstr_standard tap *
  page52_i120
#ISCELL
  mstr_standard tap *
  page52_i121
#ISCELL
  mstr_standard tap *
  page52_i122
#ISCELL
  mstr_standard tap *
  page52_i123
#ISCELL
  mstr_standard tap *
  page52_i124
#ISCELL
  mstr_standard tap *
  page52_i125
#ISCELL
  mstr_standard tap *
  page52_i126
#ISCELL
  mstr_standard tap *
  page52_i127
#ISCELL
  mstr_standard tap *
  page52_i128
#ISCELL
  mstr_standard tap *
  page52_i129
#ISCELL
  mstr_standard offpage *
  page52_i13
#ISCELL
  mstr_standard tap *
  page52_i130
#ISCELL
  mstr_standard tap *
  page52_i131
#ISCELL
  mstr_standard tap *
  page52_i132
#ISCELL
  mstr_standard tap *
  page52_i133
#ISCELL
  mstr_standard tap *
  page52_i134
#ISCELL
  mstr_standard tap *
  page52_i135
#ISCELL
  mstr_standard offpage *
  page52_i136
#ISCELL
  mstr_symbols gnd *
  page52_i137
#CELL
  mstr_sconn sconn288_h44441003 *
  page52_i138
#ISCELL
  mstr_standard offpage *
  page52_i14
#ISCELL
  mstr_standard tap *
  page52_i142
#ISCELL
  mstr_standard tap *
  page52_i143
#ISCELL
  mstr_standard tap *
  page52_i144
#ISCELL
  mstr_standard tap *
  page52_i145
#ISCELL
  mstr_standard tap *
  page52_i146
#ISCELL
  mstr_standard tap *
  page52_i147
#ISCELL
  mstr_standard tap *
  page52_i148
#ISCELL
  mstr_standard tap *
  page52_i149
#ISCELL
  mstr_standard offpage *
  page52_i15
#ISCELL
  mstr_standard tap *
  page52_i150
#ISCELL
  mstr_standard tap *
  page52_i151
#ISCELL
  mstr_standard tap *
  page52_i152
#ISCELL
  mstr_standard tap *
  page52_i153
#ISCELL
  mstr_standard tap *
  page52_i154
#ISCELL
  mstr_standard tap *
  page52_i155
#ISCELL
  mstr_symbols gnd *
  page52_i156
#ISCELL
  mstr_standard tap *
  page52_i157
#ISCELL
  mstr_standard tap *
  page52_i158
#ISCELL
  mstr_standard tap *
  page52_i159
#ISCELL
  mstr_standard offpage *
  page52_i16
#ISCELL
  mstr_standard tap *
  page52_i160
#ISCELL
  mstr_standard tap *
  page52_i161
#ISCELL
  mstr_standard tap *
  page52_i162
#ISCELL
  mstr_standard tap *
  page52_i163
#ISCELL
  mstr_standard tap *
  page52_i164
#ISCELL
  mstr_standard tap *
  page52_i165
#ISCELL
  mstr_standard tap *
  page52_i166
#ISCELL
  mstr_standard tap *
  page52_i167
#ISCELL
  mstr_standard tap *
  page52_i168
#ISCELL
  mstr_standard tap *
  page52_i169
#ISCELL
  mstr_standard offpage *
  page52_i17
#ISCELL
  mstr_standard tap *
  page52_i170
#ISCELL
  mstr_standard tap *
  page52_i171
#ISCELL
  mstr_standard tap *
  page52_i172
#ISCELL
  mstr_standard tap *
  page52_i173
#ISCELL
  mstr_standard tap *
  page52_i174
#ISCELL
  mstr_standard tap *
  page52_i175
#ISCELL
  mstr_standard tap *
  page52_i176
#ISCELL
  mstr_standard tap *
  page52_i177
#ISCELL
  mstr_standard tap *
  page52_i178
#ISCELL
  mstr_standard offpage *
  page52_i179
#ISCELL
  mstr_standard offpage *
  page52_i18
#ISCELL
  mstr_standard offpage *
  page52_i180
#ISCELL
  mstr_symbols p12v_nvdimm_def *
  page52_i181
#ISCELL
  mstr_standard tap *
  page52_i19
#ISCELL
  mstr_symbols gnd *
  page52_i2
#ISCELL
  mstr_standard tap *
  page52_i20
#ISCELL
  mstr_standard tap *
  page52_i21
#ISCELL
  mstr_standard tap *
  page52_i22
#ISCELL
  mstr_standard tap *
  page52_i23
#ISCELL
  mstr_standard tap *
  page52_i24
#ISCELL
  mstr_standard tap *
  page52_i25
#ISCELL
  mstr_standard tap *
  page52_i26
#ISCELL
  mstr_standard tap *
  page52_i27
#ISCELL
  mstr_standard tap *
  page52_i28
#ISCELL
  mstr_standard offpage *
  page52_i29
#CELL
  dev_discrete cap_a *
  page52_i3
#ISCELL
  mstr_standard offpage *
  page52_i30
#ISCELL
  mstr_standard offpage *
  page52_i31
#ISCELL
  mstr_standard tap *
  page52_i32
#ISCELL
  mstr_standard offpage *
  page52_i33
#ISCELL
  mstr_standard offpage *
  page52_i34
#ISCELL
  mstr_standard tap *
  page52_i35
#ISCELL
  mstr_standard tap *
  page52_i36
#ISCELL
  mstr_standard tap *
  page52_i37
#ISCELL
  mstr_standard tap *
  page52_i38
#ISCELL
  mstr_standard tap *
  page52_i39
#ISCELL
  mstr_standard offpage *
  page52_i4
#ISCELL
  mstr_standard tap *
  page52_i40
#ISCELL
  mstr_standard tap *
  page52_i41
#ISCELL
  mstr_standard tap *
  page52_i42
#ISCELL
  mstr_standard tap *
  page52_i43
#ISCELL
  mstr_standard tap *
  page52_i44
#ISCELL
  mstr_standard tap *
  page52_i45
#ISCELL
  mstr_standard tap *
  page52_i46
#ISCELL
  mstr_standard tap *
  page52_i47
#ISCELL
  mstr_standard tap *
  page52_i48
#ISCELL
  mstr_standard tap *
  page52_i49
#ISCELL
  mstr_symbols pvpp_def *
  page52_i5
#ISCELL
  mstr_standard tap *
  page52_i50
#ISCELL
  mstr_standard tap *
  page52_i51
#ISCELL
  mstr_standard tap *
  page52_i52
#ISCELL
  mstr_standard tap *
  page52_i53
#ISCELL
  mstr_standard tap *
  page52_i54
#CELL
  mstr_sconn sconn288_h44441003 *
  page52_i55
#ISCELL
  mstr_standard tap *
  page52_i56
#ISCELL
  mstr_standard tap *
  page52_i57
#ISCELL
  mstr_standard tap *
  page52_i58
#ISCELL
  mstr_standard tap *
  page52_i59
#ISCELL
  mstr_standard offpage *
  page52_i6
#ISCELL
  mstr_standard tap *
  page52_i60
#ISCELL
  mstr_standard tap *
  page52_i61
#ISCELL
  mstr_standard tap *
  page52_i62
#ISCELL
  mstr_standard tap *
  page52_i63
#ISCELL
  mstr_standard tap *
  page52_i64
#ISCELL
  mstr_standard tap *
  page52_i65
#ISCELL
  mstr_standard tap *
  page52_i66
#ISCELL
  mstr_standard tap *
  page52_i67
#ISCELL
  mstr_standard tap *
  page52_i68
#ISCELL
  mstr_standard tap *
  page52_i69
#ISCELL
  mstr_standard offpage *
  page52_i7
#ISCELL
  mstr_standard tap *
  page52_i70
#ISCELL
  mstr_standard tap *
  page52_i71
#ISCELL
  mstr_standard tap *
  page52_i72
#ISCELL
  mstr_standard tap *
  page52_i73
#ISCELL
  mstr_standard tap *
  page52_i74
#ISCELL
  mstr_standard tap *
  page52_i75
#ISCELL
  mstr_standard tap *
  page52_i76
#ISCELL
  mstr_symbols pvddq_def *
  page52_i77
#ISCELL
  mstr_standard tap *
  page52_i78
#ISCELL
  mstr_standard tap *
  page52_i79
#ISCELL
  mstr_standard offpage *
  page52_i8
#ISCELL
  mstr_standard tap *
  page52_i80
#ISCELL
  mstr_standard tap *
  page52_i81
#ISCELL
  mstr_standard tap *
  page52_i82
#ISCELL
  mstr_standard tap *
  page52_i83
#ISCELL
  mstr_standard tap *
  page52_i84
#ISCELL
  mstr_standard tap *
  page52_i85
#ISCELL
  mstr_standard tap *
  page52_i86
#ISCELL
  mstr_standard tap *
  page52_i87
#ISCELL
  mstr_standard tap *
  page52_i88
#ISCELL
  mstr_standard tap *
  page52_i89
#ISCELL
  mstr_standard offpage *
  page52_i9
#ISCELL
  mstr_standard tap *
  page52_i90
#ISCELL
  mstr_standard tap *
  page52_i91
#ISCELL
  mstr_standard tap *
  page52_i92
#ISCELL
  mstr_standard tap *
  page52_i93
#ISCELL
  mstr_standard tap *
  page52_i94
#ISCELL
  mstr_standard tap *
  page52_i95
#ISCELL
  mstr_standard tap *
  page52_i96
#ISCELL
  mstr_standard tap *
  page52_i97
#ISCELL
  mstr_symbols pvtt_def *
  page52_i98
#ISCELL
  mstr_symbols pvpp_def *
  page52_i99
#ISCELL
  mstr_symbols bom_note *
  *
#ISCELL
  mstr_symbols intel_corp_bpage *
  *
#ISCELL
  mstr_standard offpage *
  page53_i1
#ISCELL
  mstr_standard tap *
  page53_i10
#ISCELL
  mstr_standard tap *
  page53_i100
#ISCELL
  mstr_standard tap *
  page53_i101
#ISCELL
  mstr_standard tap *
  page53_i102
#ISCELL
  mstr_standard tap *
  page53_i103
#ISCELL
  mstr_standard tap *
  page53_i104
#ISCELL
  mstr_standard tap *
  page53_i105
#ISCELL
  mstr_standard tap *
  page53_i106
#ISCELL
  mstr_standard tap *
  page53_i107
#ISCELL
  mstr_standard tap *
  page53_i108
#ISCELL
  mstr_standard tap *
  page53_i109
#ISCELL
  mstr_standard tap *
  page53_i11
#ISCELL
  mstr_standard tap *
  page53_i110
#CELL
  mstr_sconn sconn288_h44441004 *
  page53_i111
#ISCELL
  mstr_standard tap *
  page53_i112
#ISCELL
  mstr_standard tap *
  page53_i113
#ISCELL
  mstr_standard tap *
  page53_i114
#ISCELL
  mstr_standard tap *
  page53_i115
#ISCELL
  mstr_standard tap *
  page53_i116
#ISCELL
  mstr_standard tap *
  page53_i117
#ISCELL
  mstr_standard tap *
  page53_i118
#ISCELL
  mstr_standard tap *
  page53_i119
#ISCELL
  mstr_standard tap *
  page53_i12
#ISCELL
  mstr_standard tap *
  page53_i120
#ISCELL
  mstr_standard tap *
  page53_i121
#ISCELL
  mstr_standard tap *
  page53_i122
#ISCELL
  mstr_standard tap *
  page53_i123
#ISCELL
  mstr_standard tap *
  page53_i124
#ISCELL
  mstr_standard tap *
  page53_i125
#ISCELL
  mstr_standard tap *
  page53_i126
#ISCELL
  mstr_standard tap *
  page53_i127
#ISCELL
  mstr_standard tap *
  page53_i128
#ISCELL
  mstr_standard tap *
  page53_i129
#ISCELL
  mstr_standard tap *
  page53_i13
#ISCELL
  mstr_standard tap *
  page53_i130
#ISCELL
  mstr_standard offpage *
  page53_i131
#ISCELL
  mstr_standard offpage *
  page53_i132
#ISCELL
  mstr_standard tap *
  page53_i133
#ISCELL
  mstr_standard tap *
  page53_i134
#ISCELL
  mstr_standard tap *
  page53_i135
#ISCELL
  mstr_standard offpage *
  page53_i136
#ISCELL
  mstr_standard offpage *
  page53_i137
#ISCELL
  mstr_standard tap *
  page53_i138
#ISCELL
  mstr_standard tap *
  page53_i139
#ISCELL
  mstr_standard tap *
  page53_i14
#ISCELL
  mstr_standard tap *
  page53_i140
#ISCELL
  mstr_standard tap *
  page53_i141
#ISCELL
  mstr_standard tap *
  page53_i142
#ISCELL
  mstr_standard tap *
  page53_i143
#ISCELL
  mstr_standard tap *
  page53_i144
#ISCELL
  mstr_standard tap *
  page53_i145
#ISCELL
  mstr_standard offpage *
  page53_i146
#ISCELL
  mstr_standard offpage *
  page53_i147
#ISCELL
  mstr_standard offpage *
  page53_i148
#ISCELL
  mstr_standard offpage *
  page53_i149
#ISCELL
  mstr_standard tap *
  page53_i15
#ISCELL
  mstr_standard offpage *
  page53_i150
#ISCELL
  mstr_standard tap *
  page53_i152
#ISCELL
  mstr_standard tap *
  page53_i153
#ISCELL
  mstr_standard tap *
  page53_i154
#ISCELL
  mstr_standard tap *
  page53_i155
#ISCELL
  mstr_standard offpage *
  page53_i156
#ISCELL
  mstr_standard offpage *
  page53_i157
#ISCELL
  mstr_standard tap *
  page53_i158
#ISCELL
  mstr_standard tap *
  page53_i159
#ISCELL
  mstr_standard tap *
  page53_i160
#ISCELL
  mstr_standard tap *
  page53_i161
#ISCELL
  mstr_standard tap *
  page53_i162
#ISCELL
  mstr_standard tap *
  page53_i163
#ISCELL
  mstr_standard tap *
  page53_i164
#ISCELL
  mstr_standard tap *
  page53_i165
#ISCELL
  mstr_standard offpage *
  page53_i166
#ISCELL
  mstr_standard offpage *
  page53_i167
#ISCELL
  mstr_standard offpage *
  page53_i168
#ISCELL
  mstr_standard offpage *
  page53_i169
#ISCELL
  mstr_symbols pvtt_def *
  page53_i17
#ISCELL
  mstr_standard offpage *
  page53_i170
#CELL
  mstr_sconn sconn288_h44441004 *
  page53_i171
#ISCELL
  mstr_symbols pvddq_def *
  page53_i172
#ISCELL
  mstr_symbols gnd *
  page53_i173
#ISCELL
  mstr_symbols gnd *
  page53_i175
#ISCELL
  mstr_standard offpage *
  page53_i176
#ISCELL
  mstr_standard offpage *
  page53_i177
#CELL
  dev_discrete cap_a *
  page53_i178
#ISCELL
  mstr_symbols gnd *
  page53_i179
#ISCELL
  mstr_symbols pvpp_def *
  page53_i180
#ISCELL
  mstr_symbols pvpp_def *
  page53_i181
#ISCELL
  mstr_standard offpage *
  page53_i182
#ISCELL
  mstr_standard tap *
  page53_i19
#ISCELL
  mstr_symbols p12v_nvdimm_def *
  page53_i195
#ISCELL
  mstr_standard offpage *
  page53_i2
#ISCELL
  mstr_standard tap *
  page53_i20
#ISCELL
  mstr_standard tap *
  page53_i21
#ISCELL
  mstr_standard tap *
  page53_i22
#ISCELL
  mstr_standard tap *
  page53_i23
#ISCELL
  mstr_standard tap *
  page53_i24
#ISCELL
  mstr_standard tap *
  page53_i25
#ISCELL
  mstr_standard tap *
  page53_i26
#ISCELL
  mstr_standard tap *
  page53_i27
#ISCELL
  mstr_standard tap *
  page53_i28
#ISCELL
  mstr_standard tap *
  page53_i29
#ISCELL
  mstr_standard tap *
  page53_i3
#ISCELL
  mstr_standard tap *
  page53_i30
#ISCELL
  mstr_standard tap *
  page53_i31
#ISCELL
  mstr_standard tap *
  page53_i32
#ISCELL
  mstr_standard tap *
  page53_i33
#ISCELL
  mstr_standard tap *
  page53_i34
#ISCELL
  mstr_standard tap *
  page53_i35
#ISCELL
  mstr_standard tap *
  page53_i36
#ISCELL
  mstr_standard tap *
  page53_i37
#ISCELL
  mstr_standard tap *
  page53_i38
#ISCELL
  mstr_standard tap *
  page53_i39
#ISCELL
  mstr_standard tap *
  page53_i4
#ISCELL
  mstr_standard tap *
  page53_i40
#ISCELL
  mstr_standard tap *
  page53_i41
#CELL
  mstr_sconn sconn288_h44441004 *
  page53_i43
#ISCELL
  mstr_symbols gnd *
  page53_i44
#ISCELL
  mstr_standard offpage *
  page53_i45
#ISCELL
  mstr_standard tap *
  page53_i46
#ISCELL
  mstr_standard tap *
  page53_i47
#ISCELL
  mstr_standard tap *
  page53_i48
#ISCELL
  mstr_standard tap *
  page53_i49
#ISCELL
  mstr_standard tap *
  page53_i5
#ISCELL
  mstr_standard tap *
  page53_i50
#ISCELL
  mstr_standard tap *
  page53_i51
#ISCELL
  mstr_standard tap *
  page53_i52
#ISCELL
  mstr_standard tap *
  page53_i53
#ISCELL
  mstr_standard tap *
  page53_i54
#ISCELL
  mstr_standard tap *
  page53_i55
#ISCELL
  mstr_standard tap *
  page53_i56
#ISCELL
  mstr_standard tap *
  page53_i57
#ISCELL
  mstr_standard tap *
  page53_i58
#ISCELL
  mstr_standard tap *
  page53_i59
#ISCELL
  mstr_standard tap *
  page53_i6
#ISCELL
  mstr_standard tap *
  page53_i60
#ISCELL
  mstr_standard tap *
  page53_i61
#ISCELL
  mstr_standard tap *
  page53_i62
#ISCELL
  mstr_standard tap *
  page53_i63
#ISCELL
  mstr_standard tap *
  page53_i64
#ISCELL
  mstr_standard tap *
  page53_i65
#CELL
  mstr_sconn sconn288_h44441004 *
  page53_i66
#ISCELL
  mstr_standard tap *
  page53_i67
#ISCELL
  mstr_standard tap *
  page53_i68
#ISCELL
  mstr_standard tap *
  page53_i69
#ISCELL
  mstr_standard tap *
  page53_i7
#ISCELL
  mstr_standard tap *
  page53_i70
#ISCELL
  mstr_standard tap *
  page53_i71
#ISCELL
  mstr_standard tap *
  page53_i72
#ISCELL
  mstr_standard tap *
  page53_i73
#ISCELL
  mstr_standard tap *
  page53_i74
#ISCELL
  mstr_standard tap *
  page53_i75
#ISCELL
  mstr_standard tap *
  page53_i76
#ISCELL
  mstr_standard tap *
  page53_i77
#ISCELL
  mstr_standard tap *
  page53_i78
#ISCELL
  mstr_standard tap *
  page53_i79
#ISCELL
  mstr_standard tap *
  page53_i8
#ISCELL
  mstr_standard tap *
  page53_i80
#ISCELL
  mstr_standard tap *
  page53_i81
#ISCELL
  mstr_standard tap *
  page53_i82
#ISCELL
  mstr_standard tap *
  page53_i83
#ISCELL
  mstr_standard tap *
  page53_i84
#ISCELL
  mstr_standard tap *
  page53_i85
#ISCELL
  mstr_standard tap *
  page53_i86
#ISCELL
  mstr_standard tap *
  page53_i87
#ISCELL
  mstr_standard tap *
  page53_i88
#ISCELL
  mstr_standard tap *
  page53_i89
#ISCELL
  mstr_standard tap *
  page53_i9
#ISCELL
  mstr_standard tap *
  page53_i90
#ISCELL
  mstr_standard tap *
  page53_i91
#ISCELL
  mstr_standard tap *
  page53_i92
#ISCELL
  mstr_standard tap *
  page53_i93
#ISCELL
  mstr_standard tap *
  page53_i94
#ISCELL
  mstr_standard tap *
  page53_i95
#ISCELL
  mstr_standard tap *
  page53_i96
#ISCELL
  mstr_standard tap *
  page53_i97
#ISCELL
  mstr_standard tap *
  page53_i98
#ISCELL
  mstr_standard tap *
  page53_i99
#ISCELL
  mstr_symbols bom_note *
  *
#ISCELL
  mstr_symbols intel_corp_bpage *
  *
#ISCELL
  mstr_standard offpage *
  page54_i1
#ISCELL
  mstr_standard tap *
  page54_i10
#ISCELL
  mstr_standard tap *
  page54_i100
#ISCELL
  mstr_standard tap *
  page54_i101
#ISCELL
  mstr_standard tap *
  page54_i102
#ISCELL
  mstr_standard tap *
  page54_i103
#ISCELL
  mstr_standard tap *
  page54_i104
#ISCELL
  mstr_standard tap *
  page54_i105
#ISCELL
  mstr_standard tap *
  page54_i106
#ISCELL
  mstr_standard tap *
  page54_i107
#ISCELL
  mstr_standard tap *
  page54_i108
#ISCELL
  mstr_standard tap *
  page54_i109
#ISCELL
  mstr_standard tap *
  page54_i11
#ISCELL
  mstr_standard tap *
  page54_i110
#CELL
  mstr_sconn sconn288_h44441003 *
  page54_i111
#ISCELL
  mstr_standard tap *
  page54_i112
#ISCELL
  mstr_standard tap *
  page54_i113
#ISCELL
  mstr_standard tap *
  page54_i114
#ISCELL
  mstr_standard tap *
  page54_i115
#ISCELL
  mstr_standard tap *
  page54_i116
#ISCELL
  mstr_standard tap *
  page54_i117
#ISCELL
  mstr_standard tap *
  page54_i118
#ISCELL
  mstr_standard tap *
  page54_i119
#ISCELL
  mstr_standard tap *
  page54_i12
#ISCELL
  mstr_standard tap *
  page54_i120
#ISCELL
  mstr_standard tap *
  page54_i121
#ISCELL
  mstr_standard tap *
  page54_i122
#ISCELL
  mstr_standard tap *
  page54_i123
#ISCELL
  mstr_standard tap *
  page54_i124
#ISCELL
  mstr_standard tap *
  page54_i125
#ISCELL
  mstr_standard tap *
  page54_i126
#ISCELL
  mstr_standard tap *
  page54_i127
#ISCELL
  mstr_standard tap *
  page54_i128
#ISCELL
  mstr_standard tap *
  page54_i129
#ISCELL
  mstr_standard tap *
  page54_i13
#ISCELL
  mstr_standard tap *
  page54_i130
#ISCELL
  mstr_standard offpage *
  page54_i131
#ISCELL
  mstr_standard offpage *
  page54_i132
#ISCELL
  mstr_standard tap *
  page54_i133
#ISCELL
  mstr_standard tap *
  page54_i134
#ISCELL
  mstr_standard tap *
  page54_i135
#ISCELL
  mstr_standard offpage *
  page54_i136
#ISCELL
  mstr_standard offpage *
  page54_i137
#ISCELL
  mstr_standard tap *
  page54_i138
#ISCELL
  mstr_standard tap *
  page54_i139
#ISCELL
  mstr_standard tap *
  page54_i14
#ISCELL
  mstr_standard tap *
  page54_i140
#ISCELL
  mstr_standard tap *
  page54_i141
#ISCELL
  mstr_standard tap *
  page54_i142
#ISCELL
  mstr_standard tap *
  page54_i143
#ISCELL
  mstr_standard tap *
  page54_i144
#ISCELL
  mstr_standard tap *
  page54_i145
#ISCELL
  mstr_standard offpage *
  page54_i146
#ISCELL
  mstr_standard offpage *
  page54_i147
#ISCELL
  mstr_standard offpage *
  page54_i148
#ISCELL
  mstr_standard offpage *
  page54_i149
#ISCELL
  mstr_standard tap *
  page54_i15
#ISCELL
  mstr_standard offpage *
  page54_i150
#ISCELL
  mstr_standard tap *
  page54_i152
#ISCELL
  mstr_standard tap *
  page54_i153
#ISCELL
  mstr_standard tap *
  page54_i154
#ISCELL
  mstr_standard tap *
  page54_i155
#ISCELL
  mstr_standard offpage *
  page54_i156
#ISCELL
  mstr_standard offpage *
  page54_i157
#ISCELL
  mstr_standard tap *
  page54_i158
#ISCELL
  mstr_standard tap *
  page54_i159
#ISCELL
  mstr_symbols pvddq_def *
  page54_i16
#ISCELL
  mstr_standard tap *
  page54_i160
#ISCELL
  mstr_standard tap *
  page54_i161
#ISCELL
  mstr_standard offpage *
  page54_i163
#ISCELL
  mstr_standard offpage *
  page54_i164
#ISCELL
  mstr_standard tap *
  page54_i165
#ISCELL
  mstr_standard tap *
  page54_i166
#ISCELL
  mstr_standard tap *
  page54_i167
#ISCELL
  mstr_standard tap *
  page54_i168
#ISCELL
  mstr_standard offpage *
  page54_i169
#ISCELL
  mstr_symbols pvtt_def *
  page54_i17
#CELL
  mstr_sconn sconn288_h44441003 *
  page54_i170
#ISCELL
  mstr_symbols gnd *
  page54_i171
#ISCELL
  mstr_standard offpage *
  page54_i172
#ISCELL
  mstr_standard offpage *
  page54_i173
#ISCELL
  mstr_standard offpage *
  page54_i174
#ISCELL
  mstr_standard offpage *
  page54_i175
#ISCELL
  mstr_symbols gnd *
  page54_i178
#CELL
  dev_discrete cap_a *
  page54_i179
#ISCELL
  mstr_symbols pvpp_def *
  page54_i180
#ISCELL
  mstr_symbols pvpp_def *
  page54_i181
#ISCELL
  mstr_standard offpage *
  page54_i182
#ISCELL
  mstr_symbols gnd *
  page54_i186
#ISCELL
  mstr_symbols p12v_nvdimm_def *
  page54_i187
#ISCELL
  mstr_standard tap *
  page54_i19
#ISCELL
  mstr_standard offpage *
  page54_i2
#ISCELL
  mstr_standard tap *
  page54_i20
#ISCELL
  mstr_standard tap *
  page54_i21
#ISCELL
  mstr_standard tap *
  page54_i22
#ISCELL
  mstr_standard tap *
  page54_i23
#ISCELL
  mstr_standard tap *
  page54_i24
#ISCELL
  mstr_standard tap *
  page54_i25
#ISCELL
  mstr_standard tap *
  page54_i26
#ISCELL
  mstr_standard tap *
  page54_i27
#ISCELL
  mstr_standard tap *
  page54_i28
#ISCELL
  mstr_standard tap *
  page54_i29
#ISCELL
  mstr_standard tap *
  page54_i3
#ISCELL
  mstr_standard tap *
  page54_i30
#ISCELL
  mstr_standard tap *
  page54_i31
#ISCELL
  mstr_standard tap *
  page54_i32
#ISCELL
  mstr_standard tap *
  page54_i33
#ISCELL
  mstr_standard tap *
  page54_i34
#ISCELL
  mstr_standard tap *
  page54_i35
#ISCELL
  mstr_standard tap *
  page54_i36
#ISCELL
  mstr_standard tap *
  page54_i37
#ISCELL
  mstr_standard tap *
  page54_i38
#ISCELL
  mstr_standard tap *
  page54_i39
#ISCELL
  mstr_standard tap *
  page54_i4
#ISCELL
  mstr_standard tap *
  page54_i40
#ISCELL
  mstr_standard tap *
  page54_i41
#CELL
  mstr_sconn sconn288_h44441003 *
  page54_i43
#ISCELL
  mstr_symbols gnd *
  page54_i44
#ISCELL
  mstr_standard offpage *
  page54_i45
#ISCELL
  mstr_standard tap *
  page54_i46
#ISCELL
  mstr_standard tap *
  page54_i47
#ISCELL
  mstr_standard tap *
  page54_i48
#ISCELL
  mstr_standard tap *
  page54_i49
#ISCELL
  mstr_standard tap *
  page54_i5
#ISCELL
  mstr_standard tap *
  page54_i50
#ISCELL
  mstr_standard tap *
  page54_i51
#ISCELL
  mstr_standard tap *
  page54_i52
#ISCELL
  mstr_standard tap *
  page54_i53
#ISCELL
  mstr_standard tap *
  page54_i54
#ISCELL
  mstr_standard tap *
  page54_i55
#ISCELL
  mstr_standard tap *
  page54_i56
#ISCELL
  mstr_standard tap *
  page54_i57
#ISCELL
  mstr_standard tap *
  page54_i58
#ISCELL
  mstr_standard tap *
  page54_i59
#ISCELL
  mstr_standard tap *
  page54_i6
#ISCELL
  mstr_standard tap *
  page54_i60
#ISCELL
  mstr_standard tap *
  page54_i61
#ISCELL
  mstr_standard tap *
  page54_i62
#ISCELL
  mstr_standard tap *
  page54_i63
#ISCELL
  mstr_standard tap *
  page54_i64
#ISCELL
  mstr_standard tap *
  page54_i65
#CELL
  mstr_sconn sconn288_h44441003 *
  page54_i66
#ISCELL
  mstr_standard tap *
  page54_i67
#ISCELL
  mstr_standard tap *
  page54_i68
#ISCELL
  mstr_standard tap *
  page54_i69
#ISCELL
  mstr_standard tap *
  page54_i7
#ISCELL
  mstr_standard tap *
  page54_i70
#ISCELL
  mstr_standard tap *
  page54_i71
#ISCELL
  mstr_standard tap *
  page54_i72
#ISCELL
  mstr_standard tap *
  page54_i73
#ISCELL
  mstr_standard tap *
  page54_i74
#ISCELL
  mstr_standard tap *
  page54_i75
#ISCELL
  mstr_standard tap *
  page54_i76
#ISCELL
  mstr_standard tap *
  page54_i77
#ISCELL
  mstr_standard tap *
  page54_i78
#ISCELL
  mstr_standard tap *
  page54_i79
#ISCELL
  mstr_standard tap *
  page54_i8
#ISCELL
  mstr_standard tap *
  page54_i80
#ISCELL
  mstr_standard tap *
  page54_i81
#ISCELL
  mstr_standard tap *
  page54_i82
#ISCELL
  mstr_standard tap *
  page54_i83
#ISCELL
  mstr_standard tap *
  page54_i84
#ISCELL
  mstr_standard tap *
  page54_i85
#ISCELL
  mstr_standard tap *
  page54_i86
#ISCELL
  mstr_standard tap *
  page54_i87
#ISCELL
  mstr_standard tap *
  page54_i88
#ISCELL
  mstr_standard tap *
  page54_i89
#ISCELL
  mstr_standard tap *
  page54_i9
#ISCELL
  mstr_standard tap *
  page54_i90
#ISCELL
  mstr_standard tap *
  page54_i91
#ISCELL
  mstr_standard tap *
  page54_i92
#ISCELL
  mstr_standard tap *
  page54_i93
#ISCELL
  mstr_standard tap *
  page54_i94
#ISCELL
  mstr_standard tap *
  page54_i95
#ISCELL
  mstr_standard tap *
  page54_i96
#ISCELL
  mstr_standard tap *
  page54_i97
#ISCELL
  mstr_standard tap *
  page54_i98
#ISCELL
  mstr_standard tap *
  page54_i99
#ISCELL
  mstr_misc prelim *
  *
#ISCELL
  mstr_symbols bom_note *
  *
#ISCELL
  mstr_symbols cad_note *
  *
#ISCELL
  mstr_symbols design_note *
  *
#ISCELL
  mstr_symbols intel_corp_bpage *
  *
#ISCELL
  mstr_standard offpage *
  page55_i10
#ISCELL
  mstr_standard offpage *
  page55_i100
#ISCELL
  mstr_standard offpage *
  page55_i101
#ISCELL
  mstr_standard offpage *
  page55_i102
#ISCELL
  mstr_standard offpage *
  page55_i103
#ISCELL
  mstr_standard offpage *
  page55_i108
#ISCELL
  mstr_standard offpage *
  page55_i109
#CELL
  mstr_discrete res *
  page55_i115
#CELL
  mstr_discrete res *
  page55_i116
#CELL
  mstr_discrete res *
  page55_i117
#CELL
  mstr_discrete res *
  page55_i118
#CELL
  mstr_discrete res *
  page55_i119
#ISCELL
  mstr_symbols gnd *
  page55_i121
#ISCELL
  mstr_symbols gnd *
  page55_i122
#CELL
  mstr_discrete res *
  page55_i123
#CELL
  mstr_discrete res *
  page55_i124
#CELL
  mstr_discrete res *
  page55_i125
#CELL
  mstr_discrete res *
  page55_i126
#ISCELL
  mstr_standard offpage *
  page55_i13
#ISCELL
  mstr_standard offpage *
  page55_i132
#ISCELL
  mstr_standard offpage *
  page55_i133
#ISCELL
  mstr_standard offpage *
  page55_i134
#ISCELL
  mstr_standard offpage *
  page55_i135
#ISCELL
  mstr_standard offpage *
  page55_i138
#ISCELL
  mstr_standard offpage *
  page55_i139
#ISCELL
  mstr_standard offpage *
  page55_i14
#CELL
  mstr_discrete res *
  page55_i140
#ISCELL
  mstr_standard offpage *
  page55_i145
#ISCELL
  mstr_standard offpage *
  page55_i146
#ISCELL
  mstr_standard offpage *
  page55_i148
#ISCELL
  mstr_standard offpage *
  page55_i149
#ISCELL
  mstr_standard offpage *
  page55_i15
#ISCELL
  mstr_standard offpage *
  page55_i150
#ISCELL
  mstr_standard offpage *
  page55_i151
#CELL
  chpset_lib socket_p_mech_a *
  page55_i152
#CELL
  chpset_lib socket_p_mech_a *
  page55_i153
#CELL
  mstr_discrete res *
  page55_i155
#CELL
  mstr_discrete res *
  page55_i156
#CELL
  mstr_discrete res *
  page55_i157
#CELL
  mstr_discrete res *
  page55_i158
#CELL
  mstr_discrete res *
  page55_i159
#ISCELL
  mstr_standard offpage *
  page55_i16
#CELL
  mstr_discrete res *
  page55_i160
#CELL
  mstr_discrete res *
  page55_i161
#ISCELL
  mstr_symbols p3v3_stby *
  page55_i162
#ISCELL
  mstr_standard offpage *
  page55_i163
#ISCELL
  mstr_standard offpage *
  page55_i164
#ISCELL
  mstr_standard offpage *
  page55_i165
#ISCELL
  mstr_standard offpage *
  page55_i166
#ISCELL
  mstr_standard offpage *
  page55_i167
#ISCELL
  mstr_symbols p3v3_stby *
  page55_i169
#ISCELL
  mstr_standard offpage *
  page55_i17
#CELL
  mstr_discrete res *
  page55_i170
#CELL
  chpset_lib skx_ext_b *
  page55_i172
#ISCELL
  mstr_standard offpage *
  page55_i173
#ISCELL
  mstr_standard offpage *
  page55_i174
#ISCELL
  mstr_standard offpage *
  page55_i175
#ISCELL
  mstr_standard offpage *
  page55_i178
#ISCELL
  mstr_standard offpage *
  page55_i179
#ISCELL
  mstr_standard offpage *
  page55_i18
#ISCELL
  mstr_standard offpage *
  page55_i180
#CELL
  mstr_discrete res *
  page55_i181
#ISCELL
  mstr_standard offpage *
  page55_i182
#ISCELL
  mstr_standard offpage *
  page55_i183
#ISCELL
  mstr_standard offpage *
  page55_i184
#ISCELL
  mstr_standard offpage *
  page55_i185
#ISCELL
  mstr_standard offpage *
  page55_i186
#ISCELL
  mstr_standard offpage *
  page55_i187
#ISCELL
  mstr_standard offpage *
  page55_i188
#ISCELL
  mstr_standard offpage *
  page55_i189
#CELL
  mstr_discrete res *
  page55_i19
#ISCELL
  mstr_standard offpage *
  page55_i190
#ISCELL
  mstr_standard offpage *
  page55_i191
#ISCELL
  mstr_standard offpage *
  page55_i2
#CELL
  mstr_discrete res *
  page55_i21
#ISCELL
  mstr_symbols pvccio_cpu1 *
  page55_i22
#ISCELL
  mstr_standard offpage *
  page55_i23
#CELL
  mstr_discrete res *
  page55_i24
#CELL
  mstr_discrete res *
  page55_i25
#CELL
  mstr_discrete res *
  page55_i26
#CELL
  mstr_discrete res *
  page55_i27
#CELL
  mstr_discrete res *
  page55_i28
#CELL
  mstr_discrete res *
  page55_i29
#ISCELL
  mstr_standard offpage *
  page55_i3
#ISCELL
  mstr_standard offpage *
  page55_i30
#ISCELL
  mstr_standard offpage *
  page55_i31
#ISCELL
  mstr_standard offpage *
  page55_i32
#ISCELL
  mstr_standard offpage *
  page55_i33
#ISCELL
  mstr_standard offpage *
  page55_i34
#ISCELL
  mstr_standard offpage *
  page55_i36
#ISCELL
  mstr_standard offpage *
  page55_i37
#ISCELL
  mstr_standard offpage *
  page55_i38
#ISCELL
  mstr_standard offpage *
  page55_i39
#CELL
  mstr_discrete res *
  page55_i4
#ISCELL
  mstr_standard offpage *
  page55_i40
#ISCELL
  mstr_standard offpage *
  page55_i41
#ISCELL
  mstr_standard offpage *
  page55_i42
#ISCELL
  mstr_standard offpage *
  page55_i43
#ISCELL
  mstr_standard offpage *
  page55_i44
#ISCELL
  mstr_standard offpage *
  page55_i57
#ISCELL
  mstr_standard offpage *
  page55_i58
#ISCELL
  mstr_standard offpage *
  page55_i59
#ISCELL
  mstr_symbols pvccio_cpu1 *
  page55_i6
#ISCELL
  mstr_standard offpage *
  page55_i60
#ISCELL
  mstr_standard offpage *
  page55_i61
#ISCELL
  mstr_standard offpage *
  page55_i62
#ISCELL
  mstr_standard offpage *
  page55_i63
#ISCELL
  mstr_standard offpage *
  page55_i64
#ISCELL
  mstr_standard offpage *
  page55_i65
#ISCELL
  mstr_standard offpage *
  page55_i67
#ISCELL
  mstr_standard offpage *
  page55_i68
#CELL
  mstr_discrete res *
  page55_i7
#ISCELL
  mstr_standard offpage *
  page55_i70
#ISCELL
  mstr_standard offpage *
  page55_i73
#ISCELL
  mstr_standard offpage *
  page55_i8
#ISCELL
  mstr_standard offpage *
  page55_i80
#ISCELL
  mstr_standard offpage *
  page55_i81
#ISCELL
  mstr_standard offpage *
  page55_i82
#ISCELL
  mstr_standard offpage *
  page55_i83
#ISCELL
  mstr_misc prelim *
  *
#ISCELL
  mstr_symbols design_note *
  *
#ISCELL
  mstr_symbols intel_corp_bpage *
  *
#ISCELL
  mstr_standard offpage *
  page56_i161
#ISCELL
  mstr_standard offpage *
  page56_i164
#CELL
  chpset_lib skx_ext_b *
  page56_i169
#ISCELL
  mstr_symbols gnd *
  page56_i171
#CELL
  mstr_discrete res *
  page56_i173
#CELL
  mstr_discrete res *
  page56_i174
#ISCELL
  mstr_standard offpage *
  page56_i178
#ISCELL
  mstr_standard offpage *
  page56_i179
#ISCELL
  mstr_standard offpage *
  page56_i180
#ISCELL
  mstr_standard offpage *
  page56_i181
#ISCELL
  mstr_standard offpage *
  page56_i182
#ISCELL
  mstr_standard offpage *
  page56_i183
#ISCELL
  mstr_symbols vcc_core *
  page56_i185
#ISCELL
  mstr_standard offpage *
  page56_i187
#ISCELL
  mstr_symbols vcc_core *
  page56_i188
#ISCELL
  mstr_standard offpage *
  page56_i189
#ISCELL
  mstr_standard offpage *
  page56_i190
#ISCELL
  mstr_misc prelim *
  *
#ISCELL
  mstr_symbols design_note *
  *
#ISCELL
  mstr_symbols intel_corp_bpage *
  *
#ISCELL
  mstr_standard offpage *
  page57_i1
#ISCELL
  mstr_standard tap *
  page57_i10
#ISCELL
  mstr_standard tap *
  page57_i100
#ISCELL
  mstr_standard tap *
  page57_i101
#ISCELL
  mstr_standard tap *
  page57_i102
#ISCELL
  mstr_standard tap *
  page57_i103
#ISCELL
  mstr_standard tap *
  page57_i104
#ISCELL
  mstr_standard tap *
  page57_i105
#ISCELL
  mstr_standard tap *
  page57_i106
#ISCELL
  mstr_standard tap *
  page57_i107
#ISCELL
  mstr_standard tap *
  page57_i108
#ISCELL
  mstr_standard tap *
  page57_i109
#ISCELL
  mstr_standard tap *
  page57_i11
#ISCELL
  mstr_standard tap *
  page57_i110
#ISCELL
  mstr_standard tap *
  page57_i111
#ISCELL
  mstr_standard tap *
  page57_i112
#ISCELL
  mstr_standard tap *
  page57_i113
#ISCELL
  mstr_standard tap *
  page57_i114
#ISCELL
  mstr_standard tap *
  page57_i115
#ISCELL
  mstr_standard tap *
  page57_i116
#ISCELL
  mstr_standard tap *
  page57_i117
#ISCELL
  mstr_standard tap *
  page57_i118
#ISCELL
  mstr_standard tap *
  page57_i119
#ISCELL
  mstr_standard tap *
  page57_i12
#ISCELL
  mstr_standard tap *
  page57_i120
#ISCELL
  mstr_standard tap *
  page57_i121
#ISCELL
  mstr_standard tap *
  page57_i122
#ISCELL
  mstr_standard tap *
  page57_i123
#ISCELL
  mstr_standard tap *
  page57_i124
#ISCELL
  mstr_standard tap *
  page57_i125
#ISCELL
  mstr_standard tap *
  page57_i126
#ISCELL
  mstr_standard tap *
  page57_i127
#ISCELL
  mstr_standard tap *
  page57_i128
#ISCELL
  mstr_standard tap *
  page57_i129
#ISCELL
  mstr_standard tap *
  page57_i13
#ISCELL
  mstr_standard tap *
  page57_i130
#ISCELL
  mstr_standard tap *
  page57_i131
#ISCELL
  mstr_standard tap *
  page57_i132
#ISCELL
  mstr_standard tap *
  page57_i133
#ISCELL
  mstr_standard tap *
  page57_i134
#ISCELL
  mstr_standard tap *
  page57_i135
#ISCELL
  mstr_standard tap *
  page57_i136
#ISCELL
  mstr_standard tap *
  page57_i137
#ISCELL
  mstr_standard tap *
  page57_i138
#ISCELL
  mstr_standard tap *
  page57_i139
#ISCELL
  mstr_standard tap *
  page57_i14
#ISCELL
  mstr_standard tap *
  page57_i140
#ISCELL
  mstr_standard tap *
  page57_i141
#ISCELL
  mstr_standard tap *
  page57_i142
#ISCELL
  mstr_standard tap *
  page57_i143
#ISCELL
  mstr_standard tap *
  page57_i144
#ISCELL
  mstr_standard tap *
  page57_i145
#ISCELL
  mstr_standard tap *
  page57_i146
#ISCELL
  mstr_standard offpage *
  page57_i147
#ISCELL
  mstr_standard offpage *
  page57_i148
#ISCELL
  mstr_standard offpage *
  page57_i149
#ISCELL
  mstr_standard tap *
  page57_i15
#ISCELL
  mstr_standard offpage *
  page57_i150
#ISCELL
  mstr_standard offpage *
  page57_i151
#ISCELL
  mstr_standard offpage *
  page57_i152
#ISCELL
  mstr_standard offpage *
  page57_i153
#ISCELL
  mstr_standard offpage *
  page57_i154
#ISCELL
  mstr_standard offpage *
  page57_i155
#ISCELL
  mstr_standard offpage *
  page57_i156
#ISCELL
  mstr_standard tap *
  page57_i157
#ISCELL
  mstr_standard tap *
  page57_i158
#ISCELL
  mstr_standard tap *
  page57_i159
#ISCELL
  mstr_standard tap *
  page57_i16
#ISCELL
  mstr_standard tap *
  page57_i160
#ISCELL
  mstr_standard tap *
  page57_i161
#ISCELL
  mstr_standard tap *
  page57_i162
#ISCELL
  mstr_standard tap *
  page57_i163
#ISCELL
  mstr_standard tap *
  page57_i164
#ISCELL
  mstr_standard tap *
  page57_i165
#ISCELL
  mstr_standard tap *
  page57_i166
#ISCELL
  mstr_standard tap *
  page57_i167
#ISCELL
  mstr_standard tap *
  page57_i168
#ISCELL
  mstr_standard tap *
  page57_i169
#ISCELL
  mstr_standard tap *
  page57_i17
#ISCELL
  mstr_standard tap *
  page57_i170
#ISCELL
  mstr_standard offpage *
  page57_i171
#CELL
  chpset_lib skx_ext_b *
  page57_i172
#ISCELL
  mstr_standard tap *
  page57_i18
#ISCELL
  mstr_standard tap *
  page57_i19
#ISCELL
  mstr_standard offpage *
  page57_i2
#ISCELL
  mstr_standard tap *
  page57_i20
#ISCELL
  mstr_standard tap *
  page57_i21
#ISCELL
  mstr_standard tap *
  page57_i22
#ISCELL
  mstr_standard tap *
  page57_i23
#ISCELL
  mstr_standard tap *
  page57_i24
#ISCELL
  mstr_standard tap *
  page57_i25
#ISCELL
  mstr_standard tap *
  page57_i26
#ISCELL
  mstr_standard tap *
  page57_i27
#ISCELL
  mstr_standard tap *
  page57_i28
#ISCELL
  mstr_standard tap *
  page57_i29
#ISCELL
  mstr_standard offpage *
  page57_i3
#ISCELL
  mstr_standard tap *
  page57_i31
#ISCELL
  mstr_standard tap *
  page57_i32
#ISCELL
  mstr_standard tap *
  page57_i33
#ISCELL
  mstr_standard tap *
  page57_i34
#ISCELL
  mstr_standard tap *
  page57_i35
#ISCELL
  mstr_standard tap *
  page57_i36
#ISCELL
  mstr_standard tap *
  page57_i37
#ISCELL
  mstr_standard tap *
  page57_i38
#ISCELL
  mstr_standard tap *
  page57_i39
#ISCELL
  mstr_standard offpage *
  page57_i4
#ISCELL
  mstr_standard tap *
  page57_i40
#ISCELL
  mstr_standard tap *
  page57_i41
#ISCELL
  mstr_standard tap *
  page57_i42
#ISCELL
  mstr_standard tap *
  page57_i43
#ISCELL
  mstr_standard tap *
  page57_i44
#ISCELL
  mstr_standard tap *
  page57_i45
#ISCELL
  mstr_standard tap *
  page57_i46
#ISCELL
  mstr_standard tap *
  page57_i47
#ISCELL
  mstr_standard tap *
  page57_i48
#ISCELL
  mstr_standard tap *
  page57_i49
#ISCELL
  mstr_standard tap *
  page57_i5
#ISCELL
  mstr_standard tap *
  page57_i50
#ISCELL
  mstr_standard tap *
  page57_i51
#ISCELL
  mstr_standard tap *
  page57_i52
#ISCELL
  mstr_standard tap *
  page57_i53
#ISCELL
  mstr_standard tap *
  page57_i54
#ISCELL
  mstr_standard tap *
  page57_i55
#ISCELL
  mstr_standard tap *
  page57_i56
#ISCELL
  mstr_standard tap *
  page57_i57
#ISCELL
  mstr_standard tap *
  page57_i58
#ISCELL
  mstr_standard tap *
  page57_i59
#ISCELL
  mstr_standard tap *
  page57_i6
#ISCELL
  mstr_standard tap *
  page57_i60
#ISCELL
  mstr_standard tap *
  page57_i61
#ISCELL
  mstr_standard tap *
  page57_i62
#ISCELL
  mstr_standard tap *
  page57_i63
#ISCELL
  mstr_standard tap *
  page57_i64
#ISCELL
  mstr_standard tap *
  page57_i65
#ISCELL
  mstr_standard tap *
  page57_i66
#ISCELL
  mstr_standard tap *
  page57_i67
#ISCELL
  mstr_standard tap *
  page57_i68
#ISCELL
  mstr_standard tap *
  page57_i69
#ISCELL
  mstr_standard tap *
  page57_i7
#ISCELL
  mstr_standard tap *
  page57_i70
#ISCELL
  mstr_standard tap *
  page57_i71
#ISCELL
  mstr_standard offpage *
  page57_i72
#ISCELL
  mstr_standard tap *
  page57_i73
#ISCELL
  mstr_standard tap *
  page57_i74
#ISCELL
  mstr_standard tap *
  page57_i75
#ISCELL
  mstr_standard tap *
  page57_i76
#ISCELL
  mstr_standard tap *
  page57_i77
#ISCELL
  mstr_standard tap *
  page57_i78
#ISCELL
  mstr_standard tap *
  page57_i79
#ISCELL
  mstr_standard tap *
  page57_i8
#ISCELL
  mstr_standard tap *
  page57_i80
#ISCELL
  mstr_standard tap *
  page57_i81
#ISCELL
  mstr_standard tap *
  page57_i82
#ISCELL
  mstr_standard tap *
  page57_i83
#ISCELL
  mstr_standard tap *
  page57_i84
#ISCELL
  mstr_standard tap *
  page57_i85
#ISCELL
  mstr_standard tap *
  page57_i86
#ISCELL
  mstr_standard tap *
  page57_i87
#ISCELL
  mstr_standard tap *
  page57_i88
#ISCELL
  mstr_standard tap *
  page57_i89
#ISCELL
  mstr_standard tap *
  page57_i9
#ISCELL
  mstr_standard tap *
  page57_i90
#ISCELL
  mstr_standard tap *
  page57_i91
#ISCELL
  mstr_standard tap *
  page57_i92
#ISCELL
  mstr_standard tap *
  page57_i93
#ISCELL
  mstr_standard tap *
  page57_i94
#ISCELL
  mstr_standard tap *
  page57_i95
#ISCELL
  mstr_standard tap *
  page57_i96
#ISCELL
  mstr_standard tap *
  page57_i97
#ISCELL
  mstr_standard tap *
  page57_i98
#ISCELL
  mstr_standard tap *
  page57_i99
#ISCELL
  mstr_misc prelim *
  *
#ISCELL
  mstr_symbols design_note *
  *
#ISCELL
  mstr_symbols intel_corp_bpage *
  *
#ISCELL
  mstr_standard offpage *
  page58_i1
#ISCELL
  mstr_standard tap *
  page58_i10
#ISCELL
  mstr_standard tap *
  page58_i100
#ISCELL
  mstr_standard tap *
  page58_i101
#ISCELL
  mstr_standard tap *
  page58_i102
#ISCELL
  mstr_standard tap *
  page58_i103
#ISCELL
  mstr_standard tap *
  page58_i104
#ISCELL
  mstr_standard tap *
  page58_i105
#ISCELL
  mstr_standard tap *
  page58_i106
#ISCELL
  mstr_standard tap *
  page58_i107
#ISCELL
  mstr_standard tap *
  page58_i108
#ISCELL
  mstr_standard tap *
  page58_i109
#ISCELL
  mstr_standard tap *
  page58_i11
#ISCELL
  mstr_standard tap *
  page58_i110
#ISCELL
  mstr_standard tap *
  page58_i111
#ISCELL
  mstr_standard tap *
  page58_i112
#ISCELL
  mstr_standard tap *
  page58_i113
#ISCELL
  mstr_standard tap *
  page58_i114
#ISCELL
  mstr_standard tap *
  page58_i115
#ISCELL
  mstr_standard tap *
  page58_i116
#ISCELL
  mstr_standard tap *
  page58_i117
#ISCELL
  mstr_standard tap *
  page58_i118
#ISCELL
  mstr_standard tap *
  page58_i119
#ISCELL
  mstr_standard tap *
  page58_i12
#ISCELL
  mstr_standard tap *
  page58_i120
#ISCELL
  mstr_standard tap *
  page58_i121
#ISCELL
  mstr_standard tap *
  page58_i122
#ISCELL
  mstr_standard tap *
  page58_i123
#ISCELL
  mstr_standard tap *
  page58_i124
#ISCELL
  mstr_standard tap *
  page58_i125
#ISCELL
  mstr_standard tap *
  page58_i126
#ISCELL
  mstr_standard tap *
  page58_i127
#ISCELL
  mstr_standard tap *
  page58_i128
#ISCELL
  mstr_standard tap *
  page58_i129
#ISCELL
  mstr_standard tap *
  page58_i13
#ISCELL
  mstr_standard tap *
  page58_i130
#ISCELL
  mstr_standard tap *
  page58_i131
#ISCELL
  mstr_standard tap *
  page58_i132
#ISCELL
  mstr_standard tap *
  page58_i133
#ISCELL
  mstr_standard tap *
  page58_i134
#ISCELL
  mstr_standard tap *
  page58_i135
#ISCELL
  mstr_standard tap *
  page58_i136
#ISCELL
  mstr_standard tap *
  page58_i137
#ISCELL
  mstr_standard tap *
  page58_i138
#ISCELL
  mstr_standard tap *
  page58_i139
#ISCELL
  mstr_standard tap *
  page58_i14
#ISCELL
  mstr_standard tap *
  page58_i140
#ISCELL
  mstr_standard tap *
  page58_i141
#ISCELL
  mstr_standard tap *
  page58_i142
#ISCELL
  mstr_standard tap *
  page58_i143
#ISCELL
  mstr_standard tap *
  page58_i144
#ISCELL
  mstr_standard tap *
  page58_i145
#ISCELL
  mstr_standard tap *
  page58_i146
#ISCELL
  mstr_standard offpage *
  page58_i147
#ISCELL
  mstr_standard offpage *
  page58_i148
#ISCELL
  mstr_standard offpage *
  page58_i149
#ISCELL
  mstr_standard tap *
  page58_i15
#ISCELL
  mstr_standard offpage *
  page58_i150
#ISCELL
  mstr_standard offpage *
  page58_i151
#ISCELL
  mstr_standard offpage *
  page58_i152
#ISCELL
  mstr_standard offpage *
  page58_i153
#ISCELL
  mstr_standard offpage *
  page58_i154
#ISCELL
  mstr_standard offpage *
  page58_i155
#ISCELL
  mstr_standard offpage *
  page58_i156
#ISCELL
  mstr_standard tap *
  page58_i157
#ISCELL
  mstr_standard tap *
  page58_i158
#ISCELL
  mstr_standard tap *
  page58_i159
#ISCELL
  mstr_standard tap *
  page58_i16
#ISCELL
  mstr_standard tap *
  page58_i160
#ISCELL
  mstr_standard tap *
  page58_i161
#ISCELL
  mstr_standard tap *
  page58_i162
#ISCELL
  mstr_standard tap *
  page58_i163
#ISCELL
  mstr_standard tap *
  page58_i164
#ISCELL
  mstr_standard tap *
  page58_i165
#ISCELL
  mstr_standard tap *
  page58_i166
#ISCELL
  mstr_standard tap *
  page58_i167
#ISCELL
  mstr_standard tap *
  page58_i168
#ISCELL
  mstr_standard tap *
  page58_i169
#ISCELL
  mstr_standard tap *
  page58_i17
#ISCELL
  mstr_standard tap *
  page58_i170
#ISCELL
  mstr_standard offpage *
  page58_i171
#CELL
  chpset_lib skx_ext_b *
  page58_i172
#ISCELL
  mstr_standard tap *
  page58_i18
#ISCELL
  mstr_standard tap *
  page58_i19
#ISCELL
  mstr_standard offpage *
  page58_i2
#ISCELL
  mstr_standard tap *
  page58_i20
#ISCELL
  mstr_standard tap *
  page58_i21
#ISCELL
  mstr_standard tap *
  page58_i22
#ISCELL
  mstr_standard tap *
  page58_i23
#ISCELL
  mstr_standard tap *
  page58_i24
#ISCELL
  mstr_standard tap *
  page58_i25
#ISCELL
  mstr_standard tap *
  page58_i26
#ISCELL
  mstr_standard tap *
  page58_i27
#ISCELL
  mstr_standard tap *
  page58_i28
#ISCELL
  mstr_standard tap *
  page58_i29
#ISCELL
  mstr_standard offpage *
  page58_i3
#ISCELL
  mstr_standard tap *
  page58_i31
#ISCELL
  mstr_standard tap *
  page58_i32
#ISCELL
  mstr_standard tap *
  page58_i33
#ISCELL
  mstr_standard tap *
  page58_i34
#ISCELL
  mstr_standard tap *
  page58_i35
#ISCELL
  mstr_standard tap *
  page58_i36
#ISCELL
  mstr_standard tap *
  page58_i37
#ISCELL
  mstr_standard tap *
  page58_i38
#ISCELL
  mstr_standard tap *
  page58_i39
#ISCELL
  mstr_standard offpage *
  page58_i4
#ISCELL
  mstr_standard tap *
  page58_i40
#ISCELL
  mstr_standard tap *
  page58_i41
#ISCELL
  mstr_standard tap *
  page58_i42
#ISCELL
  mstr_standard tap *
  page58_i43
#ISCELL
  mstr_standard tap *
  page58_i44
#ISCELL
  mstr_standard tap *
  page58_i45
#ISCELL
  mstr_standard tap *
  page58_i46
#ISCELL
  mstr_standard tap *
  page58_i47
#ISCELL
  mstr_standard tap *
  page58_i48
#ISCELL
  mstr_standard tap *
  page58_i49
#ISCELL
  mstr_standard tap *
  page58_i5
#ISCELL
  mstr_standard tap *
  page58_i50
#ISCELL
  mstr_standard tap *
  page58_i51
#ISCELL
  mstr_standard tap *
  page58_i52
#ISCELL
  mstr_standard tap *
  page58_i53
#ISCELL
  mstr_standard tap *
  page58_i54
#ISCELL
  mstr_standard tap *
  page58_i55
#ISCELL
  mstr_standard tap *
  page58_i56
#ISCELL
  mstr_standard tap *
  page58_i57
#ISCELL
  mstr_standard tap *
  page58_i58
#ISCELL
  mstr_standard tap *
  page58_i59
#ISCELL
  mstr_standard tap *
  page58_i6
#ISCELL
  mstr_standard tap *
  page58_i60
#ISCELL
  mstr_standard tap *
  page58_i61
#ISCELL
  mstr_standard tap *
  page58_i62
#ISCELL
  mstr_standard tap *
  page58_i63
#ISCELL
  mstr_standard tap *
  page58_i64
#ISCELL
  mstr_standard tap *
  page58_i65
#ISCELL
  mstr_standard tap *
  page58_i66
#ISCELL
  mstr_standard tap *
  page58_i67
#ISCELL
  mstr_standard tap *
  page58_i68
#ISCELL
  mstr_standard tap *
  page58_i69
#ISCELL
  mstr_standard tap *
  page58_i7
#ISCELL
  mstr_standard tap *
  page58_i70
#ISCELL
  mstr_standard tap *
  page58_i71
#ISCELL
  mstr_standard offpage *
  page58_i72
#ISCELL
  mstr_standard tap *
  page58_i73
#ISCELL
  mstr_standard tap *
  page58_i74
#ISCELL
  mstr_standard tap *
  page58_i75
#ISCELL
  mstr_standard tap *
  page58_i76
#ISCELL
  mstr_standard tap *
  page58_i77
#ISCELL
  mstr_standard tap *
  page58_i78
#ISCELL
  mstr_standard tap *
  page58_i79
#ISCELL
  mstr_standard tap *
  page58_i8
#ISCELL
  mstr_standard tap *
  page58_i80
#ISCELL
  mstr_standard tap *
  page58_i81
#ISCELL
  mstr_standard tap *
  page58_i82
#ISCELL
  mstr_standard tap *
  page58_i83
#ISCELL
  mstr_standard tap *
  page58_i84
#ISCELL
  mstr_standard tap *
  page58_i85
#ISCELL
  mstr_standard tap *
  page58_i86
#ISCELL
  mstr_standard tap *
  page58_i87
#ISCELL
  mstr_standard tap *
  page58_i88
#ISCELL
  mstr_standard tap *
  page58_i89
#ISCELL
  mstr_standard tap *
  page58_i9
#ISCELL
  mstr_standard tap *
  page58_i90
#ISCELL
  mstr_standard tap *
  page58_i91
#ISCELL
  mstr_standard tap *
  page58_i92
#ISCELL
  mstr_standard tap *
  page58_i93
#ISCELL
  mstr_standard tap *
  page58_i94
#ISCELL
  mstr_standard tap *
  page58_i95
#ISCELL
  mstr_standard tap *
  page58_i96
#ISCELL
  mstr_standard tap *
  page58_i97
#ISCELL
  mstr_standard tap *
  page58_i98
#ISCELL
  mstr_standard tap *
  page58_i99
#ISCELL
  mstr_misc prelim *
  *
#ISCELL
  mstr_symbols design_note *
  *
#ISCELL
  mstr_symbols intel_corp_bpage *
  *
#ISCELL
  mstr_standard offpage *
  page59_i1
#ISCELL
  mstr_standard tap *
  page59_i10
#ISCELL
  mstr_standard tap *
  page59_i100
#ISCELL
  mstr_standard tap *
  page59_i101
#ISCELL
  mstr_standard tap *
  page59_i102
#ISCELL
  mstr_standard tap *
  page59_i103
#ISCELL
  mstr_standard tap *
  page59_i104
#ISCELL
  mstr_standard tap *
  page59_i105
#ISCELL
  mstr_standard tap *
  page59_i106
#ISCELL
  mstr_standard tap *
  page59_i107
#ISCELL
  mstr_standard tap *
  page59_i108
#ISCELL
  mstr_standard tap *
  page59_i109
#ISCELL
  mstr_standard tap *
  page59_i11
#ISCELL
  mstr_standard tap *
  page59_i110
#ISCELL
  mstr_standard tap *
  page59_i111
#ISCELL
  mstr_standard tap *
  page59_i112
#ISCELL
  mstr_standard tap *
  page59_i113
#ISCELL
  mstr_standard tap *
  page59_i114
#ISCELL
  mstr_standard tap *
  page59_i115
#ISCELL
  mstr_standard tap *
  page59_i116
#ISCELL
  mstr_standard tap *
  page59_i117
#ISCELL
  mstr_standard tap *
  page59_i118
#ISCELL
  mstr_standard tap *
  page59_i119
#ISCELL
  mstr_standard tap *
  page59_i12
#ISCELL
  mstr_standard tap *
  page59_i120
#ISCELL
  mstr_standard tap *
  page59_i121
#ISCELL
  mstr_standard tap *
  page59_i122
#ISCELL
  mstr_standard tap *
  page59_i123
#ISCELL
  mstr_standard tap *
  page59_i124
#ISCELL
  mstr_standard tap *
  page59_i125
#ISCELL
  mstr_standard tap *
  page59_i126
#ISCELL
  mstr_standard tap *
  page59_i127
#ISCELL
  mstr_standard tap *
  page59_i128
#ISCELL
  mstr_standard tap *
  page59_i129
#ISCELL
  mstr_standard tap *
  page59_i13
#ISCELL
  mstr_standard tap *
  page59_i130
#ISCELL
  mstr_standard tap *
  page59_i131
#ISCELL
  mstr_standard tap *
  page59_i132
#ISCELL
  mstr_standard tap *
  page59_i133
#ISCELL
  mstr_standard tap *
  page59_i134
#ISCELL
  mstr_standard tap *
  page59_i135
#ISCELL
  mstr_standard tap *
  page59_i136
#ISCELL
  mstr_standard tap *
  page59_i137
#ISCELL
  mstr_standard tap *
  page59_i138
#ISCELL
  mstr_standard tap *
  page59_i139
#ISCELL
  mstr_standard tap *
  page59_i14
#ISCELL
  mstr_standard tap *
  page59_i140
#ISCELL
  mstr_standard tap *
  page59_i141
#ISCELL
  mstr_standard tap *
  page59_i142
#ISCELL
  mstr_standard tap *
  page59_i143
#ISCELL
  mstr_standard tap *
  page59_i144
#ISCELL
  mstr_standard tap *
  page59_i145
#ISCELL
  mstr_standard tap *
  page59_i146
#ISCELL
  mstr_standard offpage *
  page59_i147
#ISCELL
  mstr_standard offpage *
  page59_i148
#ISCELL
  mstr_standard offpage *
  page59_i149
#ISCELL
  mstr_standard tap *
  page59_i15
#ISCELL
  mstr_standard offpage *
  page59_i150
#ISCELL
  mstr_standard offpage *
  page59_i151
#ISCELL
  mstr_standard offpage *
  page59_i152
#ISCELL
  mstr_standard offpage *
  page59_i153
#ISCELL
  mstr_standard offpage *
  page59_i154
#ISCELL
  mstr_standard offpage *
  page59_i155
#ISCELL
  mstr_standard offpage *
  page59_i156
#ISCELL
  mstr_standard tap *
  page59_i157
#ISCELL
  mstr_standard tap *
  page59_i158
#ISCELL
  mstr_standard tap *
  page59_i159
#ISCELL
  mstr_standard tap *
  page59_i16
#ISCELL
  mstr_standard tap *
  page59_i160
#ISCELL
  mstr_standard tap *
  page59_i161
#ISCELL
  mstr_standard tap *
  page59_i162
#ISCELL
  mstr_standard tap *
  page59_i163
#ISCELL
  mstr_standard tap *
  page59_i164
#ISCELL
  mstr_standard tap *
  page59_i165
#ISCELL
  mstr_standard tap *
  page59_i166
#ISCELL
  mstr_standard tap *
  page59_i167
#ISCELL
  mstr_standard tap *
  page59_i168
#ISCELL
  mstr_standard tap *
  page59_i169
#ISCELL
  mstr_standard tap *
  page59_i17
#ISCELL
  mstr_standard tap *
  page59_i170
#ISCELL
  mstr_standard offpage *
  page59_i171
#CELL
  chpset_lib skx_ext_b *
  page59_i172
#ISCELL
  mstr_standard tap *
  page59_i18
#ISCELL
  mstr_standard tap *
  page59_i19
#ISCELL
  mstr_standard offpage *
  page59_i2
#ISCELL
  mstr_standard tap *
  page59_i20
#ISCELL
  mstr_standard tap *
  page59_i21
#ISCELL
  mstr_standard tap *
  page59_i22
#ISCELL
  mstr_standard tap *
  page59_i23
#ISCELL
  mstr_standard tap *
  page59_i24
#ISCELL
  mstr_standard tap *
  page59_i25
#ISCELL
  mstr_standard tap *
  page59_i26
#ISCELL
  mstr_standard tap *
  page59_i27
#ISCELL
  mstr_standard tap *
  page59_i28
#ISCELL
  mstr_standard tap *
  page59_i29
#ISCELL
  mstr_standard offpage *
  page59_i3
#ISCELL
  mstr_standard tap *
  page59_i31
#ISCELL
  mstr_standard tap *
  page59_i32
#ISCELL
  mstr_standard tap *
  page59_i33
#ISCELL
  mstr_standard tap *
  page59_i34
#ISCELL
  mstr_standard tap *
  page59_i35
#ISCELL
  mstr_standard tap *
  page59_i36
#ISCELL
  mstr_standard tap *
  page59_i37
#ISCELL
  mstr_standard tap *
  page59_i38
#ISCELL
  mstr_standard tap *
  page59_i39
#ISCELL
  mstr_standard offpage *
  page59_i4
#ISCELL
  mstr_standard tap *
  page59_i40
#ISCELL
  mstr_standard tap *
  page59_i41
#ISCELL
  mstr_standard tap *
  page59_i42
#ISCELL
  mstr_standard tap *
  page59_i43
#ISCELL
  mstr_standard tap *
  page59_i44
#ISCELL
  mstr_standard tap *
  page59_i45
#ISCELL
  mstr_standard tap *
  page59_i46
#ISCELL
  mstr_standard tap *
  page59_i47
#ISCELL
  mstr_standard tap *
  page59_i48
#ISCELL
  mstr_standard tap *
  page59_i49
#ISCELL
  mstr_standard tap *
  page59_i5
#ISCELL
  mstr_standard tap *
  page59_i50
#ISCELL
  mstr_standard tap *
  page59_i51
#ISCELL
  mstr_standard tap *
  page59_i52
#ISCELL
  mstr_standard tap *
  page59_i53
#ISCELL
  mstr_standard tap *
  page59_i54
#ISCELL
  mstr_standard tap *
  page59_i55
#ISCELL
  mstr_standard tap *
  page59_i56
#ISCELL
  mstr_standard tap *
  page59_i57
#ISCELL
  mstr_standard tap *
  page59_i58
#ISCELL
  mstr_standard tap *
  page59_i59
#ISCELL
  mstr_standard tap *
  page59_i6
#ISCELL
  mstr_standard tap *
  page59_i60
#ISCELL
  mstr_standard tap *
  page59_i61
#ISCELL
  mstr_standard tap *
  page59_i62
#ISCELL
  mstr_standard tap *
  page59_i63
#ISCELL
  mstr_standard tap *
  page59_i64
#ISCELL
  mstr_standard tap *
  page59_i65
#ISCELL
  mstr_standard tap *
  page59_i66
#ISCELL
  mstr_standard tap *
  page59_i67
#ISCELL
  mstr_standard tap *
  page59_i68
#ISCELL
  mstr_standard tap *
  page59_i69
#ISCELL
  mstr_standard tap *
  page59_i7
#ISCELL
  mstr_standard tap *
  page59_i70
#ISCELL
  mstr_standard tap *
  page59_i71
#ISCELL
  mstr_standard offpage *
  page59_i72
#ISCELL
  mstr_standard tap *
  page59_i73
#ISCELL
  mstr_standard tap *
  page59_i74
#ISCELL
  mstr_standard tap *
  page59_i75
#ISCELL
  mstr_standard tap *
  page59_i76
#ISCELL
  mstr_standard tap *
  page59_i77
#ISCELL
  mstr_standard tap *
  page59_i78
#ISCELL
  mstr_standard tap *
  page59_i79
#ISCELL
  mstr_standard tap *
  page59_i8
#ISCELL
  mstr_standard tap *
  page59_i80
#ISCELL
  mstr_standard tap *
  page59_i81
#ISCELL
  mstr_standard tap *
  page59_i82
#ISCELL
  mstr_standard tap *
  page59_i83
#ISCELL
  mstr_standard tap *
  page59_i84
#ISCELL
  mstr_standard tap *
  page59_i85
#ISCELL
  mstr_standard tap *
  page59_i86
#ISCELL
  mstr_standard tap *
  page59_i87
#ISCELL
  mstr_standard tap *
  page59_i88
#ISCELL
  mstr_standard tap *
  page59_i89
#ISCELL
  mstr_standard tap *
  page59_i9
#ISCELL
  mstr_standard tap *
  page59_i90
#ISCELL
  mstr_standard tap *
  page59_i91
#ISCELL
  mstr_standard tap *
  page59_i92
#ISCELL
  mstr_standard tap *
  page59_i93
#ISCELL
  mstr_standard tap *
  page59_i94
#ISCELL
  mstr_standard tap *
  page59_i95
#ISCELL
  mstr_standard tap *
  page59_i96
#ISCELL
  mstr_standard tap *
  page59_i97
#ISCELL
  mstr_standard tap *
  page59_i98
#ISCELL
  mstr_standard tap *
  page59_i99
#ISCELL
  mstr_misc prelim *
  *
#ISCELL
  mstr_symbols design_note *
  *
#ISCELL
  mstr_symbols intel_corp_bpage *
  *
#ISCELL
  mstr_standard offpage *
  page60_i1
#ISCELL
  mstr_standard tap *
  page60_i10
#ISCELL
  mstr_standard tap *
  page60_i100
#ISCELL
  mstr_standard tap *
  page60_i101
#ISCELL
  mstr_standard tap *
  page60_i102
#ISCELL
  mstr_standard tap *
  page60_i103
#ISCELL
  mstr_standard tap *
  page60_i104
#ISCELL
  mstr_standard tap *
  page60_i105
#ISCELL
  mstr_standard tap *
  page60_i106
#ISCELL
  mstr_standard tap *
  page60_i107
#ISCELL
  mstr_standard tap *
  page60_i108
#ISCELL
  mstr_standard tap *
  page60_i109
#ISCELL
  mstr_standard tap *
  page60_i11
#ISCELL
  mstr_standard tap *
  page60_i110
#ISCELL
  mstr_standard tap *
  page60_i111
#ISCELL
  mstr_standard tap *
  page60_i112
#ISCELL
  mstr_standard tap *
  page60_i113
#ISCELL
  mstr_standard tap *
  page60_i114
#ISCELL
  mstr_standard tap *
  page60_i115
#ISCELL
  mstr_standard tap *
  page60_i116
#ISCELL
  mstr_standard tap *
  page60_i117
#ISCELL
  mstr_standard tap *
  page60_i118
#ISCELL
  mstr_standard tap *
  page60_i119
#ISCELL
  mstr_standard tap *
  page60_i12
#ISCELL
  mstr_standard tap *
  page60_i120
#ISCELL
  mstr_standard tap *
  page60_i121
#ISCELL
  mstr_standard tap *
  page60_i122
#ISCELL
  mstr_standard tap *
  page60_i123
#ISCELL
  mstr_standard tap *
  page60_i124
#ISCELL
  mstr_standard tap *
  page60_i125
#ISCELL
  mstr_standard tap *
  page60_i126
#ISCELL
  mstr_standard tap *
  page60_i127
#ISCELL
  mstr_standard tap *
  page60_i128
#ISCELL
  mstr_standard tap *
  page60_i129
#ISCELL
  mstr_standard tap *
  page60_i13
#ISCELL
  mstr_standard tap *
  page60_i130
#ISCELL
  mstr_standard tap *
  page60_i131
#ISCELL
  mstr_standard tap *
  page60_i132
#ISCELL
  mstr_standard tap *
  page60_i133
#ISCELL
  mstr_standard tap *
  page60_i134
#ISCELL
  mstr_standard tap *
  page60_i135
#ISCELL
  mstr_standard tap *
  page60_i136
#ISCELL
  mstr_standard tap *
  page60_i137
#ISCELL
  mstr_standard tap *
  page60_i138
#ISCELL
  mstr_standard tap *
  page60_i139
#ISCELL
  mstr_standard tap *
  page60_i14
#ISCELL
  mstr_standard tap *
  page60_i140
#ISCELL
  mstr_standard tap *
  page60_i141
#ISCELL
  mstr_standard tap *
  page60_i142
#ISCELL
  mstr_standard tap *
  page60_i143
#ISCELL
  mstr_standard tap *
  page60_i144
#ISCELL
  mstr_standard tap *
  page60_i145
#ISCELL
  mstr_standard tap *
  page60_i146
#ISCELL
  mstr_standard offpage *
  page60_i147
#ISCELL
  mstr_standard offpage *
  page60_i148
#ISCELL
  mstr_standard offpage *
  page60_i149
#ISCELL
  mstr_standard tap *
  page60_i15
#ISCELL
  mstr_standard offpage *
  page60_i150
#ISCELL
  mstr_standard offpage *
  page60_i151
#ISCELL
  mstr_standard offpage *
  page60_i152
#ISCELL
  mstr_standard offpage *
  page60_i153
#ISCELL
  mstr_standard offpage *
  page60_i154
#ISCELL
  mstr_standard offpage *
  page60_i155
#ISCELL
  mstr_standard offpage *
  page60_i156
#ISCELL
  mstr_standard tap *
  page60_i157
#ISCELL
  mstr_standard tap *
  page60_i158
#ISCELL
  mstr_standard tap *
  page60_i159
#ISCELL
  mstr_standard tap *
  page60_i16
#ISCELL
  mstr_standard tap *
  page60_i160
#ISCELL
  mstr_standard tap *
  page60_i161
#ISCELL
  mstr_standard tap *
  page60_i162
#ISCELL
  mstr_standard tap *
  page60_i163
#ISCELL
  mstr_standard tap *
  page60_i164
#ISCELL
  mstr_standard tap *
  page60_i165
#ISCELL
  mstr_standard tap *
  page60_i166
#ISCELL
  mstr_standard tap *
  page60_i167
#ISCELL
  mstr_standard tap *
  page60_i168
#ISCELL
  mstr_standard tap *
  page60_i169
#ISCELL
  mstr_standard tap *
  page60_i17
#ISCELL
  mstr_standard tap *
  page60_i170
#ISCELL
  mstr_standard offpage *
  page60_i171
#CELL
  chpset_lib skx_ext_b *
  page60_i172
#ISCELL
  mstr_standard tap *
  page60_i18
#ISCELL
  mstr_standard tap *
  page60_i19
#ISCELL
  mstr_standard offpage *
  page60_i2
#ISCELL
  mstr_standard tap *
  page60_i20
#ISCELL
  mstr_standard tap *
  page60_i21
#ISCELL
  mstr_standard tap *
  page60_i22
#ISCELL
  mstr_standard tap *
  page60_i23
#ISCELL
  mstr_standard tap *
  page60_i24
#ISCELL
  mstr_standard tap *
  page60_i25
#ISCELL
  mstr_standard tap *
  page60_i26
#ISCELL
  mstr_standard tap *
  page60_i27
#ISCELL
  mstr_standard tap *
  page60_i28
#ISCELL
  mstr_standard tap *
  page60_i29
#ISCELL
  mstr_standard offpage *
  page60_i3
#ISCELL
  mstr_standard tap *
  page60_i31
#ISCELL
  mstr_standard tap *
  page60_i32
#ISCELL
  mstr_standard tap *
  page60_i33
#ISCELL
  mstr_standard tap *
  page60_i34
#ISCELL
  mstr_standard tap *
  page60_i35
#ISCELL
  mstr_standard tap *
  page60_i36
#ISCELL
  mstr_standard tap *
  page60_i37
#ISCELL
  mstr_standard tap *
  page60_i38
#ISCELL
  mstr_standard tap *
  page60_i39
#ISCELL
  mstr_standard offpage *
  page60_i4
#ISCELL
  mstr_standard tap *
  page60_i40
#ISCELL
  mstr_standard tap *
  page60_i41
#ISCELL
  mstr_standard tap *
  page60_i42
#ISCELL
  mstr_standard tap *
  page60_i43
#ISCELL
  mstr_standard tap *
  page60_i44
#ISCELL
  mstr_standard tap *
  page60_i45
#ISCELL
  mstr_standard tap *
  page60_i46
#ISCELL
  mstr_standard tap *
  page60_i47
#ISCELL
  mstr_standard tap *
  page60_i48
#ISCELL
  mstr_standard tap *
  page60_i49
#ISCELL
  mstr_standard tap *
  page60_i5
#ISCELL
  mstr_standard tap *
  page60_i50
#ISCELL
  mstr_standard tap *
  page60_i51
#ISCELL
  mstr_standard tap *
  page60_i52
#ISCELL
  mstr_standard tap *
  page60_i53
#ISCELL
  mstr_standard tap *
  page60_i54
#ISCELL
  mstr_standard tap *
  page60_i55
#ISCELL
  mstr_standard tap *
  page60_i56
#ISCELL
  mstr_standard tap *
  page60_i57
#ISCELL
  mstr_standard tap *
  page60_i58
#ISCELL
  mstr_standard tap *
  page60_i59
#ISCELL
  mstr_standard tap *
  page60_i6
#ISCELL
  mstr_standard tap *
  page60_i60
#ISCELL
  mstr_standard tap *
  page60_i61
#ISCELL
  mstr_standard tap *
  page60_i62
#ISCELL
  mstr_standard tap *
  page60_i63
#ISCELL
  mstr_standard tap *
  page60_i64
#ISCELL
  mstr_standard tap *
  page60_i65
#ISCELL
  mstr_standard tap *
  page60_i66
#ISCELL
  mstr_standard tap *
  page60_i67
#ISCELL
  mstr_standard tap *
  page60_i68
#ISCELL
  mstr_standard tap *
  page60_i69
#ISCELL
  mstr_standard tap *
  page60_i7
#ISCELL
  mstr_standard tap *
  page60_i70
#ISCELL
  mstr_standard tap *
  page60_i71
#ISCELL
  mstr_standard offpage *
  page60_i72
#ISCELL
  mstr_standard tap *
  page60_i73
#ISCELL
  mstr_standard tap *
  page60_i74
#ISCELL
  mstr_standard tap *
  page60_i75
#ISCELL
  mstr_standard tap *
  page60_i76
#ISCELL
  mstr_standard tap *
  page60_i77
#ISCELL
  mstr_standard tap *
  page60_i78
#ISCELL
  mstr_standard tap *
  page60_i79
#ISCELL
  mstr_standard tap *
  page60_i8
#ISCELL
  mstr_standard tap *
  page60_i80
#ISCELL
  mstr_standard tap *
  page60_i81
#ISCELL
  mstr_standard tap *
  page60_i82
#ISCELL
  mstr_standard tap *
  page60_i83
#ISCELL
  mstr_standard tap *
  page60_i84
#ISCELL
  mstr_standard tap *
  page60_i85
#ISCELL
  mstr_standard tap *
  page60_i86
#ISCELL
  mstr_standard tap *
  page60_i87
#ISCELL
  mstr_standard tap *
  page60_i88
#ISCELL
  mstr_standard tap *
  page60_i89
#ISCELL
  mstr_standard tap *
  page60_i9
#ISCELL
  mstr_standard tap *
  page60_i90
#ISCELL
  mstr_standard tap *
  page60_i91
#ISCELL
  mstr_standard tap *
  page60_i92
#ISCELL
  mstr_standard tap *
  page60_i93
#ISCELL
  mstr_standard tap *
  page60_i94
#ISCELL
  mstr_standard tap *
  page60_i95
#ISCELL
  mstr_standard tap *
  page60_i96
#ISCELL
  mstr_standard tap *
  page60_i97
#ISCELL
  mstr_standard tap *
  page60_i98
#ISCELL
  mstr_standard tap *
  page60_i99
#ISCELL
  mstr_misc prelim *
  *
#ISCELL
  mstr_symbols design_note *
  *
#ISCELL
  mstr_symbols intel_corp_bpage *
  *
#ISCELL
  mstr_standard offpage *
  page61_i1
#ISCELL
  mstr_standard tap *
  page61_i10
#ISCELL
  mstr_standard tap *
  page61_i100
#ISCELL
  mstr_standard tap *
  page61_i101
#ISCELL
  mstr_standard tap *
  page61_i102
#ISCELL
  mstr_standard tap *
  page61_i103
#ISCELL
  mstr_standard tap *
  page61_i104
#ISCELL
  mstr_standard tap *
  page61_i105
#ISCELL
  mstr_standard tap *
  page61_i106
#ISCELL
  mstr_standard tap *
  page61_i107
#ISCELL
  mstr_standard tap *
  page61_i108
#ISCELL
  mstr_standard tap *
  page61_i109
#ISCELL
  mstr_standard tap *
  page61_i11
#ISCELL
  mstr_standard tap *
  page61_i110
#ISCELL
  mstr_standard tap *
  page61_i111
#ISCELL
  mstr_standard tap *
  page61_i112
#ISCELL
  mstr_standard tap *
  page61_i113
#ISCELL
  mstr_standard tap *
  page61_i114
#ISCELL
  mstr_standard tap *
  page61_i115
#ISCELL
  mstr_standard tap *
  page61_i116
#ISCELL
  mstr_standard tap *
  page61_i117
#ISCELL
  mstr_standard tap *
  page61_i118
#ISCELL
  mstr_standard tap *
  page61_i119
#ISCELL
  mstr_standard tap *
  page61_i12
#ISCELL
  mstr_standard tap *
  page61_i120
#ISCELL
  mstr_standard tap *
  page61_i121
#ISCELL
  mstr_standard tap *
  page61_i122
#ISCELL
  mstr_standard tap *
  page61_i123
#ISCELL
  mstr_standard tap *
  page61_i124
#ISCELL
  mstr_standard tap *
  page61_i125
#ISCELL
  mstr_standard tap *
  page61_i126
#ISCELL
  mstr_standard tap *
  page61_i127
#ISCELL
  mstr_standard tap *
  page61_i128
#ISCELL
  mstr_standard tap *
  page61_i129
#ISCELL
  mstr_standard tap *
  page61_i13
#ISCELL
  mstr_standard tap *
  page61_i130
#ISCELL
  mstr_standard tap *
  page61_i131
#ISCELL
  mstr_standard tap *
  page61_i132
#ISCELL
  mstr_standard tap *
  page61_i133
#ISCELL
  mstr_standard tap *
  page61_i134
#ISCELL
  mstr_standard tap *
  page61_i135
#ISCELL
  mstr_standard tap *
  page61_i136
#ISCELL
  mstr_standard tap *
  page61_i137
#ISCELL
  mstr_standard tap *
  page61_i138
#ISCELL
  mstr_standard tap *
  page61_i139
#ISCELL
  mstr_standard tap *
  page61_i14
#ISCELL
  mstr_standard tap *
  page61_i140
#ISCELL
  mstr_standard tap *
  page61_i141
#ISCELL
  mstr_standard tap *
  page61_i142
#ISCELL
  mstr_standard tap *
  page61_i143
#ISCELL
  mstr_standard tap *
  page61_i144
#ISCELL
  mstr_standard tap *
  page61_i145
#ISCELL
  mstr_standard tap *
  page61_i146
#ISCELL
  mstr_standard offpage *
  page61_i147
#ISCELL
  mstr_standard offpage *
  page61_i148
#ISCELL
  mstr_standard offpage *
  page61_i149
#ISCELL
  mstr_standard tap *
  page61_i15
#ISCELL
  mstr_standard offpage *
  page61_i150
#ISCELL
  mstr_standard offpage *
  page61_i151
#ISCELL
  mstr_standard offpage *
  page61_i152
#ISCELL
  mstr_standard offpage *
  page61_i153
#ISCELL
  mstr_standard offpage *
  page61_i154
#ISCELL
  mstr_standard offpage *
  page61_i155
#ISCELL
  mstr_standard offpage *
  page61_i156
#ISCELL
  mstr_standard tap *
  page61_i157
#ISCELL
  mstr_standard tap *
  page61_i158
#ISCELL
  mstr_standard tap *
  page61_i159
#ISCELL
  mstr_standard tap *
  page61_i16
#ISCELL
  mstr_standard tap *
  page61_i160
#ISCELL
  mstr_standard tap *
  page61_i161
#ISCELL
  mstr_standard tap *
  page61_i162
#ISCELL
  mstr_standard tap *
  page61_i163
#ISCELL
  mstr_standard tap *
  page61_i164
#ISCELL
  mstr_standard tap *
  page61_i165
#ISCELL
  mstr_standard tap *
  page61_i166
#ISCELL
  mstr_standard tap *
  page61_i167
#ISCELL
  mstr_standard tap *
  page61_i168
#ISCELL
  mstr_standard tap *
  page61_i169
#ISCELL
  mstr_standard tap *
  page61_i17
#ISCELL
  mstr_standard tap *
  page61_i170
#ISCELL
  mstr_standard offpage *
  page61_i171
#CELL
  chpset_lib skx_ext_b *
  page61_i172
#ISCELL
  mstr_standard tap *
  page61_i18
#ISCELL
  mstr_standard tap *
  page61_i19
#ISCELL
  mstr_standard offpage *
  page61_i2
#ISCELL
  mstr_standard tap *
  page61_i20
#ISCELL
  mstr_standard tap *
  page61_i21
#ISCELL
  mstr_standard tap *
  page61_i22
#ISCELL
  mstr_standard tap *
  page61_i23
#ISCELL
  mstr_standard tap *
  page61_i24
#ISCELL
  mstr_standard tap *
  page61_i25
#ISCELL
  mstr_standard tap *
  page61_i26
#ISCELL
  mstr_standard tap *
  page61_i27
#ISCELL
  mstr_standard tap *
  page61_i28
#ISCELL
  mstr_standard tap *
  page61_i29
#ISCELL
  mstr_standard offpage *
  page61_i3
#ISCELL
  mstr_standard tap *
  page61_i31
#ISCELL
  mstr_standard tap *
  page61_i32
#ISCELL
  mstr_standard tap *
  page61_i33
#ISCELL
  mstr_standard tap *
  page61_i34
#ISCELL
  mstr_standard tap *
  page61_i35
#ISCELL
  mstr_standard tap *
  page61_i36
#ISCELL
  mstr_standard tap *
  page61_i37
#ISCELL
  mstr_standard tap *
  page61_i38
#ISCELL
  mstr_standard tap *
  page61_i39
#ISCELL
  mstr_standard offpage *
  page61_i4
#ISCELL
  mstr_standard tap *
  page61_i40
#ISCELL
  mstr_standard tap *
  page61_i41
#ISCELL
  mstr_standard tap *
  page61_i42
#ISCELL
  mstr_standard tap *
  page61_i43
#ISCELL
  mstr_standard tap *
  page61_i44
#ISCELL
  mstr_standard tap *
  page61_i45
#ISCELL
  mstr_standard tap *
  page61_i46
#ISCELL
  mstr_standard tap *
  page61_i47
#ISCELL
  mstr_standard tap *
  page61_i48
#ISCELL
  mstr_standard tap *
  page61_i49
#ISCELL
  mstr_standard tap *
  page61_i5
#ISCELL
  mstr_standard tap *
  page61_i50
#ISCELL
  mstr_standard tap *
  page61_i51
#ISCELL
  mstr_standard tap *
  page61_i52
#ISCELL
  mstr_standard tap *
  page61_i53
#ISCELL
  mstr_standard tap *
  page61_i54
#ISCELL
  mstr_standard tap *
  page61_i55
#ISCELL
  mstr_standard tap *
  page61_i56
#ISCELL
  mstr_standard tap *
  page61_i57
#ISCELL
  mstr_standard tap *
  page61_i58
#ISCELL
  mstr_standard tap *
  page61_i59
#ISCELL
  mstr_standard tap *
  page61_i6
#ISCELL
  mstr_standard tap *
  page61_i60
#ISCELL
  mstr_standard tap *
  page61_i61
#ISCELL
  mstr_standard tap *
  page61_i62
#ISCELL
  mstr_standard tap *
  page61_i63
#ISCELL
  mstr_standard tap *
  page61_i64
#ISCELL
  mstr_standard tap *
  page61_i65
#ISCELL
  mstr_standard tap *
  page61_i66
#ISCELL
  mstr_standard tap *
  page61_i67
#ISCELL
  mstr_standard tap *
  page61_i68
#ISCELL
  mstr_standard tap *
  page61_i69
#ISCELL
  mstr_standard tap *
  page61_i7
#ISCELL
  mstr_standard tap *
  page61_i70
#ISCELL
  mstr_standard tap *
  page61_i71
#ISCELL
  mstr_standard offpage *
  page61_i72
#ISCELL
  mstr_standard tap *
  page61_i73
#ISCELL
  mstr_standard tap *
  page61_i74
#ISCELL
  mstr_standard tap *
  page61_i75
#ISCELL
  mstr_standard tap *
  page61_i76
#ISCELL
  mstr_standard tap *
  page61_i77
#ISCELL
  mstr_standard tap *
  page61_i78
#ISCELL
  mstr_standard tap *
  page61_i79
#ISCELL
  mstr_standard tap *
  page61_i8
#ISCELL
  mstr_standard tap *
  page61_i80
#ISCELL
  mstr_standard tap *
  page61_i81
#ISCELL
  mstr_standard tap *
  page61_i82
#ISCELL
  mstr_standard tap *
  page61_i83
#ISCELL
  mstr_standard tap *
  page61_i84
#ISCELL
  mstr_standard tap *
  page61_i85
#ISCELL
  mstr_standard tap *
  page61_i86
#ISCELL
  mstr_standard tap *
  page61_i87
#ISCELL
  mstr_standard tap *
  page61_i88
#ISCELL
  mstr_standard tap *
  page61_i89
#ISCELL
  mstr_standard tap *
  page61_i9
#ISCELL
  mstr_standard tap *
  page61_i90
#ISCELL
  mstr_standard tap *
  page61_i91
#ISCELL
  mstr_standard tap *
  page61_i92
#ISCELL
  mstr_standard tap *
  page61_i93
#ISCELL
  mstr_standard tap *
  page61_i94
#ISCELL
  mstr_standard tap *
  page61_i95
#ISCELL
  mstr_standard tap *
  page61_i96
#ISCELL
  mstr_standard tap *
  page61_i97
#ISCELL
  mstr_standard tap *
  page61_i98
#ISCELL
  mstr_standard tap *
  page61_i99
#ISCELL
  mstr_misc prelim *
  *
#ISCELL
  mstr_symbols design_note *
  *
#ISCELL
  mstr_symbols intel_corp_bpage *
  *
#ISCELL
  mstr_standard offpage *
  page62_i1
#ISCELL
  mstr_standard tap *
  page62_i10
#ISCELL
  mstr_standard tap *
  page62_i100
#ISCELL
  mstr_standard tap *
  page62_i101
#ISCELL
  mstr_standard tap *
  page62_i102
#ISCELL
  mstr_standard tap *
  page62_i103
#ISCELL
  mstr_standard tap *
  page62_i104
#ISCELL
  mstr_standard tap *
  page62_i105
#ISCELL
  mstr_standard tap *
  page62_i106
#ISCELL
  mstr_standard tap *
  page62_i107
#ISCELL
  mstr_standard tap *
  page62_i108
#ISCELL
  mstr_standard tap *
  page62_i109
#ISCELL
  mstr_standard tap *
  page62_i11
#ISCELL
  mstr_standard tap *
  page62_i110
#ISCELL
  mstr_standard tap *
  page62_i111
#ISCELL
  mstr_standard tap *
  page62_i112
#ISCELL
  mstr_standard tap *
  page62_i113
#ISCELL
  mstr_standard tap *
  page62_i114
#ISCELL
  mstr_standard tap *
  page62_i115
#ISCELL
  mstr_standard tap *
  page62_i116
#ISCELL
  mstr_standard tap *
  page62_i117
#ISCELL
  mstr_standard tap *
  page62_i118
#ISCELL
  mstr_standard tap *
  page62_i119
#ISCELL
  mstr_standard tap *
  page62_i12
#ISCELL
  mstr_standard tap *
  page62_i120
#ISCELL
  mstr_standard tap *
  page62_i121
#ISCELL
  mstr_standard tap *
  page62_i122
#ISCELL
  mstr_standard tap *
  page62_i123
#ISCELL
  mstr_standard tap *
  page62_i124
#ISCELL
  mstr_standard tap *
  page62_i125
#ISCELL
  mstr_standard tap *
  page62_i126
#ISCELL
  mstr_standard tap *
  page62_i127
#ISCELL
  mstr_standard tap *
  page62_i128
#ISCELL
  mstr_standard tap *
  page62_i129
#ISCELL
  mstr_standard tap *
  page62_i13
#ISCELL
  mstr_standard tap *
  page62_i130
#ISCELL
  mstr_standard tap *
  page62_i131
#ISCELL
  mstr_standard tap *
  page62_i132
#ISCELL
  mstr_standard tap *
  page62_i133
#ISCELL
  mstr_standard tap *
  page62_i134
#ISCELL
  mstr_standard tap *
  page62_i135
#ISCELL
  mstr_standard tap *
  page62_i136
#ISCELL
  mstr_standard tap *
  page62_i137
#ISCELL
  mstr_standard tap *
  page62_i138
#ISCELL
  mstr_standard tap *
  page62_i139
#ISCELL
  mstr_standard tap *
  page62_i14
#ISCELL
  mstr_standard tap *
  page62_i140
#ISCELL
  mstr_standard tap *
  page62_i141
#ISCELL
  mstr_standard tap *
  page62_i142
#ISCELL
  mstr_standard tap *
  page62_i143
#ISCELL
  mstr_standard tap *
  page62_i144
#ISCELL
  mstr_standard tap *
  page62_i145
#ISCELL
  mstr_standard tap *
  page62_i146
#ISCELL
  mstr_standard offpage *
  page62_i147
#ISCELL
  mstr_standard offpage *
  page62_i148
#ISCELL
  mstr_standard offpage *
  page62_i149
#ISCELL
  mstr_standard tap *
  page62_i15
#ISCELL
  mstr_standard offpage *
  page62_i150
#ISCELL
  mstr_standard offpage *
  page62_i151
#ISCELL
  mstr_standard offpage *
  page62_i152
#ISCELL
  mstr_standard offpage *
  page62_i153
#ISCELL
  mstr_standard offpage *
  page62_i154
#ISCELL
  mstr_standard offpage *
  page62_i155
#ISCELL
  mstr_standard offpage *
  page62_i156
#ISCELL
  mstr_standard tap *
  page62_i157
#ISCELL
  mstr_standard tap *
  page62_i158
#ISCELL
  mstr_standard tap *
  page62_i159
#ISCELL
  mstr_standard tap *
  page62_i16
#ISCELL
  mstr_standard tap *
  page62_i160
#ISCELL
  mstr_standard tap *
  page62_i161
#ISCELL
  mstr_standard tap *
  page62_i162
#ISCELL
  mstr_standard tap *
  page62_i163
#ISCELL
  mstr_standard tap *
  page62_i164
#ISCELL
  mstr_standard tap *
  page62_i165
#ISCELL
  mstr_standard tap *
  page62_i166
#ISCELL
  mstr_standard tap *
  page62_i167
#ISCELL
  mstr_standard tap *
  page62_i168
#ISCELL
  mstr_standard tap *
  page62_i169
#ISCELL
  mstr_standard tap *
  page62_i17
#ISCELL
  mstr_standard tap *
  page62_i170
#ISCELL
  mstr_standard offpage *
  page62_i171
#CELL
  chpset_lib skx_ext_b *
  page62_i172
#ISCELL
  mstr_standard tap *
  page62_i18
#ISCELL
  mstr_standard tap *
  page62_i19
#ISCELL
  mstr_standard offpage *
  page62_i2
#ISCELL
  mstr_standard tap *
  page62_i20
#ISCELL
  mstr_standard tap *
  page62_i21
#ISCELL
  mstr_standard tap *
  page62_i22
#ISCELL
  mstr_standard tap *
  page62_i23
#ISCELL
  mstr_standard tap *
  page62_i24
#ISCELL
  mstr_standard tap *
  page62_i25
#ISCELL
  mstr_standard tap *
  page62_i26
#ISCELL
  mstr_standard tap *
  page62_i27
#ISCELL
  mstr_standard tap *
  page62_i28
#ISCELL
  mstr_standard tap *
  page62_i29
#ISCELL
  mstr_standard offpage *
  page62_i3
#ISCELL
  mstr_standard tap *
  page62_i31
#ISCELL
  mstr_standard tap *
  page62_i32
#ISCELL
  mstr_standard tap *
  page62_i33
#ISCELL
  mstr_standard tap *
  page62_i34
#ISCELL
  mstr_standard tap *
  page62_i35
#ISCELL
  mstr_standard tap *
  page62_i36
#ISCELL
  mstr_standard tap *
  page62_i37
#ISCELL
  mstr_standard tap *
  page62_i38
#ISCELL
  mstr_standard tap *
  page62_i39
#ISCELL
  mstr_standard offpage *
  page62_i4
#ISCELL
  mstr_standard tap *
  page62_i40
#ISCELL
  mstr_standard tap *
  page62_i41
#ISCELL
  mstr_standard tap *
  page62_i42
#ISCELL
  mstr_standard tap *
  page62_i43
#ISCELL
  mstr_standard tap *
  page62_i44
#ISCELL
  mstr_standard tap *
  page62_i45
#ISCELL
  mstr_standard tap *
  page62_i46
#ISCELL
  mstr_standard tap *
  page62_i47
#ISCELL
  mstr_standard tap *
  page62_i48
#ISCELL
  mstr_standard tap *
  page62_i49
#ISCELL
  mstr_standard tap *
  page62_i5
#ISCELL
  mstr_standard tap *
  page62_i50
#ISCELL
  mstr_standard tap *
  page62_i51
#ISCELL
  mstr_standard tap *
  page62_i52
#ISCELL
  mstr_standard tap *
  page62_i53
#ISCELL
  mstr_standard tap *
  page62_i54
#ISCELL
  mstr_standard tap *
  page62_i55
#ISCELL
  mstr_standard tap *
  page62_i56
#ISCELL
  mstr_standard tap *
  page62_i57
#ISCELL
  mstr_standard tap *
  page62_i58
#ISCELL
  mstr_standard tap *
  page62_i59
#ISCELL
  mstr_standard tap *
  page62_i6
#ISCELL
  mstr_standard tap *
  page62_i60
#ISCELL
  mstr_standard tap *
  page62_i61
#ISCELL
  mstr_standard tap *
  page62_i62
#ISCELL
  mstr_standard tap *
  page62_i63
#ISCELL
  mstr_standard tap *
  page62_i64
#ISCELL
  mstr_standard tap *
  page62_i65
#ISCELL
  mstr_standard tap *
  page62_i66
#ISCELL
  mstr_standard tap *
  page62_i67
#ISCELL
  mstr_standard tap *
  page62_i68
#ISCELL
  mstr_standard tap *
  page62_i69
#ISCELL
  mstr_standard tap *
  page62_i7
#ISCELL
  mstr_standard tap *
  page62_i70
#ISCELL
  mstr_standard tap *
  page62_i71
#ISCELL
  mstr_standard offpage *
  page62_i72
#ISCELL
  mstr_standard tap *
  page62_i73
#ISCELL
  mstr_standard tap *
  page62_i74
#ISCELL
  mstr_standard tap *
  page62_i75
#ISCELL
  mstr_standard tap *
  page62_i76
#ISCELL
  mstr_standard tap *
  page62_i77
#ISCELL
  mstr_standard tap *
  page62_i78
#ISCELL
  mstr_standard tap *
  page62_i79
#ISCELL
  mstr_standard tap *
  page62_i8
#ISCELL
  mstr_standard tap *
  page62_i80
#ISCELL
  mstr_standard tap *
  page62_i81
#ISCELL
  mstr_standard tap *
  page62_i82
#ISCELL
  mstr_standard tap *
  page62_i83
#ISCELL
  mstr_standard tap *
  page62_i84
#ISCELL
  mstr_standard tap *
  page62_i85
#ISCELL
  mstr_standard tap *
  page62_i86
#ISCELL
  mstr_standard tap *
  page62_i87
#ISCELL
  mstr_standard tap *
  page62_i88
#ISCELL
  mstr_standard tap *
  page62_i89
#ISCELL
  mstr_standard tap *
  page62_i9
#ISCELL
  mstr_standard tap *
  page62_i90
#ISCELL
  mstr_standard tap *
  page62_i91
#ISCELL
  mstr_standard tap *
  page62_i92
#ISCELL
  mstr_standard tap *
  page62_i93
#ISCELL
  mstr_standard tap *
  page62_i94
#ISCELL
  mstr_standard tap *
  page62_i95
#ISCELL
  mstr_standard tap *
  page62_i96
#ISCELL
  mstr_standard tap *
  page62_i97
#ISCELL
  mstr_standard tap *
  page62_i98
#ISCELL
  mstr_standard tap *
  page62_i99
#ISCELL
  mstr_misc prelim *
  *
#ISCELL
  mstr_symbols design_note *
  *
#ISCELL
  mstr_symbols intel_corp_bpage *
  *
#ISCELL
  mstr_standard offpage *
  page63_i10
#ISCELL
  mstr_standard offpage *
  page63_i12
#ISCELL
  mstr_standard offpage *
  page63_i15
#ISCELL
  mstr_standard offpage *
  page63_i16
#ISCELL
  mstr_standard offpage *
  page63_i20
#ISCELL
  mstr_standard offpage *
  page63_i21
#ISCELL
  mstr_standard offpage *
  page63_i22
#CELL
  chpset_lib skx_ext_b *
  page63_i23
#ISCELL
  mstr_standard offpage *
  page63_i26
#ISCELL
  mstr_symbols vcc_core *
  page63_i27
#ISCELL
  mstr_standard offpage *
  page63_i7
#ISCELL
  mstr_standard offpage *
  page63_i9
#ISCELL
  mstr_misc prelim *
  *
#ISCELL
  mstr_symbols design_note *
  *
#ISCELL
  mstr_symbols intel_corp_bpage *
  *
#ISCELL
  mstr_standard tap *
  page64_i10
#ISCELL
  mstr_standard tap *
  page64_i11
#ISCELL
  mstr_standard tap *
  page64_i12
#ISCELL
  mstr_standard tap *
  page64_i13
#ISCELL
  mstr_standard tap *
  page64_i14
#ISCELL
  mstr_standard tap *
  page64_i15
#ISCELL
  mstr_standard tap *
  page64_i16
#ISCELL
  mstr_standard tap *
  page64_i17
#ISCELL
  mstr_standard tap *
  page64_i18
#ISCELL
  mstr_standard tap *
  page64_i19
#ISCELL
  mstr_standard tap *
  page64_i20
#ISCELL
  mstr_standard tap *
  page64_i21
#ISCELL
  mstr_standard tap *
  page64_i22
#ISCELL
  mstr_standard tap *
  page64_i23
#ISCELL
  mstr_standard tap *
  page64_i24
#ISCELL
  mstr_standard tap *
  page64_i25
#ISCELL
  mstr_standard tap *
  page64_i26
#ISCELL
  mstr_standard tap *
  page64_i27
#ISCELL
  mstr_standard tap *
  page64_i28
#ISCELL
  mstr_standard tap *
  page64_i29
#ISCELL
  mstr_standard tap *
  page64_i3
#ISCELL
  mstr_standard tap *
  page64_i30
#ISCELL
  mstr_standard tap *
  page64_i31
#ISCELL
  mstr_standard tap *
  page64_i32
#ISCELL
  mstr_standard tap *
  page64_i33
#ISCELL
  mstr_standard tap *
  page64_i34
#ISCELL
  mstr_standard tap *
  page64_i35
#ISCELL
  mstr_standard tap *
  page64_i36
#ISCELL
  mstr_standard tap *
  page64_i37
#ISCELL
  mstr_standard tap *
  page64_i38
#ISCELL
  mstr_standard tap *
  page64_i39
#ISCELL
  mstr_standard tap *
  page64_i4
#ISCELL
  mstr_standard tap *
  page64_i40
#ISCELL
  mstr_standard tap *
  page64_i41
#ISCELL
  mstr_standard tap *
  page64_i42
#ISCELL
  mstr_standard tap *
  page64_i43
#ISCELL
  mstr_standard tap *
  page64_i44
#ISCELL
  mstr_standard tap *
  page64_i45
#ISCELL
  mstr_standard tap *
  page64_i46
#ISCELL
  mstr_standard tap *
  page64_i47
#ISCELL
  mstr_standard tap *
  page64_i48
#ISCELL
  mstr_standard tap *
  page64_i49
#ISCELL
  mstr_standard tap *
  page64_i5
#ISCELL
  mstr_standard tap *
  page64_i50
#ISCELL
  mstr_standard tap *
  page64_i51
#ISCELL
  mstr_standard tap *
  page64_i52
#ISCELL
  mstr_standard tap *
  page64_i53
#ISCELL
  mstr_standard tap *
  page64_i54
#ISCELL
  mstr_standard tap *
  page64_i55
#ISCELL
  mstr_standard tap *
  page64_i56
#ISCELL
  mstr_standard tap *
  page64_i57
#ISCELL
  mstr_standard tap *
  page64_i58
#ISCELL
  mstr_standard tap *
  page64_i59
#ISCELL
  mstr_standard tap *
  page64_i6
#ISCELL
  mstr_standard tap *
  page64_i60
#ISCELL
  mstr_standard tap *
  page64_i61
#ISCELL
  mstr_standard tap *
  page64_i62
#ISCELL
  mstr_standard tap *
  page64_i63
#ISCELL
  mstr_standard tap *
  page64_i64
#ISCELL
  mstr_standard tap *
  page64_i65
#ISCELL
  mstr_standard tap *
  page64_i66
#ISCELL
  mstr_standard tap *
  page64_i67
#CELL
  chpset_lib skx_ext_b *
  page64_i68
#ISCELL
  mstr_standard tap *
  page64_i7
#ISCELL
  mstr_standard tap *
  page64_i8
#ISCELL
  mstr_misc prelim *
  *
#ISCELL
  mstr_symbols design_note *
  *
#ISCELL
  mstr_symbols intel_corp_bpage *
  *
#ISCELL
  mstr_standard tap *
  page65_i11
#ISCELL
  mstr_standard tap *
  page65_i12
#ISCELL
  mstr_standard tap *
  page65_i13
#ISCELL
  mstr_standard tap *
  page65_i14
#ISCELL
  mstr_standard tap *
  page65_i15
#ISCELL
  mstr_standard tap *
  page65_i16
#ISCELL
  mstr_standard tap *
  page65_i17
#ISCELL
  mstr_standard tap *
  page65_i18
#ISCELL
  mstr_standard tap *
  page65_i19
#ISCELL
  mstr_standard tap *
  page65_i20
#ISCELL
  mstr_standard tap *
  page65_i21
#ISCELL
  mstr_standard tap *
  page65_i22
#ISCELL
  mstr_standard tap *
  page65_i23
#ISCELL
  mstr_standard tap *
  page65_i24
#ISCELL
  mstr_standard tap *
  page65_i25
#ISCELL
  mstr_standard tap *
  page65_i26
#ISCELL
  mstr_standard tap *
  page65_i27
#ISCELL
  mstr_standard tap *
  page65_i28
#ISCELL
  mstr_standard tap *
  page65_i29
#ISCELL
  mstr_standard tap *
  page65_i3
#ISCELL
  mstr_standard tap *
  page65_i30
#ISCELL
  mstr_standard tap *
  page65_i31
#ISCELL
  mstr_standard tap *
  page65_i32
#ISCELL
  mstr_standard tap *
  page65_i33
#ISCELL
  mstr_standard tap *
  page65_i34
#ISCELL
  mstr_standard tap *
  page65_i35
#ISCELL
  mstr_standard tap *
  page65_i36
#ISCELL
  mstr_standard tap *
  page65_i37
#ISCELL
  mstr_standard tap *
  page65_i38
#ISCELL
  mstr_standard tap *
  page65_i39
#ISCELL
  mstr_standard tap *
  page65_i4
#ISCELL
  mstr_standard tap *
  page65_i40
#ISCELL
  mstr_standard tap *
  page65_i41
#ISCELL
  mstr_standard tap *
  page65_i42
#ISCELL
  mstr_standard tap *
  page65_i43
#ISCELL
  mstr_standard tap *
  page65_i44
#ISCELL
  mstr_standard tap *
  page65_i45
#ISCELL
  mstr_standard tap *
  page65_i46
#ISCELL
  mstr_standard tap *
  page65_i47
#ISCELL
  mstr_standard tap *
  page65_i48
#ISCELL
  mstr_standard tap *
  page65_i49
#ISCELL
  mstr_standard tap *
  page65_i5
#ISCELL
  mstr_standard tap *
  page65_i50
#ISCELL
  mstr_standard tap *
  page65_i51
#ISCELL
  mstr_standard tap *
  page65_i52
#ISCELL
  mstr_standard tap *
  page65_i53
#ISCELL
  mstr_standard tap *
  page65_i54
#ISCELL
  mstr_standard tap *
  page65_i55
#ISCELL
  mstr_standard tap *
  page65_i56
#ISCELL
  mstr_standard tap *
  page65_i57
#ISCELL
  mstr_standard tap *
  page65_i58
#ISCELL
  mstr_standard tap *
  page65_i59
#ISCELL
  mstr_standard tap *
  page65_i6
#ISCELL
  mstr_standard tap *
  page65_i60
#ISCELL
  mstr_standard tap *
  page65_i61
#ISCELL
  mstr_standard tap *
  page65_i62
#ISCELL
  mstr_standard tap *
  page65_i63
#ISCELL
  mstr_standard tap *
  page65_i64
#ISCELL
  mstr_standard tap *
  page65_i65
#ISCELL
  mstr_standard tap *
  page65_i66
#ISCELL
  mstr_standard tap *
  page65_i67
#CELL
  chpset_lib skx_ext_b *
  page65_i68
#ISCELL
  mstr_standard tap *
  page65_i7
#ISCELL
  mstr_standard tap *
  page65_i8
#ISCELL
  mstr_standard tap *
  page65_i9
#ISCELL
  mstr_misc prelim *
  *
#ISCELL
  mstr_symbols design_note *
  *
#ISCELL
  mstr_symbols intel_corp_bpage *
  *
#ISCELL
  mstr_standard tap *
  page66_i10
#ISCELL
  mstr_standard tap *
  page66_i11
#ISCELL
  mstr_standard tap *
  page66_i12
#ISCELL
  mstr_standard tap *
  page66_i13
#ISCELL
  mstr_standard tap *
  page66_i14
#ISCELL
  mstr_standard tap *
  page66_i15
#ISCELL
  mstr_standard tap *
  page66_i16
#ISCELL
  mstr_standard tap *
  page66_i17
#ISCELL
  mstr_standard tap *
  page66_i18
#ISCELL
  mstr_standard tap *
  page66_i19
#ISCELL
  mstr_standard tap *
  page66_i20
#ISCELL
  mstr_standard tap *
  page66_i21
#ISCELL
  mstr_standard tap *
  page66_i22
#ISCELL
  mstr_standard tap *
  page66_i23
#ISCELL
  mstr_standard tap *
  page66_i24
#ISCELL
  mstr_standard tap *
  page66_i25
#ISCELL
  mstr_standard tap *
  page66_i26
#ISCELL
  mstr_standard tap *
  page66_i27
#ISCELL
  mstr_standard tap *
  page66_i28
#ISCELL
  mstr_standard tap *
  page66_i29
#ISCELL
  mstr_standard tap *
  page66_i30
#ISCELL
  mstr_standard tap *
  page66_i31
#ISCELL
  mstr_standard tap *
  page66_i32
#ISCELL
  mstr_standard tap *
  page66_i33
#ISCELL
  mstr_standard tap *
  page66_i34
#ISCELL
  mstr_standard tap *
  page66_i35
#ISCELL
  mstr_standard tap *
  page66_i36
#ISCELL
  mstr_standard tap *
  page66_i37
#ISCELL
  mstr_standard tap *
  page66_i38
#ISCELL
  mstr_standard tap *
  page66_i39
#ISCELL
  mstr_standard tap *
  page66_i40
#ISCELL
  mstr_standard tap *
  page66_i41
#ISCELL
  mstr_standard tap *
  page66_i42
#ISCELL
  mstr_standard tap *
  page66_i43
#ISCELL
  mstr_standard tap *
  page66_i44
#ISCELL
  mstr_standard tap *
  page66_i45
#ISCELL
  mstr_standard tap *
  page66_i46
#ISCELL
  mstr_standard tap *
  page66_i47
#ISCELL
  mstr_standard tap *
  page66_i48
#ISCELL
  mstr_standard tap *
  page66_i49
#ISCELL
  mstr_standard tap *
  page66_i50
#ISCELL
  mstr_standard tap *
  page66_i51
#ISCELL
  mstr_standard tap *
  page66_i52
#ISCELL
  mstr_standard tap *
  page66_i53
#ISCELL
  mstr_standard tap *
  page66_i54
#ISCELL
  mstr_standard tap *
  page66_i55
#ISCELL
  mstr_standard tap *
  page66_i56
#ISCELL
  mstr_standard tap *
  page66_i57
#ISCELL
  mstr_standard tap *
  page66_i58
#ISCELL
  mstr_standard tap *
  page66_i59
#ISCELL
  mstr_standard tap *
  page66_i60
#ISCELL
  mstr_standard tap *
  page66_i61
#ISCELL
  mstr_standard tap *
  page66_i62
#ISCELL
  mstr_standard tap *
  page66_i63
#ISCELL
  mstr_standard tap *
  page66_i64
#ISCELL
  mstr_standard tap *
  page66_i65
#ISCELL
  mstr_standard tap *
  page66_i66
#ISCELL
  mstr_standard tap *
  page66_i67
#ISCELL
  mstr_standard tap *
  page66_i68
#ISCELL
  mstr_standard tap *
  page66_i69
#ISCELL
  mstr_standard tap *
  page66_i70
#ISCELL
  mstr_standard tap *
  page66_i71
#ISCELL
  mstr_standard tap *
  page66_i72
#ISCELL
  mstr_standard tap *
  page66_i73
#ISCELL
  mstr_standard offpage *
  page66_i75
#ISCELL
  mstr_standard offpage *
  page66_i76
#ISCELL
  mstr_standard offpage *
  page66_i77
#ISCELL
  mstr_standard offpage *
  page66_i78
#ISCELL
  mstr_standard offpage *
  page66_i80
#ISCELL
  mstr_standard offpage *
  page66_i81
#ISCELL
  mstr_standard offpage *
  page66_i82
#ISCELL
  mstr_standard offpage *
  page66_i83
#CELL
  chpset_lib skx_ext_b *
  page66_i84
#ISCELL
  mstr_misc prelim *
  *
#ISCELL
  mstr_symbols design_note *
  *
#ISCELL
  mstr_symbols intel_corp_bpage *
  *
#ISCELL
  mstr_standard offpage *
  page67_i1
#ISCELL
  mstr_standard tap *
  page67_i100
#ISCELL
  mstr_standard tap *
  page67_i101
#ISCELL
  mstr_standard tap *
  page67_i102
#ISCELL
  mstr_standard tap *
  page67_i103
#ISCELL
  mstr_standard tap *
  page67_i104
#ISCELL
  mstr_standard tap *
  page67_i105
#ISCELL
  mstr_standard tap *
  page67_i106
#ISCELL
  mstr_standard tap *
  page67_i107
#ISCELL
  mstr_standard tap *
  page67_i108
#ISCELL
  mstr_standard tap *
  page67_i109
#ISCELL
  mstr_standard tap *
  page67_i110
#ISCELL
  mstr_standard tap *
  page67_i111
#ISCELL
  mstr_standard tap *
  page67_i112
#ISCELL
  mstr_standard tap *
  page67_i113
#ISCELL
  mstr_standard tap *
  page67_i114
#ISCELL
  mstr_standard tap *
  page67_i115
#ISCELL
  mstr_standard tap *
  page67_i116
#ISCELL
  mstr_standard tap *
  page67_i117
#ISCELL
  mstr_standard tap *
  page67_i118
#ISCELL
  mstr_standard tap *
  page67_i119
#ISCELL
  mstr_standard tap *
  page67_i120
#ISCELL
  mstr_standard tap *
  page67_i121
#ISCELL
  mstr_standard tap *
  page67_i122
#ISCELL
  mstr_standard tap *
  page67_i123
#ISCELL
  mstr_standard tap *
  page67_i124
#ISCELL
  mstr_standard tap *
  page67_i125
#ISCELL
  mstr_standard tap *
  page67_i126
#ISCELL
  mstr_standard tap *
  page67_i127
#ISCELL
  mstr_standard tap *
  page67_i128
#ISCELL
  mstr_standard tap *
  page67_i129
#ISCELL
  mstr_standard tap *
  page67_i130
#ISCELL
  mstr_standard tap *
  page67_i131
#CELL
  chpset_lib skx_ext_b *
  page67_i132
#ISCELL
  mstr_standard tap *
  page67_i14
#ISCELL
  mstr_standard tap *
  page67_i16
#ISCELL
  mstr_standard offpage *
  page67_i2
#ISCELL
  mstr_standard tap *
  page67_i20
#ISCELL
  mstr_standard tap *
  page67_i21
#ISCELL
  mstr_standard tap *
  page67_i26
#ISCELL
  mstr_standard tap *
  page67_i27
#ISCELL
  mstr_standard tap *
  page67_i28
#ISCELL
  mstr_standard tap *
  page67_i34
#ISCELL
  mstr_standard tap *
  page67_i36
#ISCELL
  mstr_standard tap *
  page67_i40
#ISCELL
  mstr_standard tap *
  page67_i41
#ISCELL
  mstr_standard tap *
  page67_i42
#ISCELL
  mstr_standard tap *
  page67_i43
#ISCELL
  mstr_standard tap *
  page67_i46
#ISCELL
  mstr_standard tap *
  page67_i48
#ISCELL
  mstr_standard tap *
  page67_i49
#ISCELL
  mstr_standard tap *
  page67_i5
#ISCELL
  mstr_standard tap *
  page67_i51
#ISCELL
  mstr_standard tap *
  page67_i53
#ISCELL
  mstr_standard tap *
  page67_i54
#ISCELL
  mstr_standard tap *
  page67_i58
#ISCELL
  mstr_standard tap *
  page67_i6
#ISCELL
  mstr_standard tap *
  page67_i61
#ISCELL
  mstr_standard tap *
  page67_i62
#ISCELL
  mstr_standard tap *
  page67_i66
#ISCELL
  mstr_standard tap *
  page67_i67
#ISCELL
  mstr_standard tap *
  page67_i69
#ISCELL
  mstr_standard tap *
  page67_i7
#ISCELL
  mstr_standard tap *
  page67_i72
#ISCELL
  mstr_standard tap *
  page67_i73
#ISCELL
  mstr_standard tap *
  page67_i74
#ISCELL
  mstr_standard tap *
  page67_i78
#ISCELL
  mstr_standard tap *
  page67_i81
#ISCELL
  mstr_standard tap *
  page67_i83
#ISCELL
  mstr_standard offpage *
  page67_i84
#ISCELL
  mstr_standard offpage *
  page67_i85
#ISCELL
  mstr_standard tap *
  page67_i86
#ISCELL
  mstr_standard tap *
  page67_i87
#ISCELL
  mstr_standard tap *
  page67_i88
#ISCELL
  mstr_standard tap *
  page67_i89
#ISCELL
  mstr_standard tap *
  page67_i90
#ISCELL
  mstr_standard tap *
  page67_i91
#ISCELL
  mstr_standard tap *
  page67_i92
#ISCELL
  mstr_standard tap *
  page67_i93
#ISCELL
  mstr_standard tap *
  page67_i94
#ISCELL
  mstr_standard tap *
  page67_i95
#ISCELL
  mstr_standard tap *
  page67_i96
#ISCELL
  mstr_standard tap *
  page67_i97
#ISCELL
  mstr_standard tap *
  page67_i98
#ISCELL
  mstr_standard tap *
  page67_i99
#ISCELL
  mstr_misc prelim *
  *
#ISCELL
  mstr_symbols design_note *
  *
#ISCELL
  mstr_symbols intel_corp_bpage *
  *
#ISCELL
  mstr_standard offpage *
  page68_i1
#ISCELL
  mstr_standard tap *
  page68_i10
#ISCELL
  mstr_standard tap *
  page68_i100
#ISCELL
  mstr_standard tap *
  page68_i101
#ISCELL
  mstr_standard tap *
  page68_i102
#ISCELL
  mstr_standard tap *
  page68_i103
#ISCELL
  mstr_standard tap *
  page68_i104
#ISCELL
  mstr_standard tap *
  page68_i105
#ISCELL
  mstr_standard tap *
  page68_i106
#ISCELL
  mstr_standard tap *
  page68_i107
#ISCELL
  mstr_standard tap *
  page68_i108
#ISCELL
  mstr_standard tap *
  page68_i109
#ISCELL
  mstr_standard tap *
  page68_i11
#ISCELL
  mstr_standard tap *
  page68_i110
#ISCELL
  mstr_standard tap *
  page68_i111
#ISCELL
  mstr_standard tap *
  page68_i112
#ISCELL
  mstr_standard tap *
  page68_i113
#ISCELL
  mstr_standard tap *
  page68_i114
#ISCELL
  mstr_standard tap *
  page68_i115
#ISCELL
  mstr_standard tap *
  page68_i116
#ISCELL
  mstr_standard tap *
  page68_i117
#ISCELL
  mstr_standard tap *
  page68_i118
#ISCELL
  mstr_standard tap *
  page68_i119
#ISCELL
  mstr_standard tap *
  page68_i120
#ISCELL
  mstr_standard tap *
  page68_i121
#ISCELL
  mstr_standard tap *
  page68_i122
#ISCELL
  mstr_standard tap *
  page68_i123
#ISCELL
  mstr_standard tap *
  page68_i124
#CELL
  chpset_lib skx_ext_b *
  page68_i125
#ISCELL
  mstr_standard tap *
  page68_i13
#ISCELL
  mstr_standard tap *
  page68_i14
#ISCELL
  mstr_standard tap *
  page68_i18
#ISCELL
  mstr_standard offpage *
  page68_i2
#ISCELL
  mstr_standard tap *
  page68_i21
#ISCELL
  mstr_standard tap *
  page68_i22
#ISCELL
  mstr_standard tap *
  page68_i26
#ISCELL
  mstr_standard tap *
  page68_i27
#ISCELL
  mstr_standard tap *
  page68_i28
#ISCELL
  mstr_standard tap *
  page68_i29
#ISCELL
  mstr_standard tap *
  page68_i30
#ISCELL
  mstr_standard tap *
  page68_i31
#ISCELL
  mstr_standard tap *
  page68_i32
#ISCELL
  mstr_standard tap *
  page68_i33
#ISCELL
  mstr_standard tap *
  page68_i34
#ISCELL
  mstr_standard tap *
  page68_i35
#ISCELL
  mstr_standard tap *
  page68_i36
#ISCELL
  mstr_standard tap *
  page68_i37
#ISCELL
  mstr_standard tap *
  page68_i38
#ISCELL
  mstr_standard tap *
  page68_i39
#ISCELL
  mstr_standard tap *
  page68_i40
#ISCELL
  mstr_standard tap *
  page68_i41
#ISCELL
  mstr_standard tap *
  page68_i42
#ISCELL
  mstr_standard tap *
  page68_i43
#ISCELL
  mstr_standard tap *
  page68_i46
#ISCELL
  mstr_standard tap *
  page68_i47
#ISCELL
  mstr_standard tap *
  page68_i48
#ISCELL
  mstr_standard tap *
  page68_i5
#ISCELL
  mstr_standard tap *
  page68_i54
#ISCELL
  mstr_standard tap *
  page68_i56
#ISCELL
  mstr_standard tap *
  page68_i6
#ISCELL
  mstr_standard tap *
  page68_i60
#ISCELL
  mstr_standard tap *
  page68_i61
#ISCELL
  mstr_standard tap *
  page68_i66
#ISCELL
  mstr_standard tap *
  page68_i67
#ISCELL
  mstr_standard tap *
  page68_i69
#ISCELL
  mstr_standard tap *
  page68_i74
#ISCELL
  mstr_standard tap *
  page68_i76
#ISCELL
  mstr_standard tap *
  page68_i80
#ISCELL
  mstr_standard tap *
  page68_i82
#ISCELL
  mstr_standard offpage *
  page68_i84
#ISCELL
  mstr_standard offpage *
  page68_i85
#ISCELL
  mstr_standard tap *
  page68_i86
#ISCELL
  mstr_standard tap *
  page68_i87
#ISCELL
  mstr_standard tap *
  page68_i88
#ISCELL
  mstr_standard tap *
  page68_i89
#ISCELL
  mstr_standard tap *
  page68_i90
#ISCELL
  mstr_standard tap *
  page68_i91
#ISCELL
  mstr_standard tap *
  page68_i92
#ISCELL
  mstr_standard tap *
  page68_i93
#ISCELL
  mstr_standard tap *
  page68_i94
#ISCELL
  mstr_standard tap *
  page68_i95
#ISCELL
  mstr_standard tap *
  page68_i96
#ISCELL
  mstr_standard tap *
  page68_i97
#ISCELL
  mstr_standard tap *
  page68_i98
#ISCELL
  mstr_standard tap *
  page68_i99
#ISCELL
  mstr_misc prelim *
  *
#ISCELL
  mstr_symbols design_note *
  *
#ISCELL
  mstr_symbols intel_corp_bpage *
  *
#CELL
  chpset_lib skx_ext_b *
  page69_i1
#ISCELL
  mstr_symbols gnd *
  page69_i2
#ISCELL
  mstr_misc prelim *
  *
#ISCELL
  mstr_symbols design_note *
  *
#ISCELL
  mstr_symbols intel_corp_bpage *
  *
#CELL
  chpset_lib skx_ext_b *
  page70_i10
#ISCELL
  mstr_standard offpage *
  page70_i11
#ISCELL
  mstr_symbols vcc_core *
  page70_i12
#ISCELL
  mstr_symbols vcc_core *
  page70_i13
#ISCELL
  mstr_symbols vcc_core *
  page70_i15
#ISCELL
  mstr_standard offpage *
  page70_i7
#CELL
  chpset_lib skx_ext_b *
  page70_i9
#ISCELL
  mstr_misc dns *
  *
#ISCELL
  mstr_misc prelim *
  *
#ISCELL
  mstr_symbols design_note *
  *
#ISCELL
  mstr_symbols intel_corp_bpage *
  *
#ISCELL
  mstr_symbols pvccin_cpu1 *
  page71_i35
#ISCELL
  mstr_symbols pvccin_cpu1 *
  page71_i36
#ISCELL
  mstr_standard offpage *
  page71_i38
#ISCELL
  mstr_standard offpage *
  page71_i39
#ISCELL
  mstr_symbols pvccin_cpu1 *
  page71_i40
#ISCELL
  mstr_symbols pvccin_cpu1 *
  page71_i41
#ISCELL
  mstr_symbols gnd *
  page71_i42
#CELL
  mstr_discrete res *
  page71_i43
#ISCELL
  mstr_symbols pvccin_cpu1 *
  page71_i45
#CELL
  mstr_discrete res *
  page71_i49
#CELL
  chpset_lib skx_ext_b *
  page71_i50
#CELL
  chpset_lib skx_ext_b *
  page71_i51
#ISCELL
  mstr_symbols pvccio_cpu1 *
  page71_i52
#CELL
  mstr_discrete res *
  page71_i53
#ISCELL
  mstr_misc prelim *
  *
#ISCELL
  mstr_symbols design_note *
  *
#ISCELL
  mstr_symbols intel_corp_bpage *
  *
#ISCELL
  mstr_symbols pvddq_ghj *
  page72_i14
#ISCELL
  mstr_symbols pvddq_klm *
  page72_i15
#ISCELL
  mstr_symbols pvccio_cpu1 *
  page72_i17
#ISCELL
  mstr_symbols pvccio_cpu1 *
  page72_i18
#ISCELL
  mstr_symbols pvsa_cpu1 *
  page72_i22
#ISCELL
  mstr_symbols gnd *
  page72_i23
#CELL
  mstr_discrete cap *
  page72_i25
#ISCELL
  mstr_symbols vcc_core *
  page72_i28
#ISCELL
  mstr_symbols vcc_core *
  page72_i29
#CELL
  chpset_lib skx_ext_b *
  page72_i32
#CELL
  chpset_lib skx_ext_b *
  page72_i33
#ISCELL
  mstr_symbols pvpp_ghj *
  page72_i38
#ISCELL
  mstr_symbols vcc_core *
  page72_i39
#ISCELL
  mstr_symbols p3v3_stby *
  page72_i40
#ISCELL
  mstr_misc prelim *
  *
#ISCELL
  mstr_symbols design_note *
  *
#ISCELL
  mstr_symbols intel_corp_bpage *
  *
#ISCELL
  mstr_symbols vcc_core *
  page73_i104
#ISCELL
  mstr_symbols vcc_core *
  page73_i105
#CELL
  chpset_lib skx_ext_b *
  page73_i107
#ISCELL
  mstr_symbols vcc_core *
  page73_i108
#ISCELL
  mstr_standard offpage *
  page73_i109
#ISCELL
  mstr_symbols pvccio_cpu1 *
  page73_i22
#ISCELL
  mstr_standard offpage *
  page73_i91
#ISCELL
  mstr_standard offpage *
  page73_i92
#ISCELL
  mstr_standard offpage *
  page73_i93
#ISCELL
  mstr_standard offpage *
  page73_i94
#ISCELL
  mstr_standard offpage *
  page73_i95
#ISCELL
  mstr_standard offpage *
  page73_i96
#ISCELL
  mstr_standard offpage *
  page73_i97
#ISCELL
  mstr_standard offpage *
  page73_i98
#ISCELL
  mstr_misc prelim *
  *
#ISCELL
  mstr_symbols design_note *
  *
#ISCELL
  mstr_symbols intel_corp_bpage *
  *
#ISCELL
  mstr_symbols gnd *
  page74_i1
#ISCELL
  mstr_symbols gnd *
  page74_i11
#ISCELL
  mstr_symbols gnd *
  page74_i12
#ISCELL
  mstr_symbols gnd *
  page74_i14
#CELL
  chpset_lib skx_ext_b *
  page74_i20
#CELL
  chpset_lib skx_ext_b *
  page74_i21
#CELL
  chpset_lib skx_ext_b *
  page74_i22
#CELL
  chpset_lib skx_ext_b *
  page74_i23
#ISCELL
  mstr_symbols gnd *
  page74_i3
#ISCELL
  mstr_symbols gnd *
  page74_i4
#ISCELL
  mstr_symbols gnd *
  page74_i6
#ISCELL
  mstr_symbols gnd *
  page74_i9
#ISCELL
  mstr_misc prelim *
  *
#ISCELL
  mstr_symbols design_note *
  *
#ISCELL
  mstr_symbols intel_corp_bpage *
  *
#ISCELL
  mstr_symbols gnd *
  page75_i10
#ISCELL
  mstr_symbols gnd *
  page75_i11
#ISCELL
  mstr_symbols gnd *
  page75_i12
#ISCELL
  mstr_symbols gnd *
  page75_i13
#ISCELL
  mstr_symbols gnd *
  page75_i14
#ISCELL
  mstr_symbols gnd *
  page75_i15
#ISCELL
  mstr_symbols gnd *
  page75_i16
#CELL
  chpset_lib skx_ext_b *
  page75_i17
#CELL
  chpset_lib skx_ext_b *
  page75_i18
#CELL
  chpset_lib skx_ext_b *
  page75_i19
#CELL
  chpset_lib skx_ext_b *
  page75_i20
#ISCELL
  mstr_symbols gnd *
  page75_i9
#ISCELL
  mstr_symbols design_note *
  *
#ISCELL
  mstr_symbols intel_corp_bpage *
  *
#CELL
  dev_discrete cap_a *
  page76_i1
#CELL
  dev_discrete cap_a *
  page76_i10
#CELL
  mstr_discrete cap *
  page76_i100
#CELL
  mstr_discrete cap *
  page76_i101
#CELL
  mstr_discrete cap *
  page76_i103
#CELL
  mstr_discrete cap *
  page76_i105
#CELL
  mstr_discrete cap *
  page76_i106
#CELL
  mstr_discrete cap *
  page76_i107
#CELL
  dev_discrete cap_a *
  page76_i108
#ISCELL
  mstr_symbols gnd *
  page76_i109
#CELL
  dev_discrete cap_a *
  page76_i111
#CELL
  dev_discrete cap_a *
  page76_i112
#ISCELL
  mstr_symbols gnd *
  page76_i113
#CELL
  dev_discrete cap_a *
  page76_i114
#CELL
  dev_discrete cap_a *
  page76_i116
#CELL
  mstr_discrete cap *
  page76_i118
#CELL
  dev_discrete cap_a *
  page76_i119
#CELL
  dev_discrete cap_a *
  page76_i122
#CELL
  dev_discrete cap_a *
  page76_i123
#CELL
  dev_discrete cap_a *
  page76_i124
#CELL
  mstr_discrete cap *
  page76_i125
#CELL
  mstr_discrete cap *
  page76_i127
#ISCELL
  mstr_symbols gnd *
  page76_i128
#CELL
  mstr_discrete cap *
  page76_i129
#ISCELL
  mstr_symbols gnd *
  page76_i130
#CELL
  mstr_discrete cap *
  page76_i131
#CELL
  mstr_discrete cap *
  page76_i132
#CELL
  mstr_discrete cap *
  page76_i133
#ISCELL
  mstr_symbols gnd *
  page76_i134
#CELL
  mstr_discrete cap *
  page76_i135
#CELL
  mstr_discrete cap *
  page76_i136
#CELL
  mstr_discrete cap *
  page76_i137
#CELL
  mstr_discrete cap *
  page76_i139
#CELL
  mstr_discrete cap *
  page76_i141
#ISCELL
  mstr_symbols pvccin_cpu1 *
  page76_i143
#ISCELL
  mstr_symbols pvccin_cpu1 *
  page76_i144
#ISCELL
  mstr_symbols pvccin_cpu1 *
  page76_i145
#ISCELL
  mstr_symbols pvccin_cpu1 *
  page76_i146
#ISCELL
  mstr_symbols pvccin_cpu1 *
  page76_i147
#CELL
  dev_discrete cap_a *
  page76_i15
#ISCELL
  mstr_symbols pvccin_cpu1 *
  page76_i153
#ISCELL
  mstr_symbols pvccin_cpu1 *
  page76_i154
#ISCELL
  mstr_symbols pvccin_cpu1 *
  page76_i155
#ISCELL
  mstr_symbols pvccin_cpu1 *
  page76_i156
#ISCELL
  mstr_symbols pvccin_cpu1 *
  page76_i157
#ISCELL
  mstr_symbols pvccin_cpu1 *
  page76_i158
#CELL
  dev_discrete cap_a *
  page76_i159
#ISCELL
  mstr_symbols gnd *
  page76_i16
#CELL
  dev_discrete cap_a *
  page76_i160
#CELL
  dev_discrete cap_a *
  page76_i161
#ISCELL
  mstr_symbols vcc_core *
  page76_i162
#ISCELL
  mstr_symbols vcc_core *
  page76_i163
#CELL
  dev_discrete cap_a *
  page76_i164
#CELL
  dev_discrete cap_a *
  page76_i165
#CELL
  dev_discrete cap_a *
  page76_i166
#ISCELL
  mstr_symbols pvccio_cpu1 *
  page76_i167
#CELL
  dev_discrete cap_a *
  page76_i169
#CELL
  dev_discrete cap_a *
  page76_i170
#CELL
  dev_discrete cap_a *
  page76_i171
#CELL
  dev_discrete cap_a *
  page76_i172
#CELL
  dev_discrete cap_a *
  page76_i174
#CELL
  dev_discrete cap_a *
  page76_i175
#CELL
  dev_discrete cap_a *
  page76_i176
#CELL
  dev_discrete cap_a *
  page76_i179
#CELL
  dev_discrete cap_a *
  page76_i18
#CELL
  mstr_discrete cap *
  page76_i181
#CELL
  mstr_discrete cap *
  page76_i182
#CELL
  mstr_discrete cap *
  page76_i183
#CELL
  mstr_discrete cap *
  page76_i184
#CELL
  mstr_discrete cap *
  page76_i195
#CELL
  dev_discrete cap_a *
  page76_i196
#CELL
  dev_discrete cap_a *
  page76_i197
#CELL
  dev_discrete cap_a *
  page76_i198
#CELL
  dev_discrete cap_a *
  page76_i199
#ISCELL
  mstr_symbols gnd *
  page76_i2
#CELL
  dev_discrete cap_a *
  page76_i201
#CELL
  dev_discrete cap_a *
  page76_i202
#CELL
  dev_discrete cap_a *
  page76_i203
#CELL
  dev_discrete cap_a *
  page76_i204
#CELL
  dev_discrete cap_a *
  page76_i205
#CELL
  dev_discrete cap_a *
  page76_i206
#CELL
  dev_discrete cap_a *
  page76_i207
#CELL
  dev_discrete cap_a *
  page76_i208
#ISCELL
  mstr_symbols vcc_core *
  page76_i209
#ISCELL
  mstr_symbols gnd *
  page76_i210
#CELL
  mstr_discrete cap *
  page76_i211
#CELL
  mstr_discrete cap *
  page76_i212
#CELL
  mstr_discrete cap *
  page76_i213
#CELL
  mstr_discrete cap *
  page76_i214
#CELL
  mstr_discrete cap *
  page76_i215
#CELL
  mstr_discrete cap *
  page76_i216
#CELL
  mstr_discrete cap *
  page76_i217
#CELL
  mstr_discrete cap *
  page76_i218
#CELL
  mstr_discrete cap *
  page76_i23
#ISCELL
  mstr_symbols gnd *
  page76_i24
#CELL
  mstr_discrete cap *
  page76_i25
#CELL
  mstr_discrete cap *
  page76_i26
#CELL
  mstr_discrete cap *
  page76_i27
#CELL
  mstr_discrete cap *
  page76_i28
#CELL
  mstr_discrete cap *
  page76_i29
#CELL
  dev_discrete cap_a *
  page76_i3
#ISCELL
  mstr_symbols gnd *
  page76_i30
#CELL
  mstr_discrete cap *
  page76_i33
#ISCELL
  mstr_symbols gnd *
  page76_i36
#CELL
  mstr_discrete cap *
  page76_i37
#CELL
  dev_discrete cap_a *
  page76_i4
#ISCELL
  mstr_symbols pvsa_cpu1 *
  page76_i41
#CELL
  mstr_discrete cap *
  page76_i42
#CELL
  mstr_discrete cap *
  page76_i43
#CELL
  mstr_discrete cap *
  page76_i45
#ISCELL
  mstr_symbols pvccio_cpu1 *
  page76_i47
#CELL
  mstr_discrete cap *
  page76_i48
#CELL
  mstr_discrete cap *
  page76_i49
#CELL
  dev_discrete cap_a *
  page76_i5
#CELL
  mstr_discrete cap *
  page76_i50
#CELL
  mstr_discrete cap *
  page76_i51
#CELL
  mstr_discrete cap *
  page76_i52
#ISCELL
  mstr_symbols gnd *
  page76_i53
#CELL
  mstr_discrete cap *
  page76_i55
#ISCELL
  mstr_symbols pvsa_cpu1 *
  page76_i57
#CELL
  mstr_discrete cap *
  page76_i58
#CELL
  dev_discrete cap_a *
  page76_i59
#ISCELL
  mstr_symbols gnd *
  page76_i60
#CELL
  dev_discrete cap_a *
  page76_i61
#CELL
  dev_discrete cap_a *
  page76_i63
#CELL
  dev_discrete cap_a *
  page76_i65
#CELL
  dev_discrete cap_a *
  page76_i66
#ISCELL
  mstr_symbols gnd *
  page76_i67
#CELL
  dev_discrete cap_a *
  page76_i69
#CELL
  dev_discrete cap_a *
  page76_i7
#CELL
  dev_discrete cap_a *
  page76_i70
#ISCELL
  mstr_symbols pvccin_cpu1 *
  page76_i71
#CELL
  dev_discrete cap_a *
  page76_i73
#ISCELL
  mstr_symbols gnd *
  page76_i74
#CELL
  dev_discrete cap_a *
  page76_i75
#CELL
  dev_discrete cap_a *
  page76_i76
#ISCELL
  mstr_symbols gnd *
  page76_i77
#CELL
  dev_discrete cap_a *
  page76_i79
#CELL
  dev_discrete cap_a *
  page76_i8
#CELL
  dev_discrete cap_a *
  page76_i80
#CELL
  dev_discrete cap_a *
  page76_i82
#CELL
  dev_discrete cap_a *
  page76_i83
#CELL
  dev_discrete cap_a *
  page76_i85
#CELL
  mstr_discrete cap *
  page76_i88
#CELL
  mstr_discrete cap *
  page76_i89
#CELL
  dev_discrete cap_a *
  page76_i90
#CELL
  mstr_discrete cap *
  page76_i92
#ISCELL
  mstr_symbols gnd *
  page76_i93
#ISCELL
  mstr_symbols gnd *
  page76_i95
#ISCELL
  mstr_symbols gnd *
  page76_i97
#ISCELL
  mstr_symbols bom_note *
  *
#ISCELL
  mstr_symbols intel_corp_bpage *
  *
#ISCELL
  mstr_standard offpage *
  page77_i1
#ISCELL
  mstr_standard tap *
  page77_i10
#ISCELL
  mstr_standard tap *
  page77_i100
#ISCELL
  mstr_standard tap *
  page77_i101
#ISCELL
  mstr_standard tap *
  page77_i102
#ISCELL
  mstr_standard tap *
  page77_i103
#ISCELL
  mstr_standard tap *
  page77_i104
#ISCELL
  mstr_standard tap *
  page77_i105
#ISCELL
  mstr_standard tap *
  page77_i106
#ISCELL
  mstr_standard tap *
  page77_i107
#ISCELL
  mstr_standard tap *
  page77_i108
#ISCELL
  mstr_standard tap *
  page77_i109
#ISCELL
  mstr_standard tap *
  page77_i11
#ISCELL
  mstr_standard tap *
  page77_i110
#CELL
  mstr_sconn sconn288_h44441004 *
  page77_i111
#ISCELL
  mstr_standard tap *
  page77_i112
#ISCELL
  mstr_standard tap *
  page77_i113
#ISCELL
  mstr_standard tap *
  page77_i114
#ISCELL
  mstr_standard tap *
  page77_i115
#ISCELL
  mstr_standard tap *
  page77_i116
#ISCELL
  mstr_standard tap *
  page77_i117
#ISCELL
  mstr_standard tap *
  page77_i118
#ISCELL
  mstr_standard tap *
  page77_i119
#ISCELL
  mstr_standard tap *
  page77_i12
#ISCELL
  mstr_standard tap *
  page77_i120
#ISCELL
  mstr_standard tap *
  page77_i121
#ISCELL
  mstr_standard tap *
  page77_i122
#ISCELL
  mstr_standard tap *
  page77_i123
#ISCELL
  mstr_standard tap *
  page77_i124
#ISCELL
  mstr_standard tap *
  page77_i125
#ISCELL
  mstr_standard tap *
  page77_i126
#ISCELL
  mstr_standard tap *
  page77_i127
#ISCELL
  mstr_standard tap *
  page77_i128
#ISCELL
  mstr_standard tap *
  page77_i129
#ISCELL
  mstr_standard tap *
  page77_i13
#ISCELL
  mstr_standard tap *
  page77_i130
#ISCELL
  mstr_standard offpage *
  page77_i131
#ISCELL
  mstr_standard offpage *
  page77_i132
#ISCELL
  mstr_standard tap *
  page77_i133
#ISCELL
  mstr_standard tap *
  page77_i134
#ISCELL
  mstr_standard tap *
  page77_i135
#ISCELL
  mstr_standard offpage *
  page77_i136
#ISCELL
  mstr_standard offpage *
  page77_i137
#ISCELL
  mstr_standard tap *
  page77_i138
#ISCELL
  mstr_standard tap *
  page77_i139
#ISCELL
  mstr_standard tap *
  page77_i14
#ISCELL
  mstr_standard tap *
  page77_i140
#ISCELL
  mstr_standard tap *
  page77_i141
#ISCELL
  mstr_standard tap *
  page77_i142
#ISCELL
  mstr_standard tap *
  page77_i143
#ISCELL
  mstr_standard tap *
  page77_i144
#ISCELL
  mstr_standard tap *
  page77_i145
#ISCELL
  mstr_standard offpage *
  page77_i147
#ISCELL
  mstr_standard offpage *
  page77_i148
#ISCELL
  mstr_standard offpage *
  page77_i149
#ISCELL
  mstr_standard tap *
  page77_i15
#ISCELL
  mstr_standard offpage *
  page77_i150
#ISCELL
  mstr_standard tap *
  page77_i152
#ISCELL
  mstr_standard tap *
  page77_i153
#ISCELL
  mstr_standard offpage *
  page77_i154
#ISCELL
  mstr_standard offpage *
  page77_i155
#ISCELL
  mstr_standard tap *
  page77_i156
#ISCELL
  mstr_standard tap *
  page77_i157
#ISCELL
  mstr_standard tap *
  page77_i158
#ISCELL
  mstr_standard tap *
  page77_i159
#ISCELL
  mstr_symbols pvddq_ghj *
  page77_i16
#ISCELL
  mstr_standard tap *
  page77_i160
#ISCELL
  mstr_standard tap *
  page77_i161
#ISCELL
  mstr_standard tap *
  page77_i162
#ISCELL
  mstr_standard offpage *
  page77_i163
#ISCELL
  mstr_standard offpage *
  page77_i164
#ISCELL
  mstr_standard tap *
  page77_i165
#ISCELL
  mstr_standard tap *
  page77_i166
#ISCELL
  mstr_standard offpage *
  page77_i167
#ISCELL
  mstr_standard tap *
  page77_i168
#ISCELL
  mstr_symbols pvtt_ghj *
  page77_i17
#CELL
  mstr_sconn sconn288_h44441004 *
  page77_i171
#ISCELL
  mstr_symbols gnd *
  page77_i172
#ISCELL
  mstr_standard offpage *
  page77_i173
#ISCELL
  mstr_standard offpage *
  page77_i174
#ISCELL
  mstr_standard offpage *
  page77_i175
#ISCELL
  mstr_symbols gnd *
  page77_i177
#ISCELL
  mstr_standard offpage *
  page77_i178
#ISCELL
  mstr_standard offpage *
  page77_i179
#ISCELL
  mstr_symbols gnd *
  page77_i180
#CELL
  dev_discrete cap_a *
  page77_i181
#ISCELL
  mstr_symbols pvpp_ghj *
  page77_i182
#ISCELL
  mstr_symbols pvpp_ghj *
  page77_i183
#ISCELL
  mstr_standard offpage *
  page77_i184
#ISCELL
  mstr_standard tap *
  page77_i19
#ISCELL
  mstr_symbols p12v_nvdimm_ghj *
  page77_i197
#ISCELL
  mstr_standard offpage *
  page77_i2
#ISCELL
  mstr_standard tap *
  page77_i20
#ISCELL
  mstr_standard tap *
  page77_i21
#ISCELL
  mstr_standard tap *
  page77_i22
#ISCELL
  mstr_standard tap *
  page77_i23
#ISCELL
  mstr_standard tap *
  page77_i24
#ISCELL
  mstr_standard tap *
  page77_i25
#ISCELL
  mstr_standard tap *
  page77_i26
#ISCELL
  mstr_standard tap *
  page77_i27
#ISCELL
  mstr_standard tap *
  page77_i28
#ISCELL
  mstr_standard tap *
  page77_i29
#ISCELL
  mstr_standard tap *
  page77_i3
#ISCELL
  mstr_standard tap *
  page77_i30
#ISCELL
  mstr_standard tap *
  page77_i31
#ISCELL
  mstr_standard tap *
  page77_i32
#ISCELL
  mstr_standard tap *
  page77_i33
#ISCELL
  mstr_standard tap *
  page77_i34
#ISCELL
  mstr_standard tap *
  page77_i35
#ISCELL
  mstr_standard tap *
  page77_i36
#ISCELL
  mstr_standard tap *
  page77_i37
#ISCELL
  mstr_standard tap *
  page77_i38
#ISCELL
  mstr_standard tap *
  page77_i39
#ISCELL
  mstr_standard tap *
  page77_i4
#ISCELL
  mstr_standard tap *
  page77_i40
#ISCELL
  mstr_standard tap *
  page77_i41
#CELL
  mstr_sconn sconn288_h44441004 *
  page77_i43
#ISCELL
  mstr_symbols gnd *
  page77_i44
#ISCELL
  mstr_standard offpage *
  page77_i45
#ISCELL
  mstr_standard tap *
  page77_i46
#ISCELL
  mstr_standard tap *
  page77_i47
#ISCELL
  mstr_standard tap *
  page77_i48
#ISCELL
  mstr_standard tap *
  page77_i49
#ISCELL
  mstr_standard tap *
  page77_i5
#ISCELL
  mstr_standard tap *
  page77_i50
#ISCELL
  mstr_standard tap *
  page77_i51
#ISCELL
  mstr_standard tap *
  page77_i52
#ISCELL
  mstr_standard tap *
  page77_i53
#ISCELL
  mstr_standard tap *
  page77_i54
#ISCELL
  mstr_standard tap *
  page77_i55
#ISCELL
  mstr_standard tap *
  page77_i56
#ISCELL
  mstr_standard tap *
  page77_i57
#ISCELL
  mstr_standard tap *
  page77_i58
#ISCELL
  mstr_standard tap *
  page77_i59
#ISCELL
  mstr_standard tap *
  page77_i6
#ISCELL
  mstr_standard tap *
  page77_i60
#ISCELL
  mstr_standard tap *
  page77_i61
#ISCELL
  mstr_standard tap *
  page77_i62
#ISCELL
  mstr_standard tap *
  page77_i63
#ISCELL
  mstr_standard tap *
  page77_i64
#ISCELL
  mstr_standard tap *
  page77_i65
#CELL
  mstr_sconn sconn288_h44441004 *
  page77_i66
#ISCELL
  mstr_standard tap *
  page77_i67
#ISCELL
  mstr_standard tap *
  page77_i68
#ISCELL
  mstr_standard tap *
  page77_i69
#ISCELL
  mstr_standard tap *
  page77_i7
#ISCELL
  mstr_standard tap *
  page77_i70
#ISCELL
  mstr_standard tap *
  page77_i71
#ISCELL
  mstr_standard tap *
  page77_i72
#ISCELL
  mstr_standard tap *
  page77_i73
#ISCELL
  mstr_standard tap *
  page77_i74
#ISCELL
  mstr_standard tap *
  page77_i75
#ISCELL
  mstr_standard tap *
  page77_i76
#ISCELL
  mstr_standard tap *
  page77_i77
#ISCELL
  mstr_standard tap *
  page77_i78
#ISCELL
  mstr_standard tap *
  page77_i79
#ISCELL
  mstr_standard tap *
  page77_i8
#ISCELL
  mstr_standard tap *
  page77_i80
#ISCELL
  mstr_standard tap *
  page77_i81
#ISCELL
  mstr_standard tap *
  page77_i82
#ISCELL
  mstr_standard tap *
  page77_i83
#ISCELL
  mstr_standard tap *
  page77_i84
#ISCELL
  mstr_standard tap *
  page77_i85
#ISCELL
  mstr_standard tap *
  page77_i86
#ISCELL
  mstr_standard tap *
  page77_i87
#ISCELL
  mstr_standard tap *
  page77_i88
#ISCELL
  mstr_standard tap *
  page77_i89
#ISCELL
  mstr_standard tap *
  page77_i9
#ISCELL
  mstr_standard tap *
  page77_i90
#ISCELL
  mstr_standard tap *
  page77_i91
#ISCELL
  mstr_standard tap *
  page77_i92
#ISCELL
  mstr_standard tap *
  page77_i93
#ISCELL
  mstr_standard tap *
  page77_i94
#ISCELL
  mstr_standard tap *
  page77_i95
#ISCELL
  mstr_standard tap *
  page77_i96
#ISCELL
  mstr_standard tap *
  page77_i97
#ISCELL
  mstr_standard tap *
  page77_i98
#ISCELL
  mstr_standard tap *
  page77_i99
#ISCELL
  mstr_symbols bom_note *
  *
#ISCELL
  mstr_symbols intel_corp_bpage *
  *
#ISCELL
  mstr_symbols gnd *
  page78_i1
#ISCELL
  mstr_standard offpage *
  page78_i10
#ISCELL
  mstr_standard tap *
  page78_i100
#ISCELL
  mstr_standard tap *
  page78_i101
#ISCELL
  mstr_standard tap *
  page78_i102
#ISCELL
  mstr_standard tap *
  page78_i103
#ISCELL
  mstr_standard tap *
  page78_i104
#ISCELL
  mstr_standard tap *
  page78_i105
#ISCELL
  mstr_standard tap *
  page78_i106
#ISCELL
  mstr_standard tap *
  page78_i107
#ISCELL
  mstr_standard tap *
  page78_i108
#ISCELL
  mstr_standard tap *
  page78_i109
#ISCELL
  mstr_standard offpage *
  page78_i11
#ISCELL
  mstr_standard tap *
  page78_i110
#ISCELL
  mstr_standard tap *
  page78_i111
#ISCELL
  mstr_standard tap *
  page78_i112
#ISCELL
  mstr_standard tap *
  page78_i113
#ISCELL
  mstr_standard tap *
  page78_i114
#ISCELL
  mstr_standard tap *
  page78_i115
#ISCELL
  mstr_standard tap *
  page78_i116
#ISCELL
  mstr_standard tap *
  page78_i117
#ISCELL
  mstr_standard tap *
  page78_i118
#ISCELL
  mstr_symbols pvpp_ghj *
  page78_i119
#ISCELL
  mstr_standard tap *
  page78_i12
#CELL
  mstr_sconn sconn288_h44441003 *
  page78_i120
#ISCELL
  mstr_standard offpage *
  page78_i121
#ISCELL
  mstr_standard tap *
  page78_i122
#ISCELL
  mstr_standard tap *
  page78_i123
#ISCELL
  mstr_standard tap *
  page78_i124
#ISCELL
  mstr_standard tap *
  page78_i125
#ISCELL
  mstr_standard tap *
  page78_i126
#ISCELL
  mstr_standard tap *
  page78_i127
#ISCELL
  mstr_standard tap *
  page78_i128
#CELL
  mstr_sconn sconn288_h44441003 *
  page78_i13
#ISCELL
  mstr_standard tap *
  page78_i135
#ISCELL
  mstr_standard tap *
  page78_i136
#ISCELL
  mstr_standard tap *
  page78_i137
#ISCELL
  mstr_standard tap *
  page78_i138
#ISCELL
  mstr_standard tap *
  page78_i139
#ISCELL
  mstr_standard offpage *
  page78_i14
#ISCELL
  mstr_standard tap *
  page78_i140
#ISCELL
  mstr_standard tap *
  page78_i141
#ISCELL
  mstr_standard offpage *
  page78_i142
#ISCELL
  mstr_symbols gnd *
  page78_i143
#CELL
  mstr_sconn sconn288_h44441003 *
  page78_i144
#ISCELL
  mstr_standard tap *
  page78_i148
#ISCELL
  mstr_standard tap *
  page78_i149
#ISCELL
  mstr_standard offpage *
  page78_i15
#ISCELL
  mstr_standard tap *
  page78_i150
#ISCELL
  mstr_standard tap *
  page78_i151
#ISCELL
  mstr_standard tap *
  page78_i152
#ISCELL
  mstr_standard tap *
  page78_i153
#ISCELL
  mstr_standard tap *
  page78_i154
#ISCELL
  mstr_standard tap *
  page78_i155
#ISCELL
  mstr_standard tap *
  page78_i156
#ISCELL
  mstr_standard tap *
  page78_i157
#ISCELL
  mstr_standard tap *
  page78_i158
#ISCELL
  mstr_standard tap *
  page78_i159
#ISCELL
  mstr_standard offpage *
  page78_i16
#ISCELL
  mstr_standard tap *
  page78_i160
#ISCELL
  mstr_standard tap *
  page78_i161
#ISCELL
  mstr_standard tap *
  page78_i162
#ISCELL
  mstr_standard tap *
  page78_i163
#ISCELL
  mstr_symbols gnd *
  page78_i164
#ISCELL
  mstr_standard tap *
  page78_i165
#ISCELL
  mstr_standard tap *
  page78_i166
#ISCELL
  mstr_standard tap *
  page78_i167
#ISCELL
  mstr_standard tap *
  page78_i168
#ISCELL
  mstr_standard tap *
  page78_i169
#ISCELL
  mstr_standard offpage *
  page78_i17
#ISCELL
  mstr_standard tap *
  page78_i170
#ISCELL
  mstr_standard tap *
  page78_i171
#ISCELL
  mstr_standard tap *
  page78_i172
#ISCELL
  mstr_standard tap *
  page78_i173
#ISCELL
  mstr_standard tap *
  page78_i174
#ISCELL
  mstr_standard tap *
  page78_i175
#ISCELL
  mstr_standard tap *
  page78_i176
#ISCELL
  mstr_standard tap *
  page78_i177
#ISCELL
  mstr_standard tap *
  page78_i178
#ISCELL
  mstr_standard tap *
  page78_i179
#ISCELL
  mstr_standard offpage *
  page78_i18
#ISCELL
  mstr_standard tap *
  page78_i180
#ISCELL
  mstr_standard tap *
  page78_i181
#ISCELL
  mstr_standard tap *
  page78_i182
#ISCELL
  mstr_standard tap *
  page78_i183
#ISCELL
  mstr_standard tap *
  page78_i184
#ISCELL
  mstr_standard offpage *
  page78_i185
#ISCELL
  mstr_standard offpage *
  page78_i186
#ISCELL
  mstr_symbols p12v_nvdimm_ghj *
  page78_i187
#ISCELL
  mstr_standard offpage *
  page78_i19
#CELL
  dev_discrete cap_a *
  page78_i2
#ISCELL
  mstr_standard offpage *
  page78_i20
#ISCELL
  mstr_standard tap *
  page78_i21
#ISCELL
  mstr_standard tap *
  page78_i22
#ISCELL
  mstr_standard tap *
  page78_i23
#ISCELL
  mstr_standard tap *
  page78_i24
#ISCELL
  mstr_standard tap *
  page78_i25
#ISCELL
  mstr_standard tap *
  page78_i26
#ISCELL
  mstr_standard tap *
  page78_i27
#ISCELL
  mstr_standard tap *
  page78_i28
#ISCELL
  mstr_standard tap *
  page78_i29
#ISCELL
  mstr_symbols gnd *
  page78_i3
#ISCELL
  mstr_standard tap *
  page78_i30
#ISCELL
  mstr_standard tap *
  page78_i31
#ISCELL
  mstr_standard tap *
  page78_i32
#ISCELL
  mstr_standard tap *
  page78_i33
#ISCELL
  mstr_standard tap *
  page78_i34
#ISCELL
  mstr_standard tap *
  page78_i35
#ISCELL
  mstr_standard offpage *
  page78_i36
#ISCELL
  mstr_standard offpage *
  page78_i37
#ISCELL
  mstr_standard offpage *
  page78_i38
#ISCELL
  mstr_standard offpage *
  page78_i39
#ISCELL
  mstr_standard offpage *
  page78_i4
#ISCELL
  mstr_standard tap *
  page78_i40
#ISCELL
  mstr_standard tap *
  page78_i41
#ISCELL
  mstr_standard tap *
  page78_i42
#ISCELL
  mstr_standard tap *
  page78_i43
#ISCELL
  mstr_standard tap *
  page78_i44
#ISCELL
  mstr_standard tap *
  page78_i45
#ISCELL
  mstr_standard tap *
  page78_i46
#ISCELL
  mstr_standard tap *
  page78_i47
#ISCELL
  mstr_standard tap *
  page78_i48
#ISCELL
  mstr_standard tap *
  page78_i49
#ISCELL
  mstr_symbols pvpp_ghj *
  page78_i5
#ISCELL
  mstr_standard tap *
  page78_i50
#ISCELL
  mstr_standard tap *
  page78_i51
#ISCELL
  mstr_standard tap *
  page78_i52
#ISCELL
  mstr_standard tap *
  page78_i53
#ISCELL
  mstr_standard tap *
  page78_i54
#ISCELL
  mstr_standard tap *
  page78_i55
#ISCELL
  mstr_standard tap *
  page78_i56
#ISCELL
  mstr_standard tap *
  page78_i57
#ISCELL
  mstr_standard tap *
  page78_i58
#ISCELL
  mstr_standard tap *
  page78_i59
#ISCELL
  mstr_standard offpage *
  page78_i6
#ISCELL
  mstr_standard tap *
  page78_i60
#ISCELL
  mstr_standard tap *
  page78_i61
#ISCELL
  mstr_standard tap *
  page78_i62
#ISCELL
  mstr_standard tap *
  page78_i63
#ISCELL
  mstr_standard tap *
  page78_i64
#ISCELL
  mstr_standard tap *
  page78_i65
#ISCELL
  mstr_standard tap *
  page78_i66
#ISCELL
  mstr_standard tap *
  page78_i67
#ISCELL
  mstr_standard tap *
  page78_i68
#ISCELL
  mstr_standard tap *
  page78_i69
#ISCELL
  mstr_standard offpage *
  page78_i7
#ISCELL
  mstr_standard tap *
  page78_i70
#ISCELL
  mstr_standard tap *
  page78_i71
#ISCELL
  mstr_standard tap *
  page78_i72
#ISCELL
  mstr_standard tap *
  page78_i73
#ISCELL
  mstr_standard tap *
  page78_i74
#CELL
  mstr_sconn sconn288_h44441003 *
  page78_i75
#ISCELL
  mstr_standard tap *
  page78_i76
#ISCELL
  mstr_standard tap *
  page78_i77
#ISCELL
  mstr_standard tap *
  page78_i78
#ISCELL
  mstr_standard tap *
  page78_i79
#ISCELL
  mstr_standard offpage *
  page78_i8
#ISCELL
  mstr_standard tap *
  page78_i80
#ISCELL
  mstr_standard tap *
  page78_i81
#ISCELL
  mstr_standard tap *
  page78_i82
#ISCELL
  mstr_standard tap *
  page78_i83
#ISCELL
  mstr_standard tap *
  page78_i84
#ISCELL
  mstr_standard tap *
  page78_i85
#ISCELL
  mstr_standard tap *
  page78_i86
#ISCELL
  mstr_standard tap *
  page78_i87
#ISCELL
  mstr_standard tap *
  page78_i88
#ISCELL
  mstr_standard tap *
  page78_i89
#ISCELL
  mstr_standard offpage *
  page78_i9
#ISCELL
  mstr_standard tap *
  page78_i90
#ISCELL
  mstr_standard tap *
  page78_i91
#ISCELL
  mstr_standard tap *
  page78_i92
#ISCELL
  mstr_standard tap *
  page78_i93
#ISCELL
  mstr_standard tap *
  page78_i94
#ISCELL
  mstr_standard tap *
  page78_i95
#ISCELL
  mstr_symbols pvddq_ghj *
  page78_i96
#ISCELL
  mstr_symbols pvtt_ghj *
  page78_i97
#ISCELL
  mstr_standard tap *
  page78_i98
#ISCELL
  mstr_standard tap *
  page78_i99
#ISCELL
  mstr_symbols bom_note *
  *
#ISCELL
  mstr_symbols intel_corp_bpage *
  *
#ISCELL
  mstr_standard offpage *
  page79_i1
#ISCELL
  mstr_standard tap *
  page79_i10
#ISCELL
  mstr_standard tap *
  page79_i100
#ISCELL
  mstr_standard tap *
  page79_i101
#ISCELL
  mstr_standard tap *
  page79_i102
#ISCELL
  mstr_standard tap *
  page79_i103
#ISCELL
  mstr_standard tap *
  page79_i104
#ISCELL
  mstr_standard tap *
  page79_i105
#ISCELL
  mstr_standard tap *
  page79_i106
#ISCELL
  mstr_standard tap *
  page79_i107
#ISCELL
  mstr_standard tap *
  page79_i108
#ISCELL
  mstr_standard tap *
  page79_i109
#ISCELL
  mstr_standard tap *
  page79_i11
#ISCELL
  mstr_standard tap *
  page79_i110
#CELL
  mstr_sconn sconn288_h44441004 *
  page79_i111
#ISCELL
  mstr_standard tap *
  page79_i112
#ISCELL
  mstr_standard tap *
  page79_i113
#ISCELL
  mstr_standard tap *
  page79_i114
#ISCELL
  mstr_standard tap *
  page79_i115
#ISCELL
  mstr_standard tap *
  page79_i116
#ISCELL
  mstr_standard tap *
  page79_i117
#ISCELL
  mstr_standard tap *
  page79_i118
#ISCELL
  mstr_standard tap *
  page79_i119
#ISCELL
  mstr_standard tap *
  page79_i12
#ISCELL
  mstr_standard tap *
  page79_i120
#ISCELL
  mstr_standard tap *
  page79_i121
#ISCELL
  mstr_standard tap *
  page79_i122
#ISCELL
  mstr_standard tap *
  page79_i123
#ISCELL
  mstr_standard tap *
  page79_i124
#ISCELL
  mstr_standard tap *
  page79_i125
#ISCELL
  mstr_standard tap *
  page79_i126
#ISCELL
  mstr_standard tap *
  page79_i127
#ISCELL
  mstr_standard tap *
  page79_i128
#ISCELL
  mstr_standard tap *
  page79_i129
#ISCELL
  mstr_standard tap *
  page79_i13
#ISCELL
  mstr_standard offpage *
  page79_i130
#ISCELL
  mstr_standard tap *
  page79_i131
#ISCELL
  mstr_standard tap *
  page79_i132
#ISCELL
  mstr_standard tap *
  page79_i133
#ISCELL
  mstr_standard tap *
  page79_i134
#ISCELL
  mstr_standard offpage *
  page79_i135
#ISCELL
  mstr_standard offpage *
  page79_i136
#ISCELL
  mstr_standard offpage *
  page79_i137
#ISCELL
  mstr_standard tap *
  page79_i138
#ISCELL
  mstr_standard tap *
  page79_i139
#ISCELL
  mstr_symbols pvddq_ghj *
  page79_i14
#ISCELL
  mstr_standard tap *
  page79_i140
#ISCELL
  mstr_standard tap *
  page79_i141
#ISCELL
  mstr_standard tap *
  page79_i142
#ISCELL
  mstr_standard tap *
  page79_i143
#ISCELL
  mstr_standard tap *
  page79_i144
#ISCELL
  mstr_standard tap *
  page79_i145
#ISCELL
  mstr_standard offpage *
  page79_i146
#ISCELL
  mstr_standard offpage *
  page79_i147
#ISCELL
  mstr_standard offpage *
  page79_i148
#ISCELL
  mstr_standard offpage *
  page79_i149
#ISCELL
  mstr_standard offpage *
  page79_i150
#ISCELL
  mstr_standard tap *
  page79_i152
#ISCELL
  mstr_standard tap *
  page79_i153
#ISCELL
  mstr_standard tap *
  page79_i154
#ISCELL
  mstr_standard tap *
  page79_i155
#ISCELL
  mstr_standard offpage *
  page79_i156
#ISCELL
  mstr_standard offpage *
  page79_i157
#ISCELL
  mstr_standard tap *
  page79_i158
#ISCELL
  mstr_standard tap *
  page79_i159
#ISCELL
  mstr_symbols pvtt_ghj *
  page79_i16
#ISCELL
  mstr_standard tap *
  page79_i160
#ISCELL
  mstr_standard tap *
  page79_i161
#ISCELL
  mstr_standard tap *
  page79_i162
#ISCELL
  mstr_standard tap *
  page79_i163
#ISCELL
  mstr_standard tap *
  page79_i164
#ISCELL
  mstr_standard offpage *
  page79_i165
#ISCELL
  mstr_standard offpage *
  page79_i166
#ISCELL
  mstr_standard offpage *
  page79_i167
#ISCELL
  mstr_standard tap *
  page79_i168
#CELL
  mstr_sconn sconn288_h44441004 *
  page79_i169
#ISCELL
  mstr_standard tap *
  page79_i17
#ISCELL
  mstr_symbols gnd *
  page79_i170
#ISCELL
  mstr_standard offpage *
  page79_i171
#ISCELL
  mstr_standard offpage *
  page79_i172
#ISCELL
  mstr_standard offpage *
  page79_i173
#ISCELL
  mstr_symbols gnd *
  page79_i175
#ISCELL
  mstr_standard offpage *
  page79_i176
#ISCELL
  mstr_symbols gnd *
  page79_i177
#CELL
  dev_discrete cap_a *
  page79_i178
#ISCELL
  mstr_symbols pvpp_ghj *
  page79_i179
#ISCELL
  mstr_standard tap *
  page79_i18
#ISCELL
  mstr_symbols pvpp_ghj *
  page79_i180
#ISCELL
  mstr_standard offpage *
  page79_i181
#ISCELL
  mstr_standard tap *
  page79_i185
#ISCELL
  mstr_symbols p12v_nvdimm_ghj *
  page79_i186
#ISCELL
  mstr_standard tap *
  page79_i19
#ISCELL
  mstr_standard offpage *
  page79_i2
#ISCELL
  mstr_standard tap *
  page79_i20
#ISCELL
  mstr_standard tap *
  page79_i21
#ISCELL
  mstr_standard tap *
  page79_i22
#ISCELL
  mstr_standard tap *
  page79_i23
#ISCELL
  mstr_standard tap *
  page79_i24
#ISCELL
  mstr_standard tap *
  page79_i25
#ISCELL
  mstr_standard tap *
  page79_i26
#ISCELL
  mstr_standard tap *
  page79_i27
#ISCELL
  mstr_standard tap *
  page79_i28
#ISCELL
  mstr_standard tap *
  page79_i29
#ISCELL
  mstr_standard tap *
  page79_i3
#ISCELL
  mstr_standard tap *
  page79_i30
#ISCELL
  mstr_standard tap *
  page79_i31
#ISCELL
  mstr_standard tap *
  page79_i32
#ISCELL
  mstr_standard tap *
  page79_i33
#ISCELL
  mstr_standard tap *
  page79_i34
#ISCELL
  mstr_standard tap *
  page79_i35
#ISCELL
  mstr_standard tap *
  page79_i36
#ISCELL
  mstr_standard tap *
  page79_i37
#ISCELL
  mstr_standard tap *
  page79_i38
#ISCELL
  mstr_standard tap *
  page79_i39
#ISCELL
  mstr_standard tap *
  page79_i4
#ISCELL
  mstr_standard tap *
  page79_i40
#CELL
  mstr_sconn sconn288_h44441004 *
  page79_i43
#ISCELL
  mstr_symbols gnd *
  page79_i44
#ISCELL
  mstr_standard offpage *
  page79_i45
#ISCELL
  mstr_standard tap *
  page79_i46
#ISCELL
  mstr_standard tap *
  page79_i47
#ISCELL
  mstr_standard tap *
  page79_i48
#ISCELL
  mstr_standard tap *
  page79_i49
#ISCELL
  mstr_standard tap *
  page79_i5
#ISCELL
  mstr_standard tap *
  page79_i50
#ISCELL
  mstr_standard tap *
  page79_i51
#ISCELL
  mstr_standard tap *
  page79_i52
#ISCELL
  mstr_standard tap *
  page79_i53
#ISCELL
  mstr_standard tap *
  page79_i54
#ISCELL
  mstr_standard tap *
  page79_i55
#ISCELL
  mstr_standard tap *
  page79_i56
#ISCELL
  mstr_standard tap *
  page79_i57
#ISCELL
  mstr_standard tap *
  page79_i58
#ISCELL
  mstr_standard tap *
  page79_i59
#ISCELL
  mstr_standard tap *
  page79_i6
#ISCELL
  mstr_standard tap *
  page79_i60
#ISCELL
  mstr_standard tap *
  page79_i61
#ISCELL
  mstr_standard tap *
  page79_i62
#ISCELL
  mstr_standard tap *
  page79_i63
#CELL
  mstr_sconn sconn288_h44441004 *
  page79_i64
#ISCELL
  mstr_standard tap *
  page79_i65
#ISCELL
  mstr_standard tap *
  page79_i66
#ISCELL
  mstr_standard tap *
  page79_i67
#ISCELL
  mstr_standard tap *
  page79_i68
#ISCELL
  mstr_standard tap *
  page79_i69
#ISCELL
  mstr_standard tap *
  page79_i7
#ISCELL
  mstr_standard tap *
  page79_i70
#ISCELL
  mstr_standard tap *
  page79_i71
#ISCELL
  mstr_standard tap *
  page79_i72
#ISCELL
  mstr_standard tap *
  page79_i73
#ISCELL
  mstr_standard tap *
  page79_i74
#ISCELL
  mstr_standard tap *
  page79_i75
#ISCELL
  mstr_standard tap *
  page79_i76
#ISCELL
  mstr_standard tap *
  page79_i77
#ISCELL
  mstr_standard tap *
  page79_i78
#ISCELL
  mstr_standard tap *
  page79_i79
#ISCELL
  mstr_standard tap *
  page79_i8
#ISCELL
  mstr_standard tap *
  page79_i80
#ISCELL
  mstr_standard tap *
  page79_i81
#ISCELL
  mstr_standard tap *
  page79_i82
#ISCELL
  mstr_standard tap *
  page79_i83
#ISCELL
  mstr_standard tap *
  page79_i84
#ISCELL
  mstr_standard tap *
  page79_i85
#ISCELL
  mstr_standard tap *
  page79_i86
#ISCELL
  mstr_standard tap *
  page79_i87
#ISCELL
  mstr_standard tap *
  page79_i88
#ISCELL
  mstr_standard tap *
  page79_i89
#ISCELL
  mstr_standard tap *
  page79_i9
#ISCELL
  mstr_standard tap *
  page79_i90
#ISCELL
  mstr_standard tap *
  page79_i91
#ISCELL
  mstr_standard tap *
  page79_i92
#ISCELL
  mstr_standard tap *
  page79_i93
#ISCELL
  mstr_standard tap *
  page79_i94
#ISCELL
  mstr_standard tap *
  page79_i95
#ISCELL
  mstr_standard tap *
  page79_i96
#ISCELL
  mstr_standard tap *
  page79_i97
#ISCELL
  mstr_standard tap *
  page79_i98
#ISCELL
  mstr_standard tap *
  page79_i99
#ISCELL
  mstr_symbols bom_note *
  *
#ISCELL
  mstr_symbols intel_corp_bpage *
  *
#ISCELL
  mstr_symbols gnd *
  page80_i1
#ISCELL
  mstr_standard offpage *
  page80_i10
#ISCELL
  mstr_standard tap *
  page80_i100
#CELL
  mstr_sconn sconn288_h44441003 *
  page80_i101
#ISCELL
  mstr_standard tap *
  page80_i102
#ISCELL
  mstr_standard tap *
  page80_i103
#ISCELL
  mstr_standard tap *
  page80_i104
#ISCELL
  mstr_standard tap *
  page80_i105
#ISCELL
  mstr_standard tap *
  page80_i106
#ISCELL
  mstr_standard tap *
  page80_i107
#ISCELL
  mstr_standard tap *
  page80_i108
#ISCELL
  mstr_standard tap *
  page80_i109
#ISCELL
  mstr_standard offpage *
  page80_i11
#ISCELL
  mstr_standard tap *
  page80_i110
#ISCELL
  mstr_standard tap *
  page80_i111
#ISCELL
  mstr_standard tap *
  page80_i112
#ISCELL
  mstr_standard tap *
  page80_i113
#ISCELL
  mstr_standard tap *
  page80_i114
#ISCELL
  mstr_standard tap *
  page80_i115
#ISCELL
  mstr_standard tap *
  page80_i116
#ISCELL
  mstr_standard tap *
  page80_i117
#ISCELL
  mstr_standard tap *
  page80_i118
#ISCELL
  mstr_standard tap *
  page80_i119
#ISCELL
  mstr_standard offpage *
  page80_i12
#ISCELL
  mstr_standard tap *
  page80_i120
#ISCELL
  mstr_standard tap *
  page80_i121
#ISCELL
  mstr_standard tap *
  page80_i122
#ISCELL
  mstr_standard tap *
  page80_i123
#ISCELL
  mstr_standard tap *
  page80_i124
#ISCELL
  mstr_standard tap *
  page80_i125
#ISCELL
  mstr_standard tap *
  page80_i126
#ISCELL
  mstr_standard tap *
  page80_i127
#ISCELL
  mstr_standard tap *
  page80_i128
#ISCELL
  mstr_standard tap *
  page80_i129
#ISCELL
  mstr_standard offpage *
  page80_i13
#ISCELL
  mstr_standard tap *
  page80_i130
#ISCELL
  mstr_standard tap *
  page80_i131
#ISCELL
  mstr_standard tap *
  page80_i132
#ISCELL
  mstr_standard tap *
  page80_i133
#ISCELL
  mstr_standard tap *
  page80_i134
#ISCELL
  mstr_standard tap *
  page80_i135
#ISCELL
  mstr_standard offpage *
  page80_i136
#ISCELL
  mstr_symbols gnd *
  page80_i137
#CELL
  mstr_sconn sconn288_h44441003 *
  page80_i138
#ISCELL
  mstr_standard offpage *
  page80_i14
#ISCELL
  mstr_standard tap *
  page80_i142
#ISCELL
  mstr_standard tap *
  page80_i143
#ISCELL
  mstr_standard tap *
  page80_i144
#ISCELL
  mstr_standard tap *
  page80_i145
#ISCELL
  mstr_standard tap *
  page80_i146
#ISCELL
  mstr_standard tap *
  page80_i147
#ISCELL
  mstr_standard tap *
  page80_i148
#ISCELL
  mstr_standard tap *
  page80_i149
#ISCELL
  mstr_standard offpage *
  page80_i15
#ISCELL
  mstr_standard tap *
  page80_i150
#ISCELL
  mstr_standard tap *
  page80_i151
#ISCELL
  mstr_standard tap *
  page80_i152
#ISCELL
  mstr_standard tap *
  page80_i153
#ISCELL
  mstr_standard tap *
  page80_i154
#ISCELL
  mstr_standard tap *
  page80_i155
#ISCELL
  mstr_symbols gnd *
  page80_i156
#ISCELL
  mstr_standard tap *
  page80_i157
#ISCELL
  mstr_standard tap *
  page80_i158
#ISCELL
  mstr_standard tap *
  page80_i159
#ISCELL
  mstr_standard offpage *
  page80_i16
#ISCELL
  mstr_standard tap *
  page80_i160
#ISCELL
  mstr_standard tap *
  page80_i161
#ISCELL
  mstr_standard tap *
  page80_i162
#ISCELL
  mstr_standard tap *
  page80_i163
#ISCELL
  mstr_standard tap *
  page80_i164
#ISCELL
  mstr_standard tap *
  page80_i165
#ISCELL
  mstr_standard tap *
  page80_i166
#ISCELL
  mstr_standard tap *
  page80_i167
#ISCELL
  mstr_standard tap *
  page80_i168
#ISCELL
  mstr_standard tap *
  page80_i169
#ISCELL
  mstr_standard offpage *
  page80_i17
#ISCELL
  mstr_standard tap *
  page80_i170
#ISCELL
  mstr_standard tap *
  page80_i171
#ISCELL
  mstr_standard tap *
  page80_i172
#ISCELL
  mstr_standard tap *
  page80_i173
#ISCELL
  mstr_standard tap *
  page80_i174
#ISCELL
  mstr_standard tap *
  page80_i175
#ISCELL
  mstr_standard tap *
  page80_i176
#ISCELL
  mstr_standard tap *
  page80_i177
#ISCELL
  mstr_standard tap *
  page80_i178
#ISCELL
  mstr_standard offpage *
  page80_i179
#ISCELL
  mstr_standard offpage *
  page80_i18
#ISCELL
  mstr_standard offpage *
  page80_i180
#ISCELL
  mstr_symbols p12v_nvdimm_ghj *
  page80_i181
#ISCELL
  mstr_standard offpage *
  page80_i19
#ISCELL
  mstr_standard offpage *
  page80_i2
#ISCELL
  mstr_standard offpage *
  page80_i20
#ISCELL
  mstr_standard offpage *
  page80_i21
#ISCELL
  mstr_standard offpage *
  page80_i22
#ISCELL
  mstr_standard offpage *
  page80_i23
#CELL
  mstr_sconn sconn288_h44441003 *
  page80_i24
#ISCELL
  mstr_standard tap *
  page80_i25
#ISCELL
  mstr_standard tap *
  page80_i26
#ISCELL
  mstr_standard tap *
  page80_i27
#ISCELL
  mstr_standard tap *
  page80_i28
#ISCELL
  mstr_standard tap *
  page80_i29
#CELL
  dev_discrete cap_a *
  page80_i3
#ISCELL
  mstr_standard tap *
  page80_i30
#ISCELL
  mstr_standard tap *
  page80_i31
#ISCELL
  mstr_standard tap *
  page80_i32
#ISCELL
  mstr_standard tap *
  page80_i33
#ISCELL
  mstr_standard tap *
  page80_i34
#ISCELL
  mstr_standard tap *
  page80_i35
#ISCELL
  mstr_standard tap *
  page80_i36
#ISCELL
  mstr_standard tap *
  page80_i37
#ISCELL
  mstr_standard tap *
  page80_i38
#ISCELL
  mstr_standard tap *
  page80_i39
#ISCELL
  mstr_symbols gnd *
  page80_i4
#ISCELL
  mstr_standard tap *
  page80_i40
#ISCELL
  mstr_standard tap *
  page80_i41
#ISCELL
  mstr_standard tap *
  page80_i42
#ISCELL
  mstr_standard tap *
  page80_i43
#ISCELL
  mstr_standard tap *
  page80_i44
#ISCELL
  mstr_standard tap *
  page80_i45
#ISCELL
  mstr_standard tap *
  page80_i46
#ISCELL
  mstr_standard tap *
  page80_i47
#ISCELL
  mstr_standard tap *
  page80_i48
#ISCELL
  mstr_standard tap *
  page80_i49
#ISCELL
  mstr_standard offpage *
  page80_i5
#ISCELL
  mstr_standard tap *
  page80_i50
#ISCELL
  mstr_standard tap *
  page80_i51
#ISCELL
  mstr_standard tap *
  page80_i52
#ISCELL
  mstr_standard tap *
  page80_i53
#ISCELL
  mstr_standard tap *
  page80_i54
#ISCELL
  mstr_standard tap *
  page80_i55
#CELL
  mstr_sconn sconn288_h44441003 *
  page80_i56
#ISCELL
  mstr_standard tap *
  page80_i57
#ISCELL
  mstr_standard tap *
  page80_i58
#ISCELL
  mstr_standard tap *
  page80_i59
#ISCELL
  mstr_standard offpage *
  page80_i6
#ISCELL
  mstr_standard tap *
  page80_i60
#ISCELL
  mstr_standard tap *
  page80_i61
#ISCELL
  mstr_standard tap *
  page80_i62
#ISCELL
  mstr_standard tap *
  page80_i63
#ISCELL
  mstr_standard tap *
  page80_i64
#ISCELL
  mstr_standard tap *
  page80_i65
#ISCELL
  mstr_standard tap *
  page80_i66
#ISCELL
  mstr_standard tap *
  page80_i67
#ISCELL
  mstr_standard tap *
  page80_i68
#ISCELL
  mstr_standard tap *
  page80_i69
#ISCELL
  mstr_standard offpage *
  page80_i7
#ISCELL
  mstr_standard tap *
  page80_i70
#ISCELL
  mstr_standard tap *
  page80_i71
#ISCELL
  mstr_standard tap *
  page80_i72
#ISCELL
  mstr_standard tap *
  page80_i73
#ISCELL
  mstr_standard tap *
  page80_i74
#ISCELL
  mstr_standard tap *
  page80_i75
#ISCELL
  mstr_standard tap *
  page80_i76
#ISCELL
  mstr_standard tap *
  page80_i77
#ISCELL
  mstr_symbols pvddq_ghj *
  page80_i78
#ISCELL
  mstr_symbols pvtt_ghj *
  page80_i79
#ISCELL
  mstr_symbols pvpp_ghj *
  page80_i8
#ISCELL
  mstr_symbols pvpp_ghj *
  page80_i80
#ISCELL
  mstr_standard tap *
  page80_i81
#ISCELL
  mstr_standard tap *
  page80_i82
#ISCELL
  mstr_standard tap *
  page80_i83
#ISCELL
  mstr_standard tap *
  page80_i84
#ISCELL
  mstr_standard tap *
  page80_i85
#ISCELL
  mstr_standard tap *
  page80_i86
#ISCELL
  mstr_standard tap *
  page80_i87
#ISCELL
  mstr_standard tap *
  page80_i88
#ISCELL
  mstr_standard tap *
  page80_i89
#ISCELL
  mstr_standard offpage *
  page80_i9
#ISCELL
  mstr_standard tap *
  page80_i90
#ISCELL
  mstr_standard tap *
  page80_i91
#ISCELL
  mstr_standard tap *
  page80_i92
#ISCELL
  mstr_standard tap *
  page80_i93
#ISCELL
  mstr_standard tap *
  page80_i94
#ISCELL
  mstr_standard tap *
  page80_i95
#ISCELL
  mstr_standard tap *
  page80_i96
#ISCELL
  mstr_standard tap *
  page80_i97
#ISCELL
  mstr_standard tap *
  page80_i98
#ISCELL
  mstr_standard tap *
  page80_i99
#ISCELL
  mstr_symbols bom_note *
  *
#ISCELL
  mstr_symbols intel_corp_bpage *
  *
#ISCELL
  mstr_standard offpage *
  page81_i1
#ISCELL
  mstr_standard tap *
  page81_i10
#ISCELL
  mstr_standard tap *
  page81_i100
#ISCELL
  mstr_standard tap *
  page81_i101
#ISCELL
  mstr_standard tap *
  page81_i102
#ISCELL
  mstr_standard tap *
  page81_i103
#ISCELL
  mstr_standard tap *
  page81_i104
#ISCELL
  mstr_standard tap *
  page81_i105
#ISCELL
  mstr_standard tap *
  page81_i106
#ISCELL
  mstr_standard tap *
  page81_i107
#ISCELL
  mstr_standard tap *
  page81_i108
#ISCELL
  mstr_standard tap *
  page81_i109
#ISCELL
  mstr_standard tap *
  page81_i11
#ISCELL
  mstr_standard tap *
  page81_i110
#ISCELL
  mstr_standard tap *
  page81_i112
#ISCELL
  mstr_standard offpage *
  page81_i113
#ISCELL
  mstr_standard tap *
  page81_i114
#ISCELL
  mstr_standard tap *
  page81_i115
#ISCELL
  mstr_standard tap *
  page81_i116
#ISCELL
  mstr_standard tap *
  page81_i117
#ISCELL
  mstr_standard tap *
  page81_i118
#ISCELL
  mstr_standard tap *
  page81_i119
#ISCELL
  mstr_standard tap *
  page81_i12
#ISCELL
  mstr_standard tap *
  page81_i120
#ISCELL
  mstr_standard tap *
  page81_i121
#ISCELL
  mstr_standard tap *
  page81_i122
#ISCELL
  mstr_standard tap *
  page81_i123
#ISCELL
  mstr_standard tap *
  page81_i124
#ISCELL
  mstr_standard tap *
  page81_i125
#ISCELL
  mstr_standard tap *
  page81_i126
#ISCELL
  mstr_standard tap *
  page81_i127
#ISCELL
  mstr_standard tap *
  page81_i128
#ISCELL
  mstr_standard tap *
  page81_i129
#ISCELL
  mstr_standard tap *
  page81_i13
#ISCELL
  mstr_standard tap *
  page81_i130
#ISCELL
  mstr_standard tap *
  page81_i131
#ISCELL
  mstr_standard tap *
  page81_i132
#ISCELL
  mstr_standard offpage *
  page81_i133
#ISCELL
  mstr_standard tap *
  page81_i134
#ISCELL
  mstr_standard tap *
  page81_i135
#ISCELL
  mstr_standard offpage *
  page81_i136
#ISCELL
  mstr_standard tap *
  page81_i137
#ISCELL
  mstr_standard offpage *
  page81_i138
#ISCELL
  mstr_standard offpage *
  page81_i139
#ISCELL
  mstr_standard tap *
  page81_i14
#ISCELL
  mstr_standard tap *
  page81_i140
#ISCELL
  mstr_standard tap *
  page81_i141
#ISCELL
  mstr_standard tap *
  page81_i142
#ISCELL
  mstr_standard tap *
  page81_i143
#ISCELL
  mstr_standard tap *
  page81_i144
#ISCELL
  mstr_standard tap *
  page81_i145
#ISCELL
  mstr_standard tap *
  page81_i146
#ISCELL
  mstr_standard offpage *
  page81_i147
#ISCELL
  mstr_standard offpage *
  page81_i148
#ISCELL
  mstr_standard offpage *
  page81_i149
#ISCELL
  mstr_standard tap *
  page81_i15
#ISCELL
  mstr_standard offpage *
  page81_i150
#ISCELL
  mstr_standard tap *
  page81_i152
#ISCELL
  mstr_standard tap *
  page81_i153
#ISCELL
  mstr_standard tap *
  page81_i154
#ISCELL
  mstr_standard tap *
  page81_i155
#ISCELL
  mstr_standard offpage *
  page81_i156
#ISCELL
  mstr_standard offpage *
  page81_i157
#ISCELL
  mstr_standard tap *
  page81_i158
#ISCELL
  mstr_standard tap *
  page81_i159
#ISCELL
  mstr_standard tap *
  page81_i16
#ISCELL
  mstr_standard tap *
  page81_i160
#ISCELL
  mstr_standard tap *
  page81_i161
#ISCELL
  mstr_standard tap *
  page81_i162
#ISCELL
  mstr_standard tap *
  page81_i163
#ISCELL
  mstr_standard tap *
  page81_i164
#ISCELL
  mstr_standard offpage *
  page81_i165
#ISCELL
  mstr_standard offpage *
  page81_i166
#ISCELL
  mstr_standard offpage *
  page81_i167
#ISCELL
  mstr_standard tap *
  page81_i168
#CELL
  mstr_sconn sconn288_h44441004 *
  page81_i169
#ISCELL
  mstr_symbols pvddq_ghj *
  page81_i17
#ISCELL
  mstr_symbols gnd *
  page81_i170
#ISCELL
  mstr_standard offpage *
  page81_i171
#ISCELL
  mstr_standard offpage *
  page81_i172
#ISCELL
  mstr_standard offpage *
  page81_i173
#ISCELL
  mstr_symbols gnd *
  page81_i175
#ISCELL
  mstr_standard offpage *
  page81_i176
#ISCELL
  mstr_symbols gnd *
  page81_i177
#CELL
  dev_discrete cap_a *
  page81_i178
#ISCELL
  mstr_symbols pvpp_ghj *
  page81_i179
#ISCELL
  mstr_symbols pvtt_ghj *
  page81_i18
#ISCELL
  mstr_symbols pvpp_ghj *
  page81_i180
#ISCELL
  mstr_standard offpage *
  page81_i181
#CELL
  mstr_sconn sconn288_h44441004 *
  page81_i185
#CELL
  mstr_sconn sconn288_h44441004 *
  page81_i186
#ISCELL
  mstr_symbols p12v_nvdimm_ghj *
  page81_i187
#ISCELL
  mstr_standard offpage *
  page81_i2
#ISCELL
  mstr_standard tap *
  page81_i20
#ISCELL
  mstr_standard tap *
  page81_i21
#ISCELL
  mstr_standard tap *
  page81_i22
#ISCELL
  mstr_standard tap *
  page81_i23
#ISCELL
  mstr_standard tap *
  page81_i24
#ISCELL
  mstr_standard tap *
  page81_i25
#ISCELL
  mstr_standard tap *
  page81_i26
#ISCELL
  mstr_standard tap *
  page81_i27
#ISCELL
  mstr_standard tap *
  page81_i28
#ISCELL
  mstr_standard tap *
  page81_i29
#ISCELL
  mstr_standard tap *
  page81_i3
#ISCELL
  mstr_standard tap *
  page81_i30
#ISCELL
  mstr_standard tap *
  page81_i31
#ISCELL
  mstr_standard tap *
  page81_i32
#ISCELL
  mstr_standard tap *
  page81_i33
#ISCELL
  mstr_standard tap *
  page81_i34
#ISCELL
  mstr_standard tap *
  page81_i35
#ISCELL
  mstr_standard tap *
  page81_i36
#ISCELL
  mstr_standard tap *
  page81_i37
#ISCELL
  mstr_standard tap *
  page81_i38
#ISCELL
  mstr_standard tap *
  page81_i39
#ISCELL
  mstr_standard tap *
  page81_i4
#ISCELL
  mstr_standard tap *
  page81_i40
#ISCELL
  mstr_standard tap *
  page81_i41
#ISCELL
  mstr_symbols gnd *
  page81_i44
#ISCELL
  mstr_standard offpage *
  page81_i45
#ISCELL
  mstr_standard tap *
  page81_i46
#ISCELL
  mstr_standard tap *
  page81_i47
#ISCELL
  mstr_standard tap *
  page81_i48
#ISCELL
  mstr_standard tap *
  page81_i49
#ISCELL
  mstr_standard tap *
  page81_i5
#ISCELL
  mstr_standard tap *
  page81_i50
#ISCELL
  mstr_standard tap *
  page81_i51
#ISCELL
  mstr_standard tap *
  page81_i52
#ISCELL
  mstr_standard tap *
  page81_i53
#ISCELL
  mstr_standard tap *
  page81_i54
#ISCELL
  mstr_standard tap *
  page81_i55
#ISCELL
  mstr_standard tap *
  page81_i56
#ISCELL
  mstr_standard tap *
  page81_i57
#ISCELL
  mstr_standard tap *
  page81_i58
#ISCELL
  mstr_standard tap *
  page81_i59
#ISCELL
  mstr_standard tap *
  page81_i6
#ISCELL
  mstr_standard tap *
  page81_i60
#ISCELL
  mstr_standard tap *
  page81_i61
#ISCELL
  mstr_standard tap *
  page81_i62
#ISCELL
  mstr_standard tap *
  page81_i63
#ISCELL
  mstr_standard tap *
  page81_i64
#ISCELL
  mstr_standard tap *
  page81_i65
#ISCELL
  mstr_standard tap *
  page81_i66
#CELL
  mstr_sconn sconn288_h44441004 *
  page81_i67
#ISCELL
  mstr_standard tap *
  page81_i68
#ISCELL
  mstr_standard tap *
  page81_i69
#ISCELL
  mstr_standard tap *
  page81_i7
#ISCELL
  mstr_standard tap *
  page81_i70
#ISCELL
  mstr_standard tap *
  page81_i71
#ISCELL
  mstr_standard tap *
  page81_i72
#ISCELL
  mstr_standard tap *
  page81_i73
#ISCELL
  mstr_standard tap *
  page81_i74
#ISCELL
  mstr_standard tap *
  page81_i75
#ISCELL
  mstr_standard tap *
  page81_i76
#ISCELL
  mstr_standard tap *
  page81_i77
#ISCELL
  mstr_standard tap *
  page81_i78
#ISCELL
  mstr_standard tap *
  page81_i79
#ISCELL
  mstr_standard tap *
  page81_i8
#ISCELL
  mstr_standard tap *
  page81_i80
#ISCELL
  mstr_standard tap *
  page81_i81
#ISCELL
  mstr_standard tap *
  page81_i82
#ISCELL
  mstr_standard tap *
  page81_i83
#ISCELL
  mstr_standard tap *
  page81_i84
#ISCELL
  mstr_standard tap *
  page81_i85
#ISCELL
  mstr_standard tap *
  page81_i86
#ISCELL
  mstr_standard tap *
  page81_i87
#ISCELL
  mstr_standard tap *
  page81_i88
#ISCELL
  mstr_standard tap *
  page81_i89
#ISCELL
  mstr_standard tap *
  page81_i9
#ISCELL
  mstr_standard tap *
  page81_i90
#ISCELL
  mstr_standard tap *
  page81_i91
#ISCELL
  mstr_standard tap *
  page81_i92
#ISCELL
  mstr_standard tap *
  page81_i93
#ISCELL
  mstr_standard tap *
  page81_i94
#ISCELL
  mstr_standard tap *
  page81_i95
#ISCELL
  mstr_standard tap *
  page81_i96
#ISCELL
  mstr_standard tap *
  page81_i97
#ISCELL
  mstr_standard tap *
  page81_i98
#ISCELL
  mstr_standard tap *
  page81_i99
#ISCELL
  mstr_symbols bom_note *
  *
#ISCELL
  mstr_symbols intel_corp_bpage *
  *
#ISCELL
  mstr_standard offpage *
  page82_i1
#ISCELL
  mstr_standard tap *
  page82_i10
#ISCELL
  mstr_standard tap *
  page82_i100
#ISCELL
  mstr_standard tap *
  page82_i101
#ISCELL
  mstr_standard tap *
  page82_i102
#ISCELL
  mstr_standard tap *
  page82_i103
#ISCELL
  mstr_standard tap *
  page82_i104
#ISCELL
  mstr_standard tap *
  page82_i105
#ISCELL
  mstr_standard tap *
  page82_i106
#ISCELL
  mstr_standard tap *
  page82_i107
#ISCELL
  mstr_standard tap *
  page82_i108
#ISCELL
  mstr_standard tap *
  page82_i109
#ISCELL
  mstr_standard tap *
  page82_i11
#ISCELL
  mstr_standard tap *
  page82_i110
#ISCELL
  mstr_standard tap *
  page82_i112
#ISCELL
  mstr_standard tap *
  page82_i113
#ISCELL
  mstr_standard tap *
  page82_i114
#ISCELL
  mstr_standard tap *
  page82_i115
#ISCELL
  mstr_standard tap *
  page82_i116
#ISCELL
  mstr_standard tap *
  page82_i117
#ISCELL
  mstr_standard tap *
  page82_i118
#ISCELL
  mstr_standard tap *
  page82_i119
#ISCELL
  mstr_standard tap *
  page82_i12
#ISCELL
  mstr_standard tap *
  page82_i120
#ISCELL
  mstr_standard tap *
  page82_i121
#ISCELL
  mstr_standard tap *
  page82_i122
#ISCELL
  mstr_standard tap *
  page82_i123
#ISCELL
  mstr_standard tap *
  page82_i124
#ISCELL
  mstr_standard tap *
  page82_i125
#ISCELL
  mstr_standard tap *
  page82_i126
#ISCELL
  mstr_standard tap *
  page82_i127
#ISCELL
  mstr_standard tap *
  page82_i128
#ISCELL
  mstr_standard tap *
  page82_i129
#ISCELL
  mstr_standard tap *
  page82_i13
#ISCELL
  mstr_standard offpage *
  page82_i130
#ISCELL
  mstr_standard tap *
  page82_i131
#ISCELL
  mstr_standard tap *
  page82_i132
#ISCELL
  mstr_standard tap *
  page82_i133
#ISCELL
  mstr_standard tap *
  page82_i134
#ISCELL
  mstr_standard offpage *
  page82_i135
#ISCELL
  mstr_standard offpage *
  page82_i136
#ISCELL
  mstr_standard offpage *
  page82_i137
#ISCELL
  mstr_standard tap *
  page82_i138
#ISCELL
  mstr_standard tap *
  page82_i139
#ISCELL
  mstr_symbols pvddq_ghj *
  page82_i14
#ISCELL
  mstr_standard tap *
  page82_i140
#ISCELL
  mstr_standard tap *
  page82_i141
#ISCELL
  mstr_standard tap *
  page82_i142
#ISCELL
  mstr_standard tap *
  page82_i143
#ISCELL
  mstr_standard tap *
  page82_i144
#ISCELL
  mstr_standard tap *
  page82_i145
#ISCELL
  mstr_standard offpage *
  page82_i146
#ISCELL
  mstr_standard offpage *
  page82_i147
#ISCELL
  mstr_standard offpage *
  page82_i148
#ISCELL
  mstr_standard offpage *
  page82_i149
#ISCELL
  mstr_standard offpage *
  page82_i150
#ISCELL
  mstr_standard tap *
  page82_i152
#ISCELL
  mstr_standard tap *
  page82_i153
#ISCELL
  mstr_standard tap *
  page82_i154
#ISCELL
  mstr_standard tap *
  page82_i155
#ISCELL
  mstr_standard offpage *
  page82_i156
#ISCELL
  mstr_standard offpage *
  page82_i157
#ISCELL
  mstr_standard tap *
  page82_i158
#ISCELL
  mstr_standard tap *
  page82_i159
#ISCELL
  mstr_symbols pvtt_ghj *
  page82_i16
#ISCELL
  mstr_standard tap *
  page82_i160
#ISCELL
  mstr_standard tap *
  page82_i161
#ISCELL
  mstr_standard tap *
  page82_i162
#ISCELL
  mstr_standard offpage *
  page82_i163
#ISCELL
  mstr_standard offpage *
  page82_i164
#ISCELL
  mstr_standard tap *
  page82_i165
#ISCELL
  mstr_standard tap *
  page82_i166
#ISCELL
  mstr_standard offpage *
  page82_i167
#ISCELL
  mstr_standard tap *
  page82_i168
#ISCELL
  mstr_standard tap *
  page82_i17
#CELL
  mstr_sconn sconn288_h44441003 *
  page82_i171
#ISCELL
  mstr_symbols gnd *
  page82_i172
#ISCELL
  mstr_standard offpage *
  page82_i173
#ISCELL
  mstr_standard offpage *
  page82_i174
#ISCELL
  mstr_standard offpage *
  page82_i175
#ISCELL
  mstr_standard offpage *
  page82_i178
#ISCELL
  mstr_symbols gnd *
  page82_i179
#ISCELL
  mstr_standard tap *
  page82_i18
#CELL
  dev_discrete cap_a *
  page82_i180
#ISCELL
  mstr_symbols pvpp_ghj *
  page82_i181
#ISCELL
  mstr_symbols pvpp_ghj *
  page82_i182
#ISCELL
  mstr_standard offpage *
  page82_i183
#CELL
  mstr_sconn sconn288_h44441003 *
  page82_i187
#CELL
  mstr_sconn sconn288_h44441003 *
  page82_i188
#ISCELL
  mstr_symbols gnd *
  page82_i189
#ISCELL
  mstr_standard tap *
  page82_i19
#ISCELL
  mstr_symbols p12v_nvdimm_ghj *
  page82_i190
#ISCELL
  mstr_standard offpage *
  page82_i2
#ISCELL
  mstr_standard tap *
  page82_i20
#ISCELL
  mstr_standard tap *
  page82_i21
#ISCELL
  mstr_standard tap *
  page82_i22
#ISCELL
  mstr_standard tap *
  page82_i23
#ISCELL
  mstr_standard tap *
  page82_i24
#ISCELL
  mstr_standard tap *
  page82_i25
#ISCELL
  mstr_standard tap *
  page82_i26
#ISCELL
  mstr_standard tap *
  page82_i27
#ISCELL
  mstr_standard tap *
  page82_i28
#ISCELL
  mstr_standard tap *
  page82_i29
#ISCELL
  mstr_standard tap *
  page82_i3
#ISCELL
  mstr_standard tap *
  page82_i30
#ISCELL
  mstr_standard tap *
  page82_i31
#ISCELL
  mstr_standard tap *
  page82_i32
#ISCELL
  mstr_standard tap *
  page82_i33
#ISCELL
  mstr_standard tap *
  page82_i34
#ISCELL
  mstr_standard tap *
  page82_i35
#ISCELL
  mstr_standard tap *
  page82_i36
#ISCELL
  mstr_standard tap *
  page82_i37
#ISCELL
  mstr_standard tap *
  page82_i38
#ISCELL
  mstr_standard tap *
  page82_i39
#ISCELL
  mstr_standard tap *
  page82_i4
#ISCELL
  mstr_standard tap *
  page82_i40
#ISCELL
  mstr_standard tap *
  page82_i41
#ISCELL
  mstr_symbols gnd *
  page82_i44
#ISCELL
  mstr_standard offpage *
  page82_i45
#ISCELL
  mstr_standard tap *
  page82_i46
#ISCELL
  mstr_standard tap *
  page82_i47
#ISCELL
  mstr_standard tap *
  page82_i48
#ISCELL
  mstr_standard tap *
  page82_i49
#ISCELL
  mstr_standard tap *
  page82_i5
#ISCELL
  mstr_standard tap *
  page82_i50
#ISCELL
  mstr_standard tap *
  page82_i51
#ISCELL
  mstr_standard tap *
  page82_i52
#ISCELL
  mstr_standard tap *
  page82_i53
#ISCELL
  mstr_standard tap *
  page82_i54
#ISCELL
  mstr_standard tap *
  page82_i55
#ISCELL
  mstr_standard tap *
  page82_i56
#ISCELL
  mstr_standard tap *
  page82_i57
#ISCELL
  mstr_standard tap *
  page82_i58
#ISCELL
  mstr_standard tap *
  page82_i59
#ISCELL
  mstr_standard tap *
  page82_i6
#ISCELL
  mstr_standard tap *
  page82_i60
#ISCELL
  mstr_standard tap *
  page82_i61
#ISCELL
  mstr_standard tap *
  page82_i62
#ISCELL
  mstr_standard tap *
  page82_i63
#CELL
  mstr_sconn sconn288_h44441003 *
  page82_i64
#ISCELL
  mstr_standard tap *
  page82_i65
#ISCELL
  mstr_standard tap *
  page82_i66
#ISCELL
  mstr_standard tap *
  page82_i67
#ISCELL
  mstr_standard tap *
  page82_i68
#ISCELL
  mstr_standard tap *
  page82_i69
#ISCELL
  mstr_standard tap *
  page82_i7
#ISCELL
  mstr_standard tap *
  page82_i70
#ISCELL
  mstr_standard tap *
  page82_i71
#ISCELL
  mstr_standard tap *
  page82_i72
#ISCELL
  mstr_standard tap *
  page82_i73
#ISCELL
  mstr_standard tap *
  page82_i74
#ISCELL
  mstr_standard tap *
  page82_i75
#ISCELL
  mstr_standard tap *
  page82_i76
#ISCELL
  mstr_standard tap *
  page82_i77
#ISCELL
  mstr_standard tap *
  page82_i78
#ISCELL
  mstr_standard tap *
  page82_i79
#ISCELL
  mstr_standard tap *
  page82_i8
#ISCELL
  mstr_standard tap *
  page82_i80
#ISCELL
  mstr_standard tap *
  page82_i81
#ISCELL
  mstr_standard tap *
  page82_i82
#ISCELL
  mstr_standard tap *
  page82_i83
#ISCELL
  mstr_standard tap *
  page82_i84
#ISCELL
  mstr_standard tap *
  page82_i85
#ISCELL
  mstr_standard tap *
  page82_i86
#ISCELL
  mstr_standard tap *
  page82_i87
#ISCELL
  mstr_standard tap *
  page82_i88
#ISCELL
  mstr_standard tap *
  page82_i89
#ISCELL
  mstr_standard tap *
  page82_i9
#ISCELL
  mstr_standard tap *
  page82_i90
#ISCELL
  mstr_standard tap *
  page82_i91
#ISCELL
  mstr_standard tap *
  page82_i92
#ISCELL
  mstr_standard tap *
  page82_i93
#ISCELL
  mstr_standard tap *
  page82_i94
#ISCELL
  mstr_standard tap *
  page82_i95
#ISCELL
  mstr_standard tap *
  page82_i96
#ISCELL
  mstr_standard tap *
  page82_i97
#ISCELL
  mstr_standard tap *
  page82_i98
#ISCELL
  mstr_standard tap *
  page82_i99
#ISCELL
  mstr_symbols bom_note *
  *
#ISCELL
  mstr_symbols intel_corp_bpage *
  *
#ISCELL
  mstr_standard offpage *
  page83_i1
#ISCELL
  mstr_standard tap *
  page83_i10
#ISCELL
  mstr_standard tap *
  page83_i100
#ISCELL
  mstr_standard tap *
  page83_i101
#ISCELL
  mstr_standard tap *
  page83_i102
#ISCELL
  mstr_standard tap *
  page83_i103
#ISCELL
  mstr_standard tap *
  page83_i104
#ISCELL
  mstr_standard tap *
  page83_i105
#ISCELL
  mstr_standard tap *
  page83_i106
#ISCELL
  mstr_standard tap *
  page83_i107
#ISCELL
  mstr_standard tap *
  page83_i108
#ISCELL
  mstr_standard tap *
  page83_i109
#ISCELL
  mstr_standard tap *
  page83_i11
#ISCELL
  mstr_standard tap *
  page83_i110
#CELL
  mstr_sconn sconn288_h44441004 *
  page83_i111
#ISCELL
  mstr_standard tap *
  page83_i112
#ISCELL
  mstr_standard tap *
  page83_i113
#ISCELL
  mstr_standard tap *
  page83_i114
#ISCELL
  mstr_standard tap *
  page83_i115
#ISCELL
  mstr_standard tap *
  page83_i116
#ISCELL
  mstr_standard tap *
  page83_i117
#ISCELL
  mstr_standard tap *
  page83_i118
#ISCELL
  mstr_standard tap *
  page83_i119
#ISCELL
  mstr_standard tap *
  page83_i12
#ISCELL
  mstr_standard tap *
  page83_i120
#ISCELL
  mstr_standard tap *
  page83_i121
#ISCELL
  mstr_standard tap *
  page83_i122
#ISCELL
  mstr_standard tap *
  page83_i123
#ISCELL
  mstr_standard tap *
  page83_i124
#ISCELL
  mstr_standard tap *
  page83_i125
#ISCELL
  mstr_standard tap *
  page83_i126
#ISCELL
  mstr_standard tap *
  page83_i127
#ISCELL
  mstr_standard tap *
  page83_i128
#ISCELL
  mstr_standard tap *
  page83_i129
#ISCELL
  mstr_standard tap *
  page83_i13
#ISCELL
  mstr_standard tap *
  page83_i130
#ISCELL
  mstr_standard offpage *
  page83_i131
#ISCELL
  mstr_standard offpage *
  page83_i132
#ISCELL
  mstr_standard tap *
  page83_i133
#ISCELL
  mstr_standard tap *
  page83_i134
#ISCELL
  mstr_standard tap *
  page83_i135
#ISCELL
  mstr_standard offpage *
  page83_i136
#ISCELL
  mstr_standard offpage *
  page83_i137
#ISCELL
  mstr_standard tap *
  page83_i138
#ISCELL
  mstr_standard tap *
  page83_i139
#ISCELL
  mstr_standard tap *
  page83_i14
#ISCELL
  mstr_standard tap *
  page83_i140
#ISCELL
  mstr_standard tap *
  page83_i141
#ISCELL
  mstr_standard tap *
  page83_i142
#ISCELL
  mstr_standard tap *
  page83_i143
#ISCELL
  mstr_standard tap *
  page83_i144
#ISCELL
  mstr_standard tap *
  page83_i145
#ISCELL
  mstr_standard offpage *
  page83_i146
#ISCELL
  mstr_standard offpage *
  page83_i147
#ISCELL
  mstr_standard offpage *
  page83_i148
#ISCELL
  mstr_standard offpage *
  page83_i149
#ISCELL
  mstr_standard tap *
  page83_i15
#ISCELL
  mstr_standard offpage *
  page83_i150
#ISCELL
  mstr_standard tap *
  page83_i152
#ISCELL
  mstr_standard tap *
  page83_i153
#ISCELL
  mstr_standard tap *
  page83_i154
#ISCELL
  mstr_standard tap *
  page83_i155
#ISCELL
  mstr_standard tap *
  page83_i156
#ISCELL
  mstr_standard offpage *
  page83_i157
#ISCELL
  mstr_standard offpage *
  page83_i158
#ISCELL
  mstr_standard tap *
  page83_i159
#ISCELL
  mstr_symbols pvddq_klm *
  page83_i16
#ISCELL
  mstr_standard offpage *
  page83_i160
#ISCELL
  mstr_standard offpage *
  page83_i161
#ISCELL
  mstr_standard offpage *
  page83_i162
#ISCELL
  mstr_standard tap *
  page83_i163
#ISCELL
  mstr_standard tap *
  page83_i164
#ISCELL
  mstr_standard tap *
  page83_i165
#ISCELL
  mstr_standard tap *
  page83_i166
#CELL
  mstr_sconn sconn288_h44441004 *
  page83_i167
#ISCELL
  mstr_symbols gnd *
  page83_i168
#ISCELL
  mstr_standard offpage *
  page83_i169
#ISCELL
  mstr_symbols pvtt_klm *
  page83_i17
#ISCELL
  mstr_standard offpage *
  page83_i170
#ISCELL
  mstr_standard offpage *
  page83_i171
#ISCELL
  mstr_symbols gnd *
  page83_i173
#ISCELL
  mstr_standard offpage *
  page83_i174
#ISCELL
  mstr_symbols gnd *
  page83_i175
#CELL
  dev_discrete cap_a *
  page83_i176
#ISCELL
  mstr_symbols pvpp_klm *
  page83_i177
#ISCELL
  mstr_symbols pvpp_klm *
  page83_i178
#ISCELL
  mstr_standard offpage *
  page83_i179
#ISCELL
  mstr_standard tap *
  page83_i183
#ISCELL
  mstr_standard tap *
  page83_i184
#ISCELL
  mstr_symbols p12v_nvdimm_klm *
  page83_i185
#ISCELL
  mstr_standard tap *
  page83_i19
#ISCELL
  mstr_standard offpage *
  page83_i2
#ISCELL
  mstr_standard tap *
  page83_i20
#ISCELL
  mstr_standard tap *
  page83_i21
#ISCELL
  mstr_standard tap *
  page83_i22
#ISCELL
  mstr_standard tap *
  page83_i23
#ISCELL
  mstr_standard tap *
  page83_i24
#ISCELL
  mstr_standard tap *
  page83_i25
#ISCELL
  mstr_standard tap *
  page83_i26
#ISCELL
  mstr_standard tap *
  page83_i27
#ISCELL
  mstr_standard tap *
  page83_i28
#ISCELL
  mstr_standard tap *
  page83_i29
#ISCELL
  mstr_standard tap *
  page83_i3
#ISCELL
  mstr_standard tap *
  page83_i30
#ISCELL
  mstr_standard tap *
  page83_i31
#ISCELL
  mstr_standard tap *
  page83_i32
#ISCELL
  mstr_standard tap *
  page83_i33
#ISCELL
  mstr_standard tap *
  page83_i34
#ISCELL
  mstr_standard tap *
  page83_i35
#ISCELL
  mstr_standard tap *
  page83_i36
#ISCELL
  mstr_standard tap *
  page83_i37
#ISCELL
  mstr_standard tap *
  page83_i38
#ISCELL
  mstr_standard tap *
  page83_i39
#ISCELL
  mstr_standard tap *
  page83_i4
#ISCELL
  mstr_standard tap *
  page83_i40
#ISCELL
  mstr_standard tap *
  page83_i41
#CELL
  mstr_sconn sconn288_h44441004 *
  page83_i43
#ISCELL
  mstr_symbols gnd *
  page83_i44
#ISCELL
  mstr_standard offpage *
  page83_i45
#ISCELL
  mstr_standard tap *
  page83_i46
#ISCELL
  mstr_standard tap *
  page83_i47
#ISCELL
  mstr_standard tap *
  page83_i48
#ISCELL
  mstr_standard tap *
  page83_i49
#ISCELL
  mstr_standard tap *
  page83_i5
#ISCELL
  mstr_standard tap *
  page83_i50
#ISCELL
  mstr_standard tap *
  page83_i51
#ISCELL
  mstr_standard tap *
  page83_i52
#ISCELL
  mstr_standard tap *
  page83_i53
#ISCELL
  mstr_standard tap *
  page83_i54
#ISCELL
  mstr_standard tap *
  page83_i55
#ISCELL
  mstr_standard tap *
  page83_i56
#ISCELL
  mstr_standard tap *
  page83_i57
#ISCELL
  mstr_standard tap *
  page83_i58
#ISCELL
  mstr_standard tap *
  page83_i59
#ISCELL
  mstr_standard tap *
  page83_i6
#ISCELL
  mstr_standard tap *
  page83_i60
#ISCELL
  mstr_standard tap *
  page83_i61
#ISCELL
  mstr_standard tap *
  page83_i62
#ISCELL
  mstr_standard tap *
  page83_i63
#ISCELL
  mstr_standard tap *
  page83_i64
#ISCELL
  mstr_standard tap *
  page83_i65
#CELL
  mstr_sconn sconn288_h44441004 *
  page83_i66
#ISCELL
  mstr_standard tap *
  page83_i67
#ISCELL
  mstr_standard tap *
  page83_i68
#ISCELL
  mstr_standard tap *
  page83_i69
#ISCELL
  mstr_standard tap *
  page83_i7
#ISCELL
  mstr_standard tap *
  page83_i70
#ISCELL
  mstr_standard tap *
  page83_i71
#ISCELL
  mstr_standard tap *
  page83_i72
#ISCELL
  mstr_standard tap *
  page83_i73
#ISCELL
  mstr_standard tap *
  page83_i74
#ISCELL
  mstr_standard tap *
  page83_i75
#ISCELL
  mstr_standard tap *
  page83_i76
#ISCELL
  mstr_standard tap *
  page83_i77
#ISCELL
  mstr_standard tap *
  page83_i78
#ISCELL
  mstr_standard tap *
  page83_i79
#ISCELL
  mstr_standard tap *
  page83_i8
#ISCELL
  mstr_standard tap *
  page83_i80
#ISCELL
  mstr_standard tap *
  page83_i81
#ISCELL
  mstr_standard tap *
  page83_i82
#ISCELL
  mstr_standard tap *
  page83_i83
#ISCELL
  mstr_standard tap *
  page83_i84
#ISCELL
  mstr_standard tap *
  page83_i85
#ISCELL
  mstr_standard tap *
  page83_i86
#ISCELL
  mstr_standard tap *
  page83_i87
#ISCELL
  mstr_standard tap *
  page83_i88
#ISCELL
  mstr_standard tap *
  page83_i89
#ISCELL
  mstr_standard tap *
  page83_i9
#ISCELL
  mstr_standard tap *
  page83_i90
#ISCELL
  mstr_standard tap *
  page83_i91
#ISCELL
  mstr_standard tap *
  page83_i92
#ISCELL
  mstr_standard tap *
  page83_i93
#ISCELL
  mstr_standard tap *
  page83_i94
#ISCELL
  mstr_standard tap *
  page83_i95
#ISCELL
  mstr_standard tap *
  page83_i96
#ISCELL
  mstr_standard tap *
  page83_i97
#ISCELL
  mstr_standard tap *
  page83_i98
#ISCELL
  mstr_standard tap *
  page83_i99
#ISCELL
  mstr_symbols bom_note *
  *
#ISCELL
  mstr_symbols intel_corp_bpage *
  *
#ISCELL
  mstr_symbols gnd *
  page84_i1
#ISCELL
  mstr_standard offpage *
  page84_i10
#ISCELL
  mstr_symbols pvtt_klm *
  page84_i100
#ISCELL
  mstr_symbols pvpp_klm *
  page84_i101
#CELL
  mstr_sconn sconn288_h44441003 *
  page84_i102
#ISCELL
  mstr_standard offpage *
  page84_i103
#ISCELL
  mstr_standard tap *
  page84_i104
#ISCELL
  mstr_standard tap *
  page84_i105
#ISCELL
  mstr_standard tap *
  page84_i106
#ISCELL
  mstr_standard tap *
  page84_i107
#ISCELL
  mstr_standard tap *
  page84_i108
#ISCELL
  mstr_standard tap *
  page84_i109
#ISCELL
  mstr_standard offpage *
  page84_i11
#ISCELL
  mstr_standard tap *
  page84_i110
#ISCELL
  mstr_standard tap *
  page84_i111
#ISCELL
  mstr_standard tap *
  page84_i112
#ISCELL
  mstr_standard tap *
  page84_i113
#ISCELL
  mstr_standard tap *
  page84_i114
#ISCELL
  mstr_standard tap *
  page84_i115
#ISCELL
  mstr_standard tap *
  page84_i116
#ISCELL
  mstr_standard tap *
  page84_i117
#ISCELL
  mstr_standard tap *
  page84_i118
#ISCELL
  mstr_standard tap *
  page84_i119
#ISCELL
  mstr_standard offpage *
  page84_i12
#ISCELL
  mstr_standard tap *
  page84_i120
#ISCELL
  mstr_standard tap *
  page84_i121
#ISCELL
  mstr_standard tap *
  page84_i122
#ISCELL
  mstr_standard tap *
  page84_i123
#ISCELL
  mstr_standard tap *
  page84_i124
#ISCELL
  mstr_standard tap *
  page84_i125
#ISCELL
  mstr_standard tap *
  page84_i126
#ISCELL
  mstr_standard tap *
  page84_i127
#ISCELL
  mstr_standard tap *
  page84_i128
#ISCELL
  mstr_standard tap *
  page84_i129
#ISCELL
  mstr_standard offpage *
  page84_i13
#ISCELL
  mstr_standard tap *
  page84_i130
#ISCELL
  mstr_standard tap *
  page84_i131
#ISCELL
  mstr_standard tap *
  page84_i132
#ISCELL
  mstr_standard tap *
  page84_i133
#ISCELL
  mstr_standard tap *
  page84_i134
#ISCELL
  mstr_standard tap *
  page84_i135
#ISCELL
  mstr_standard offpage *
  page84_i136
#ISCELL
  mstr_symbols gnd *
  page84_i137
#CELL
  mstr_sconn sconn288_h44441003 *
  page84_i138
#CELL
  mstr_sconn sconn288_h44441003 *
  page84_i14
#ISCELL
  mstr_standard tap *
  page84_i142
#ISCELL
  mstr_standard tap *
  page84_i143
#ISCELL
  mstr_standard tap *
  page84_i144
#ISCELL
  mstr_standard tap *
  page84_i145
#ISCELL
  mstr_standard tap *
  page84_i146
#ISCELL
  mstr_standard tap *
  page84_i147
#ISCELL
  mstr_standard tap *
  page84_i148
#ISCELL
  mstr_standard tap *
  page84_i149
#ISCELL
  mstr_standard offpage *
  page84_i15
#ISCELL
  mstr_standard tap *
  page84_i150
#ISCELL
  mstr_standard tap *
  page84_i151
#ISCELL
  mstr_standard tap *
  page84_i152
#ISCELL
  mstr_standard tap *
  page84_i153
#ISCELL
  mstr_standard tap *
  page84_i154
#ISCELL
  mstr_symbols gnd *
  page84_i155
#ISCELL
  mstr_standard tap *
  page84_i156
#ISCELL
  mstr_standard tap *
  page84_i157
#ISCELL
  mstr_standard tap *
  page84_i158
#ISCELL
  mstr_standard tap *
  page84_i159
#ISCELL
  mstr_standard offpage *
  page84_i16
#ISCELL
  mstr_standard tap *
  page84_i160
#ISCELL
  mstr_standard tap *
  page84_i161
#ISCELL
  mstr_standard tap *
  page84_i162
#ISCELL
  mstr_standard tap *
  page84_i163
#ISCELL
  mstr_standard tap *
  page84_i164
#ISCELL
  mstr_standard tap *
  page84_i165
#ISCELL
  mstr_standard tap *
  page84_i166
#ISCELL
  mstr_standard tap *
  page84_i167
#ISCELL
  mstr_standard tap *
  page84_i168
#ISCELL
  mstr_standard tap *
  page84_i169
#ISCELL
  mstr_standard offpage *
  page84_i17
#ISCELL
  mstr_standard tap *
  page84_i170
#ISCELL
  mstr_standard tap *
  page84_i171
#ISCELL
  mstr_standard tap *
  page84_i172
#ISCELL
  mstr_standard tap *
  page84_i173
#ISCELL
  mstr_standard tap *
  page84_i174
#ISCELL
  mstr_standard tap *
  page84_i175
#ISCELL
  mstr_standard tap *
  page84_i176
#ISCELL
  mstr_standard tap *
  page84_i177
#ISCELL
  mstr_standard tap *
  page84_i178
#ISCELL
  mstr_standard offpage *
  page84_i179
#ISCELL
  mstr_standard offpage *
  page84_i18
#ISCELL
  mstr_standard offpage *
  page84_i180
#ISCELL
  mstr_symbols p12v_nvdimm_klm *
  page84_i181
#ISCELL
  mstr_standard tap *
  page84_i19
#ISCELL
  mstr_standard offpage *
  page84_i2
#ISCELL
  mstr_standard tap *
  page84_i20
#ISCELL
  mstr_standard tap *
  page84_i21
#ISCELL
  mstr_standard tap *
  page84_i22
#ISCELL
  mstr_standard tap *
  page84_i23
#ISCELL
  mstr_standard tap *
  page84_i24
#ISCELL
  mstr_standard tap *
  page84_i25
#ISCELL
  mstr_standard tap *
  page84_i26
#ISCELL
  mstr_standard tap *
  page84_i27
#ISCELL
  mstr_standard tap *
  page84_i28
#ISCELL
  mstr_standard tap *
  page84_i29
#ISCELL
  mstr_symbols gnd *
  page84_i3
#ISCELL
  mstr_standard offpage *
  page84_i30
#ISCELL
  mstr_standard offpage *
  page84_i31
#ISCELL
  mstr_standard offpage *
  page84_i32
#ISCELL
  mstr_standard tap *
  page84_i33
#ISCELL
  mstr_standard tap *
  page84_i34
#ISCELL
  mstr_standard offpage *
  page84_i35
#ISCELL
  mstr_standard offpage *
  page84_i36
#ISCELL
  mstr_standard tap *
  page84_i37
#ISCELL
  mstr_standard tap *
  page84_i38
#ISCELL
  mstr_standard tap *
  page84_i39
#CELL
  dev_discrete cap_a *
  page84_i4
#ISCELL
  mstr_standard tap *
  page84_i40
#ISCELL
  mstr_standard tap *
  page84_i41
#ISCELL
  mstr_standard tap *
  page84_i42
#ISCELL
  mstr_standard tap *
  page84_i43
#ISCELL
  mstr_standard tap *
  page84_i44
#ISCELL
  mstr_standard tap *
  page84_i45
#ISCELL
  mstr_standard tap *
  page84_i46
#ISCELL
  mstr_standard tap *
  page84_i47
#ISCELL
  mstr_standard tap *
  page84_i48
#ISCELL
  mstr_standard tap *
  page84_i49
#ISCELL
  mstr_symbols pvpp_klm *
  page84_i5
#ISCELL
  mstr_standard tap *
  page84_i50
#ISCELL
  mstr_standard tap *
  page84_i51
#ISCELL
  mstr_standard tap *
  page84_i52
#ISCELL
  mstr_standard tap *
  page84_i53
#ISCELL
  mstr_standard tap *
  page84_i54
#ISCELL
  mstr_standard tap *
  page84_i55
#ISCELL
  mstr_standard tap *
  page84_i56
#CELL
  mstr_sconn sconn288_h44441003 *
  page84_i57
#ISCELL
  mstr_standard tap *
  page84_i58
#ISCELL
  mstr_standard tap *
  page84_i59
#ISCELL
  mstr_standard offpage *
  page84_i6
#ISCELL
  mstr_standard tap *
  page84_i60
#ISCELL
  mstr_standard tap *
  page84_i61
#ISCELL
  mstr_standard tap *
  page84_i62
#ISCELL
  mstr_standard tap *
  page84_i63
#ISCELL
  mstr_standard tap *
  page84_i64
#ISCELL
  mstr_standard tap *
  page84_i65
#ISCELL
  mstr_standard tap *
  page84_i66
#ISCELL
  mstr_standard tap *
  page84_i67
#ISCELL
  mstr_standard tap *
  page84_i68
#ISCELL
  mstr_standard tap *
  page84_i69
#ISCELL
  mstr_standard offpage *
  page84_i7
#ISCELL
  mstr_standard tap *
  page84_i70
#ISCELL
  mstr_standard tap *
  page84_i71
#ISCELL
  mstr_standard tap *
  page84_i72
#ISCELL
  mstr_standard tap *
  page84_i73
#ISCELL
  mstr_standard tap *
  page84_i74
#ISCELL
  mstr_standard tap *
  page84_i75
#ISCELL
  mstr_standard tap *
  page84_i76
#ISCELL
  mstr_standard tap *
  page84_i77
#ISCELL
  mstr_standard tap *
  page84_i78
#ISCELL
  mstr_symbols pvddq_klm *
  page84_i79
#ISCELL
  mstr_standard offpage *
  page84_i8
#ISCELL
  mstr_standard tap *
  page84_i80
#ISCELL
  mstr_standard tap *
  page84_i81
#ISCELL
  mstr_standard tap *
  page84_i82
#ISCELL
  mstr_standard tap *
  page84_i83
#ISCELL
  mstr_standard tap *
  page84_i84
#ISCELL
  mstr_standard tap *
  page84_i85
#ISCELL
  mstr_standard tap *
  page84_i86
#ISCELL
  mstr_standard tap *
  page84_i87
#ISCELL
  mstr_standard tap *
  page84_i88
#ISCELL
  mstr_standard tap *
  page84_i89
#ISCELL
  mstr_standard offpage *
  page84_i9
#ISCELL
  mstr_standard tap *
  page84_i90
#ISCELL
  mstr_standard tap *
  page84_i91
#ISCELL
  mstr_standard tap *
  page84_i92
#ISCELL
  mstr_standard tap *
  page84_i93
#ISCELL
  mstr_standard tap *
  page84_i94
#ISCELL
  mstr_standard tap *
  page84_i95
#ISCELL
  mstr_standard tap *
  page84_i96
#ISCELL
  mstr_standard tap *
  page84_i97
#ISCELL
  mstr_standard tap *
  page84_i98
#ISCELL
  mstr_standard tap *
  page84_i99
#ISCELL
  mstr_symbols bom_note *
  *
#ISCELL
  mstr_symbols intel_corp_bpage *
  *
#ISCELL
  mstr_standard offpage *
  page85_i1
#ISCELL
  mstr_standard tap *
  page85_i10
#ISCELL
  mstr_standard tap *
  page85_i100
#ISCELL
  mstr_standard tap *
  page85_i101
#ISCELL
  mstr_standard tap *
  page85_i102
#ISCELL
  mstr_standard tap *
  page85_i103
#ISCELL
  mstr_standard tap *
  page85_i104
#ISCELL
  mstr_standard tap *
  page85_i105
#ISCELL
  mstr_standard tap *
  page85_i106
#ISCELL
  mstr_standard tap *
  page85_i107
#ISCELL
  mstr_standard tap *
  page85_i108
#ISCELL
  mstr_standard tap *
  page85_i109
#ISCELL
  mstr_standard tap *
  page85_i11
#ISCELL
  mstr_standard tap *
  page85_i110
#CELL
  mstr_sconn sconn288_h44441004 *
  page85_i111
#ISCELL
  mstr_standard tap *
  page85_i112
#ISCELL
  mstr_standard tap *
  page85_i113
#ISCELL
  mstr_standard tap *
  page85_i114
#ISCELL
  mstr_standard tap *
  page85_i115
#ISCELL
  mstr_standard tap *
  page85_i116
#ISCELL
  mstr_standard tap *
  page85_i117
#ISCELL
  mstr_standard tap *
  page85_i118
#ISCELL
  mstr_standard tap *
  page85_i119
#ISCELL
  mstr_standard tap *
  page85_i12
#ISCELL
  mstr_standard tap *
  page85_i120
#ISCELL
  mstr_standard tap *
  page85_i121
#ISCELL
  mstr_standard tap *
  page85_i122
#ISCELL
  mstr_standard tap *
  page85_i123
#ISCELL
  mstr_standard tap *
  page85_i124
#ISCELL
  mstr_standard tap *
  page85_i125
#ISCELL
  mstr_standard tap *
  page85_i126
#ISCELL
  mstr_standard tap *
  page85_i127
#ISCELL
  mstr_standard tap *
  page85_i128
#ISCELL
  mstr_standard tap *
  page85_i129
#ISCELL
  mstr_standard tap *
  page85_i13
#ISCELL
  mstr_standard tap *
  page85_i130
#ISCELL
  mstr_standard offpage *
  page85_i131
#ISCELL
  mstr_standard offpage *
  page85_i132
#ISCELL
  mstr_standard tap *
  page85_i133
#ISCELL
  mstr_standard tap *
  page85_i134
#ISCELL
  mstr_standard tap *
  page85_i135
#ISCELL
  mstr_standard offpage *
  page85_i136
#ISCELL
  mstr_standard offpage *
  page85_i137
#ISCELL
  mstr_standard tap *
  page85_i138
#ISCELL
  mstr_standard tap *
  page85_i139
#ISCELL
  mstr_standard tap *
  page85_i14
#ISCELL
  mstr_standard tap *
  page85_i140
#ISCELL
  mstr_standard tap *
  page85_i141
#ISCELL
  mstr_standard tap *
  page85_i142
#ISCELL
  mstr_standard tap *
  page85_i143
#ISCELL
  mstr_standard tap *
  page85_i144
#ISCELL
  mstr_standard tap *
  page85_i145
#ISCELL
  mstr_standard offpage *
  page85_i146
#ISCELL
  mstr_standard offpage *
  page85_i147
#ISCELL
  mstr_standard offpage *
  page85_i148
#ISCELL
  mstr_standard offpage *
  page85_i149
#ISCELL
  mstr_standard tap *
  page85_i15
#ISCELL
  mstr_standard offpage *
  page85_i150
#ISCELL
  mstr_standard tap *
  page85_i152
#ISCELL
  mstr_standard tap *
  page85_i153
#ISCELL
  mstr_standard tap *
  page85_i154
#ISCELL
  mstr_standard tap *
  page85_i155
#ISCELL
  mstr_standard offpage *
  page85_i156
#ISCELL
  mstr_standard offpage *
  page85_i157
#ISCELL
  mstr_standard tap *
  page85_i159
#ISCELL
  mstr_symbols pvddq_klm *
  page85_i16
#ISCELL
  mstr_standard tap *
  page85_i160
#ISCELL
  mstr_standard tap *
  page85_i161
#ISCELL
  mstr_standard tap *
  page85_i162
#ISCELL
  mstr_standard tap *
  page85_i163
#ISCELL
  mstr_standard offpage *
  page85_i164
#ISCELL
  mstr_standard offpage *
  page85_i165
#ISCELL
  mstr_standard tap *
  page85_i166
#ISCELL
  mstr_standard tap *
  page85_i167
#ISCELL
  mstr_standard tap *
  page85_i168
#ISCELL
  mstr_standard offpage *
  page85_i169
#ISCELL
  mstr_symbols pvtt_klm *
  page85_i17
#CELL
  mstr_sconn sconn288_h44441004 *
  page85_i172
#ISCELL
  mstr_symbols gnd *
  page85_i173
#ISCELL
  mstr_symbols gnd *
  page85_i175
#ISCELL
  mstr_standard offpage *
  page85_i176
#ISCELL
  mstr_standard offpage *
  page85_i177
#ISCELL
  mstr_standard offpage *
  page85_i178
#ISCELL
  mstr_standard offpage *
  page85_i179
#ISCELL
  mstr_symbols gnd *
  page85_i180
#CELL
  dev_discrete cap_a *
  page85_i181
#ISCELL
  mstr_symbols pvpp_klm *
  page85_i182
#ISCELL
  mstr_symbols pvpp_klm *
  page85_i183
#ISCELL
  mstr_standard offpage *
  page85_i184
#ISCELL
  mstr_symbols p12v_nvdimm_klm *
  page85_i185
#ISCELL
  mstr_standard tap *
  page85_i19
#ISCELL
  mstr_standard offpage *
  page85_i2
#ISCELL
  mstr_standard tap *
  page85_i20
#ISCELL
  mstr_standard tap *
  page85_i21
#ISCELL
  mstr_standard tap *
  page85_i22
#ISCELL
  mstr_standard tap *
  page85_i23
#ISCELL
  mstr_standard tap *
  page85_i24
#ISCELL
  mstr_standard tap *
  page85_i25
#ISCELL
  mstr_standard tap *
  page85_i26
#ISCELL
  mstr_standard tap *
  page85_i27
#ISCELL
  mstr_standard tap *
  page85_i28
#ISCELL
  mstr_standard tap *
  page85_i29
#ISCELL
  mstr_standard tap *
  page85_i3
#ISCELL
  mstr_standard tap *
  page85_i30
#ISCELL
  mstr_standard tap *
  page85_i31
#ISCELL
  mstr_standard tap *
  page85_i32
#ISCELL
  mstr_standard tap *
  page85_i33
#ISCELL
  mstr_standard tap *
  page85_i34
#ISCELL
  mstr_standard tap *
  page85_i35
#ISCELL
  mstr_standard tap *
  page85_i36
#ISCELL
  mstr_standard tap *
  page85_i37
#ISCELL
  mstr_standard tap *
  page85_i38
#ISCELL
  mstr_standard tap *
  page85_i39
#ISCELL
  mstr_standard tap *
  page85_i4
#ISCELL
  mstr_standard tap *
  page85_i40
#ISCELL
  mstr_standard tap *
  page85_i41
#CELL
  mstr_sconn sconn288_h44441004 *
  page85_i43
#ISCELL
  mstr_symbols gnd *
  page85_i44
#ISCELL
  mstr_standard offpage *
  page85_i45
#ISCELL
  mstr_standard tap *
  page85_i46
#ISCELL
  mstr_standard tap *
  page85_i47
#ISCELL
  mstr_standard tap *
  page85_i48
#ISCELL
  mstr_standard tap *
  page85_i49
#ISCELL
  mstr_standard tap *
  page85_i5
#ISCELL
  mstr_standard tap *
  page85_i50
#ISCELL
  mstr_standard tap *
  page85_i51
#ISCELL
  mstr_standard tap *
  page85_i52
#ISCELL
  mstr_standard tap *
  page85_i53
#ISCELL
  mstr_standard tap *
  page85_i54
#ISCELL
  mstr_standard tap *
  page85_i55
#ISCELL
  mstr_standard tap *
  page85_i56
#ISCELL
  mstr_standard tap *
  page85_i57
#ISCELL
  mstr_standard tap *
  page85_i58
#ISCELL
  mstr_standard tap *
  page85_i59
#ISCELL
  mstr_standard tap *
  page85_i6
#ISCELL
  mstr_standard tap *
  page85_i60
#ISCELL
  mstr_standard tap *
  page85_i61
#ISCELL
  mstr_standard tap *
  page85_i62
#ISCELL
  mstr_standard tap *
  page85_i63
#ISCELL
  mstr_standard tap *
  page85_i64
#ISCELL
  mstr_standard tap *
  page85_i65
#CELL
  mstr_sconn sconn288_h44441004 *
  page85_i66
#ISCELL
  mstr_standard tap *
  page85_i67
#ISCELL
  mstr_standard tap *
  page85_i68
#ISCELL
  mstr_standard tap *
  page85_i69
#ISCELL
  mstr_standard tap *
  page85_i7
#ISCELL
  mstr_standard tap *
  page85_i70
#ISCELL
  mstr_standard tap *
  page85_i71
#ISCELL
  mstr_standard tap *
  page85_i72
#ISCELL
  mstr_standard tap *
  page85_i73
#ISCELL
  mstr_standard tap *
  page85_i74
#ISCELL
  mstr_standard tap *
  page85_i75
#ISCELL
  mstr_standard tap *
  page85_i76
#ISCELL
  mstr_standard tap *
  page85_i77
#ISCELL
  mstr_standard tap *
  page85_i78
#ISCELL
  mstr_standard tap *
  page85_i79
#ISCELL
  mstr_standard tap *
  page85_i8
#ISCELL
  mstr_standard tap *
  page85_i80
#ISCELL
  mstr_standard tap *
  page85_i81
#ISCELL
  mstr_standard tap *
  page85_i82
#ISCELL
  mstr_standard tap *
  page85_i83
#ISCELL
  mstr_standard tap *
  page85_i84
#ISCELL
  mstr_standard tap *
  page85_i85
#ISCELL
  mstr_standard tap *
  page85_i86
#ISCELL
  mstr_standard tap *
  page85_i87
#ISCELL
  mstr_standard tap *
  page85_i88
#ISCELL
  mstr_standard tap *
  page85_i89
#ISCELL
  mstr_standard tap *
  page85_i9
#ISCELL
  mstr_standard tap *
  page85_i90
#ISCELL
  mstr_standard tap *
  page85_i91
#ISCELL
  mstr_standard tap *
  page85_i92
#ISCELL
  mstr_standard tap *
  page85_i93
#ISCELL
  mstr_standard tap *
  page85_i94
#ISCELL
  mstr_standard tap *
  page85_i95
#ISCELL
  mstr_standard tap *
  page85_i96
#ISCELL
  mstr_standard tap *
  page85_i97
#ISCELL
  mstr_standard tap *
  page85_i98
#ISCELL
  mstr_standard tap *
  page85_i99
#ISCELL
  mstr_symbols bom_note *
  *
#ISCELL
  mstr_symbols intel_corp_bpage *
  *
#ISCELL
  mstr_symbols gnd *
  page86_i1
#ISCELL
  mstr_standard offpage *
  page86_i10
#CELL
  mstr_sconn sconn288_h44441003 *
  page86_i100
#ISCELL
  mstr_standard offpage *
  page86_i101
#ISCELL
  mstr_standard tap *
  page86_i102
#ISCELL
  mstr_standard tap *
  page86_i103
#ISCELL
  mstr_standard tap *
  page86_i104
#ISCELL
  mstr_standard tap *
  page86_i105
#ISCELL
  mstr_standard tap *
  page86_i106
#ISCELL
  mstr_standard tap *
  page86_i107
#ISCELL
  mstr_standard tap *
  page86_i108
#ISCELL
  mstr_standard tap *
  page86_i109
#ISCELL
  mstr_standard offpage *
  page86_i11
#ISCELL
  mstr_standard tap *
  page86_i110
#ISCELL
  mstr_standard tap *
  page86_i111
#ISCELL
  mstr_standard tap *
  page86_i112
#ISCELL
  mstr_standard tap *
  page86_i113
#ISCELL
  mstr_standard tap *
  page86_i114
#ISCELL
  mstr_standard tap *
  page86_i115
#ISCELL
  mstr_standard tap *
  page86_i116
#ISCELL
  mstr_standard tap *
  page86_i117
#ISCELL
  mstr_standard tap *
  page86_i118
#ISCELL
  mstr_standard tap *
  page86_i119
#CELL
  mstr_sconn sconn288_h44441003 *
  page86_i12
#ISCELL
  mstr_standard tap *
  page86_i120
#ISCELL
  mstr_standard tap *
  page86_i121
#ISCELL
  mstr_standard tap *
  page86_i122
#ISCELL
  mstr_standard tap *
  page86_i123
#ISCELL
  mstr_standard tap *
  page86_i124
#ISCELL
  mstr_standard tap *
  page86_i125
#ISCELL
  mstr_standard tap *
  page86_i126
#ISCELL
  mstr_standard tap *
  page86_i127
#ISCELL
  mstr_standard tap *
  page86_i128
#ISCELL
  mstr_standard tap *
  page86_i129
#ISCELL
  mstr_standard offpage *
  page86_i13
#ISCELL
  mstr_standard tap *
  page86_i130
#ISCELL
  mstr_standard tap *
  page86_i131
#ISCELL
  mstr_standard tap *
  page86_i132
#ISCELL
  mstr_standard tap *
  page86_i133
#ISCELL
  mstr_standard tap *
  page86_i134
#ISCELL
  mstr_standard tap *
  page86_i135
#ISCELL
  mstr_standard offpage *
  page86_i136
#ISCELL
  mstr_symbols gnd *
  page86_i137
#CELL
  mstr_sconn sconn288_h44441003 *
  page86_i138
#ISCELL
  mstr_standard offpage *
  page86_i14
#ISCELL
  mstr_standard tap *
  page86_i142
#ISCELL
  mstr_standard tap *
  page86_i143
#ISCELL
  mstr_standard tap *
  page86_i144
#ISCELL
  mstr_standard tap *
  page86_i145
#ISCELL
  mstr_standard tap *
  page86_i146
#ISCELL
  mstr_standard tap *
  page86_i147
#ISCELL
  mstr_standard tap *
  page86_i148
#ISCELL
  mstr_standard tap *
  page86_i149
#ISCELL
  mstr_standard offpage *
  page86_i15
#ISCELL
  mstr_standard tap *
  page86_i150
#ISCELL
  mstr_standard tap *
  page86_i151
#ISCELL
  mstr_standard tap *
  page86_i152
#ISCELL
  mstr_standard tap *
  page86_i153
#ISCELL
  mstr_standard tap *
  page86_i154
#ISCELL
  mstr_standard tap *
  page86_i155
#ISCELL
  mstr_symbols gnd *
  page86_i156
#ISCELL
  mstr_standard tap *
  page86_i157
#ISCELL
  mstr_standard tap *
  page86_i158
#ISCELL
  mstr_standard tap *
  page86_i159
#ISCELL
  mstr_standard offpage *
  page86_i16
#ISCELL
  mstr_standard tap *
  page86_i160
#ISCELL
  mstr_standard tap *
  page86_i161
#ISCELL
  mstr_standard tap *
  page86_i162
#ISCELL
  mstr_standard tap *
  page86_i163
#ISCELL
  mstr_standard tap *
  page86_i164
#ISCELL
  mstr_standard tap *
  page86_i165
#ISCELL
  mstr_standard tap *
  page86_i166
#ISCELL
  mstr_standard tap *
  page86_i167
#ISCELL
  mstr_standard tap *
  page86_i168
#ISCELL
  mstr_standard tap *
  page86_i169
#ISCELL
  mstr_standard tap *
  page86_i17
#ISCELL
  mstr_standard tap *
  page86_i170
#ISCELL
  mstr_standard tap *
  page86_i171
#ISCELL
  mstr_standard tap *
  page86_i172
#ISCELL
  mstr_standard tap *
  page86_i173
#ISCELL
  mstr_standard tap *
  page86_i174
#ISCELL
  mstr_standard tap *
  page86_i175
#ISCELL
  mstr_standard tap *
  page86_i176
#ISCELL
  mstr_standard tap *
  page86_i177
#ISCELL
  mstr_standard tap *
  page86_i178
#ISCELL
  mstr_standard offpage *
  page86_i179
#ISCELL
  mstr_standard tap *
  page86_i18
#ISCELL
  mstr_standard offpage *
  page86_i180
#ISCELL
  mstr_symbols p12v_nvdimm_klm *
  page86_i181
#CELL
  dev_discrete cap_a *
  page86_i182
#ISCELL
  mstr_standard tap *
  page86_i19
#ISCELL
  mstr_symbols gnd *
  page86_i2
#ISCELL
  mstr_standard tap *
  page86_i20
#ISCELL
  mstr_standard tap *
  page86_i21
#ISCELL
  mstr_standard tap *
  page86_i22
#ISCELL
  mstr_standard tap *
  page86_i23
#ISCELL
  mstr_standard tap *
  page86_i24
#ISCELL
  mstr_standard tap *
  page86_i25
#ISCELL
  mstr_standard tap *
  page86_i26
#ISCELL
  mstr_standard offpage *
  page86_i27
#ISCELL
  mstr_standard offpage *
  page86_i28
#ISCELL
  mstr_standard offpage *
  page86_i29
#ISCELL
  mstr_standard offpage *
  page86_i30
#ISCELL
  mstr_standard offpage *
  page86_i31
#ISCELL
  mstr_standard offpage *
  page86_i32
#ISCELL
  mstr_standard offpage *
  page86_i33
#ISCELL
  mstr_standard tap *
  page86_i34
#ISCELL
  mstr_standard tap *
  page86_i35
#ISCELL
  mstr_standard tap *
  page86_i36
#ISCELL
  mstr_standard tap *
  page86_i37
#ISCELL
  mstr_standard tap *
  page86_i38
#ISCELL
  mstr_standard tap *
  page86_i39
#ISCELL
  mstr_standard offpage *
  page86_i4
#ISCELL
  mstr_standard tap *
  page86_i40
#ISCELL
  mstr_standard tap *
  page86_i41
#ISCELL
  mstr_standard tap *
  page86_i42
#ISCELL
  mstr_standard tap *
  page86_i43
#ISCELL
  mstr_standard tap *
  page86_i44
#ISCELL
  mstr_standard tap *
  page86_i45
#ISCELL
  mstr_standard tap *
  page86_i46
#ISCELL
  mstr_standard tap *
  page86_i47
#ISCELL
  mstr_standard tap *
  page86_i48
#ISCELL
  mstr_standard tap *
  page86_i49
#ISCELL
  mstr_symbols pvpp_klm *
  page86_i5
#ISCELL
  mstr_standard tap *
  page86_i50
#ISCELL
  mstr_standard tap *
  page86_i51
#ISCELL
  mstr_standard tap *
  page86_i52
#ISCELL
  mstr_standard tap *
  page86_i53
#ISCELL
  mstr_standard tap *
  page86_i54
#CELL
  mstr_sconn sconn288_h44441003 *
  page86_i55
#ISCELL
  mstr_standard tap *
  page86_i56
#ISCELL
  mstr_standard tap *
  page86_i57
#ISCELL
  mstr_standard tap *
  page86_i58
#ISCELL
  mstr_standard tap *
  page86_i59
#ISCELL
  mstr_standard offpage *
  page86_i6
#ISCELL
  mstr_standard tap *
  page86_i60
#ISCELL
  mstr_standard tap *
  page86_i61
#ISCELL
  mstr_standard tap *
  page86_i62
#ISCELL
  mstr_standard tap *
  page86_i63
#ISCELL
  mstr_standard tap *
  page86_i64
#ISCELL
  mstr_standard tap *
  page86_i65
#ISCELL
  mstr_standard tap *
  page86_i66
#ISCELL
  mstr_standard tap *
  page86_i67
#ISCELL
  mstr_standard tap *
  page86_i68
#ISCELL
  mstr_standard tap *
  page86_i69
#ISCELL
  mstr_standard offpage *
  page86_i7
#ISCELL
  mstr_standard tap *
  page86_i70
#ISCELL
  mstr_standard tap *
  page86_i71
#ISCELL
  mstr_standard tap *
  page86_i72
#ISCELL
  mstr_standard tap *
  page86_i73
#ISCELL
  mstr_standard tap *
  page86_i74
#ISCELL
  mstr_standard tap *
  page86_i75
#ISCELL
  mstr_standard tap *
  page86_i76
#ISCELL
  mstr_symbols pvddq_klm *
  page86_i77
#ISCELL
  mstr_symbols pvtt_klm *
  page86_i78
#ISCELL
  mstr_standard tap *
  page86_i79
#ISCELL
  mstr_standard offpage *
  page86_i8
#ISCELL
  mstr_standard tap *
  page86_i80
#ISCELL
  mstr_standard tap *
  page86_i81
#ISCELL
  mstr_standard tap *
  page86_i82
#ISCELL
  mstr_standard tap *
  page86_i83
#ISCELL
  mstr_standard tap *
  page86_i84
#ISCELL
  mstr_standard tap *
  page86_i85
#ISCELL
  mstr_standard tap *
  page86_i86
#ISCELL
  mstr_standard tap *
  page86_i87
#ISCELL
  mstr_standard tap *
  page86_i88
#ISCELL
  mstr_standard tap *
  page86_i89
#ISCELL
  mstr_standard offpage *
  page86_i9
#ISCELL
  mstr_standard tap *
  page86_i90
#ISCELL
  mstr_standard tap *
  page86_i91
#ISCELL
  mstr_standard tap *
  page86_i92
#ISCELL
  mstr_standard tap *
  page86_i93
#ISCELL
  mstr_standard tap *
  page86_i94
#ISCELL
  mstr_standard tap *
  page86_i95
#ISCELL
  mstr_standard tap *
  page86_i96
#ISCELL
  mstr_standard tap *
  page86_i97
#ISCELL
  mstr_standard tap *
  page86_i98
#ISCELL
  mstr_symbols pvpp_klm *
  page86_i99
#ISCELL
  mstr_symbols bom_note *
  *
#ISCELL
  mstr_symbols intel_corp_bpage *
  *
#ISCELL
  mstr_standard offpage *
  page87_i1
#ISCELL
  mstr_standard tap *
  page87_i100
#ISCELL
  mstr_standard tap *
  page87_i101
#ISCELL
  mstr_standard tap *
  page87_i102
#ISCELL
  mstr_standard tap *
  page87_i103
#ISCELL
  mstr_standard tap *
  page87_i104
#ISCELL
  mstr_standard tap *
  page87_i105
#ISCELL
  mstr_standard tap *
  page87_i106
#ISCELL
  mstr_standard tap *
  page87_i107
#ISCELL
  mstr_standard tap *
  page87_i108
#ISCELL
  mstr_standard tap *
  page87_i109
#ISCELL
  mstr_symbols pvddq_klm *
  page87_i11
#ISCELL
  mstr_standard tap *
  page87_i110
#ISCELL
  mstr_standard tap *
  page87_i112
#ISCELL
  mstr_standard tap *
  page87_i113
#ISCELL
  mstr_standard tap *
  page87_i114
#ISCELL
  mstr_standard tap *
  page87_i115
#ISCELL
  mstr_standard tap *
  page87_i116
#ISCELL
  mstr_standard tap *
  page87_i117
#ISCELL
  mstr_standard tap *
  page87_i118
#ISCELL
  mstr_standard tap *
  page87_i119
#ISCELL
  mstr_standard tap *
  page87_i12
#ISCELL
  mstr_standard tap *
  page87_i120
#ISCELL
  mstr_standard tap *
  page87_i121
#ISCELL
  mstr_standard tap *
  page87_i122
#ISCELL
  mstr_standard tap *
  page87_i123
#ISCELL
  mstr_standard tap *
  page87_i124
#ISCELL
  mstr_standard tap *
  page87_i125
#ISCELL
  mstr_standard tap *
  page87_i126
#ISCELL
  mstr_standard tap *
  page87_i127
#ISCELL
  mstr_standard tap *
  page87_i128
#ISCELL
  mstr_standard tap *
  page87_i129
#ISCELL
  mstr_standard tap *
  page87_i13
#ISCELL
  mstr_standard tap *
  page87_i130
#ISCELL
  mstr_standard offpage *
  page87_i131
#ISCELL
  mstr_standard offpage *
  page87_i132
#ISCELL
  mstr_standard tap *
  page87_i133
#ISCELL
  mstr_standard tap *
  page87_i134
#ISCELL
  mstr_standard tap *
  page87_i135
#ISCELL
  mstr_standard offpage *
  page87_i136
#ISCELL
  mstr_standard offpage *
  page87_i137
#ISCELL
  mstr_standard tap *
  page87_i138
#ISCELL
  mstr_standard tap *
  page87_i139
#ISCELL
  mstr_standard tap *
  page87_i14
#ISCELL
  mstr_standard tap *
  page87_i140
#ISCELL
  mstr_standard tap *
  page87_i141
#ISCELL
  mstr_standard tap *
  page87_i142
#ISCELL
  mstr_standard tap *
  page87_i143
#ISCELL
  mstr_standard tap *
  page87_i144
#ISCELL
  mstr_standard tap *
  page87_i145
#ISCELL
  mstr_standard offpage *
  page87_i146
#ISCELL
  mstr_standard offpage *
  page87_i147
#ISCELL
  mstr_standard offpage *
  page87_i148
#ISCELL
  mstr_standard offpage *
  page87_i149
#ISCELL
  mstr_standard tap *
  page87_i15
#ISCELL
  mstr_standard offpage *
  page87_i150
#ISCELL
  mstr_standard tap *
  page87_i152
#ISCELL
  mstr_standard tap *
  page87_i153
#ISCELL
  mstr_standard tap *
  page87_i154
#ISCELL
  mstr_standard tap *
  page87_i155
#ISCELL
  mstr_standard offpage *
  page87_i156
#ISCELL
  mstr_standard offpage *
  page87_i157
#ISCELL
  mstr_standard tap *
  page87_i158
#ISCELL
  mstr_standard tap *
  page87_i159
#ISCELL
  mstr_standard tap *
  page87_i16
#ISCELL
  mstr_standard tap *
  page87_i160
#ISCELL
  mstr_standard tap *
  page87_i161
#ISCELL
  mstr_standard offpage *
  page87_i162
#ISCELL
  mstr_standard tap *
  page87_i163
#ISCELL
  mstr_standard tap *
  page87_i164
#ISCELL
  mstr_standard tap *
  page87_i165
#ISCELL
  mstr_standard tap *
  page87_i166
#ISCELL
  mstr_standard offpage *
  page87_i167
#ISCELL
  mstr_standard offpage *
  page87_i168
#CELL
  mstr_sconn sconn288_h44441004 *
  page87_i169
#ISCELL
  mstr_standard tap *
  page87_i17
#ISCELL
  mstr_symbols gnd *
  page87_i170
#ISCELL
  mstr_standard offpage *
  page87_i171
#ISCELL
  mstr_standard offpage *
  page87_i172
#ISCELL
  mstr_standard offpage *
  page87_i173
#ISCELL
  mstr_standard offpage *
  page87_i174
#ISCELL
  mstr_symbols gnd *
  page87_i176
#ISCELL
  mstr_symbols gnd *
  page87_i177
#CELL
  dev_discrete cap_a *
  page87_i178
#ISCELL
  mstr_symbols pvpp_klm *
  page87_i179
#ISCELL
  mstr_standard tap *
  page87_i18
#ISCELL
  mstr_symbols pvpp_klm *
  page87_i180
#ISCELL
  mstr_standard offpage *
  page87_i181
#CELL
  mstr_sconn sconn288_h44441004 *
  page87_i185
#CELL
  mstr_sconn sconn288_h44441004 *
  page87_i186
#CELL
  mstr_sconn sconn288_h44441004 *
  page87_i187
#ISCELL
  mstr_symbols p12v_nvdimm_klm *
  page87_i188
#ISCELL
  mstr_standard tap *
  page87_i19
#ISCELL
  mstr_standard offpage *
  page87_i2
#ISCELL
  mstr_standard tap *
  page87_i20
#ISCELL
  mstr_standard tap *
  page87_i21
#ISCELL
  mstr_standard tap *
  page87_i22
#ISCELL
  mstr_standard tap *
  page87_i23
#ISCELL
  mstr_symbols gnd *
  page87_i26
#ISCELL
  mstr_standard tap *
  page87_i27
#ISCELL
  mstr_standard tap *
  page87_i28
#ISCELL
  mstr_standard tap *
  page87_i29
#ISCELL
  mstr_standard tap *
  page87_i3
#ISCELL
  mstr_standard tap *
  page87_i30
#ISCELL
  mstr_standard tap *
  page87_i31
#ISCELL
  mstr_standard tap *
  page87_i32
#ISCELL
  mstr_standard tap *
  page87_i33
#ISCELL
  mstr_standard offpage *
  page87_i34
#ISCELL
  mstr_standard tap *
  page87_i35
#ISCELL
  mstr_standard tap *
  page87_i36
#ISCELL
  mstr_standard tap *
  page87_i37
#ISCELL
  mstr_standard tap *
  page87_i38
#ISCELL
  mstr_standard tap *
  page87_i39
#ISCELL
  mstr_standard tap *
  page87_i4
#ISCELL
  mstr_standard tap *
  page87_i40
#ISCELL
  mstr_standard tap *
  page87_i41
#ISCELL
  mstr_standard tap *
  page87_i42
#ISCELL
  mstr_standard tap *
  page87_i43
#ISCELL
  mstr_standard tap *
  page87_i44
#ISCELL
  mstr_standard tap *
  page87_i45
#ISCELL
  mstr_standard tap *
  page87_i46
#ISCELL
  mstr_standard tap *
  page87_i47
#ISCELL
  mstr_standard tap *
  page87_i48
#ISCELL
  mstr_standard tap *
  page87_i49
#ISCELL
  mstr_standard tap *
  page87_i5
#ISCELL
  mstr_standard tap *
  page87_i50
#ISCELL
  mstr_standard tap *
  page87_i51
#ISCELL
  mstr_standard tap *
  page87_i52
#ISCELL
  mstr_standard tap *
  page87_i53
#ISCELL
  mstr_standard tap *
  page87_i54
#ISCELL
  mstr_standard tap *
  page87_i55
#ISCELL
  mstr_standard tap *
  page87_i56
#ISCELL
  mstr_standard tap *
  page87_i57
#ISCELL
  mstr_standard tap *
  page87_i58
#ISCELL
  mstr_standard tap *
  page87_i59
#ISCELL
  mstr_standard tap *
  page87_i6
#ISCELL
  mstr_standard tap *
  page87_i60
#ISCELL
  mstr_standard tap *
  page87_i61
#ISCELL
  mstr_standard tap *
  page87_i62
#ISCELL
  mstr_standard tap *
  page87_i63
#ISCELL
  mstr_standard tap *
  page87_i64
#ISCELL
  mstr_standard tap *
  page87_i65
#ISCELL
  mstr_standard tap *
  page87_i66
#ISCELL
  mstr_standard tap *
  page87_i67
#ISCELL
  mstr_standard tap *
  page87_i68
#ISCELL
  mstr_standard tap *
  page87_i69
#ISCELL
  mstr_standard tap *
  page87_i7
#ISCELL
  mstr_standard tap *
  page87_i70
#ISCELL
  mstr_standard tap *
  page87_i71
#ISCELL
  mstr_standard tap *
  page87_i72
#ISCELL
  mstr_standard tap *
  page87_i73
#ISCELL
  mstr_standard tap *
  page87_i74
#ISCELL
  mstr_standard tap *
  page87_i75
#ISCELL
  mstr_standard tap *
  page87_i76
#ISCELL
  mstr_standard tap *
  page87_i77
#ISCELL
  mstr_standard tap *
  page87_i78
#ISCELL
  mstr_standard tap *
  page87_i79
#ISCELL
  mstr_standard tap *
  page87_i8
#ISCELL
  mstr_standard tap *
  page87_i80
#ISCELL
  mstr_standard tap *
  page87_i81
#ISCELL
  mstr_standard tap *
  page87_i82
#ISCELL
  mstr_standard tap *
  page87_i83
#ISCELL
  mstr_standard tap *
  page87_i84
#ISCELL
  mstr_standard tap *
  page87_i85
#ISCELL
  mstr_standard tap *
  page87_i86
#ISCELL
  mstr_standard tap *
  page87_i88
#ISCELL
  mstr_standard tap *
  page87_i89
#ISCELL
  mstr_symbols pvtt_klm *
  page87_i9
#ISCELL
  mstr_standard tap *
  page87_i90
#ISCELL
  mstr_standard tap *
  page87_i91
#ISCELL
  mstr_standard tap *
  page87_i92
#ISCELL
  mstr_standard tap *
  page87_i93
#ISCELL
  mstr_standard tap *
  page87_i94
#ISCELL
  mstr_standard tap *
  page87_i95
#ISCELL
  mstr_standard tap *
  page87_i96
#ISCELL
  mstr_standard tap *
  page87_i97
#ISCELL
  mstr_standard tap *
  page87_i98
#ISCELL
  mstr_standard tap *
  page87_i99
#ISCELL
  mstr_symbols bom_note *
  *
#ISCELL
  mstr_symbols intel_corp_bpage *
  *
#ISCELL
  mstr_standard offpage *
  page88_i1
#ISCELL
  mstr_standard tap *
  page88_i100
#ISCELL
  mstr_standard tap *
  page88_i101
#ISCELL
  mstr_standard tap *
  page88_i102
#ISCELL
  mstr_standard tap *
  page88_i103
#ISCELL
  mstr_standard tap *
  page88_i104
#ISCELL
  mstr_standard tap *
  page88_i105
#ISCELL
  mstr_standard tap *
  page88_i106
#ISCELL
  mstr_standard tap *
  page88_i107
#ISCELL
  mstr_standard tap *
  page88_i108
#ISCELL
  mstr_standard tap *
  page88_i109
#ISCELL
  mstr_symbols pvddq_klm *
  page88_i11
#ISCELL
  mstr_standard tap *
  page88_i110
#CELL
  mstr_sconn sconn288_h44441003 *
  page88_i111
#ISCELL
  mstr_standard tap *
  page88_i112
#ISCELL
  mstr_standard tap *
  page88_i113
#ISCELL
  mstr_standard tap *
  page88_i114
#ISCELL
  mstr_standard tap *
  page88_i115
#ISCELL
  mstr_standard tap *
  page88_i116
#ISCELL
  mstr_standard tap *
  page88_i117
#ISCELL
  mstr_standard tap *
  page88_i118
#ISCELL
  mstr_standard tap *
  page88_i119
#ISCELL
  mstr_standard tap *
  page88_i12
#ISCELL
  mstr_standard tap *
  page88_i120
#ISCELL
  mstr_standard tap *
  page88_i121
#ISCELL
  mstr_standard tap *
  page88_i122
#ISCELL
  mstr_standard tap *
  page88_i123
#ISCELL
  mstr_standard tap *
  page88_i124
#ISCELL
  mstr_standard tap *
  page88_i125
#ISCELL
  mstr_standard tap *
  page88_i126
#ISCELL
  mstr_standard tap *
  page88_i127
#ISCELL
  mstr_standard tap *
  page88_i128
#ISCELL
  mstr_standard tap *
  page88_i129
#ISCELL
  mstr_standard tap *
  page88_i13
#ISCELL
  mstr_standard tap *
  page88_i130
#ISCELL
  mstr_standard offpage *
  page88_i131
#ISCELL
  mstr_standard offpage *
  page88_i132
#ISCELL
  mstr_standard tap *
  page88_i133
#ISCELL
  mstr_standard tap *
  page88_i134
#ISCELL
  mstr_standard tap *
  page88_i135
#ISCELL
  mstr_standard offpage *
  page88_i136
#ISCELL
  mstr_standard offpage *
  page88_i137
#ISCELL
  mstr_standard tap *
  page88_i138
#ISCELL
  mstr_standard tap *
  page88_i139
#ISCELL
  mstr_standard tap *
  page88_i14
#ISCELL
  mstr_standard tap *
  page88_i140
#ISCELL
  mstr_standard tap *
  page88_i141
#ISCELL
  mstr_standard tap *
  page88_i142
#ISCELL
  mstr_standard tap *
  page88_i143
#ISCELL
  mstr_standard tap *
  page88_i144
#ISCELL
  mstr_standard tap *
  page88_i145
#ISCELL
  mstr_standard offpage *
  page88_i146
#ISCELL
  mstr_standard offpage *
  page88_i147
#ISCELL
  mstr_standard offpage *
  page88_i148
#ISCELL
  mstr_standard offpage *
  page88_i149
#ISCELL
  mstr_standard tap *
  page88_i15
#ISCELL
  mstr_standard offpage *
  page88_i150
#ISCELL
  mstr_standard tap *
  page88_i152
#ISCELL
  mstr_standard tap *
  page88_i153
#ISCELL
  mstr_standard offpage *
  page88_i155
#ISCELL
  mstr_standard offpage *
  page88_i156
#ISCELL
  mstr_standard offpage *
  page88_i157
#ISCELL
  mstr_standard offpage *
  page88_i158
#ISCELL
  mstr_standard offpage *
  page88_i159
#ISCELL
  mstr_standard tap *
  page88_i16
#ISCELL
  mstr_standard tap *
  page88_i160
#ISCELL
  mstr_standard tap *
  page88_i161
#ISCELL
  mstr_standard tap *
  page88_i162
#ISCELL
  mstr_standard tap *
  page88_i163
#ISCELL
  mstr_standard tap *
  page88_i164
#ISCELL
  mstr_standard tap *
  page88_i165
#ISCELL
  mstr_standard tap *
  page88_i166
#ISCELL
  mstr_standard tap *
  page88_i167
#CELL
  mstr_sconn sconn288_h44441003 *
  page88_i168
#ISCELL
  mstr_symbols gnd *
  page88_i169
#ISCELL
  mstr_standard tap *
  page88_i17
#ISCELL
  mstr_standard offpage *
  page88_i170
#ISCELL
  mstr_standard offpage *
  page88_i171
#ISCELL
  mstr_standard offpage *
  page88_i172
#ISCELL
  mstr_standard offpage *
  page88_i173
#ISCELL
  mstr_symbols gnd *
  page88_i175
#ISCELL
  mstr_symbols gnd *
  page88_i176
#CELL
  dev_discrete cap_a *
  page88_i177
#ISCELL
  mstr_symbols pvpp_klm *
  page88_i178
#ISCELL
  mstr_symbols pvpp_klm *
  page88_i179
#ISCELL
  mstr_standard tap *
  page88_i18
#ISCELL
  mstr_standard offpage *
  page88_i180
#ISCELL
  mstr_standard tap *
  page88_i184
#ISCELL
  mstr_standard tap *
  page88_i185
#ISCELL
  mstr_symbols p12v_nvdimm_klm *
  page88_i186
#ISCELL
  mstr_standard tap *
  page88_i19
#ISCELL
  mstr_standard offpage *
  page88_i2
#ISCELL
  mstr_standard tap *
  page88_i20
#ISCELL
  mstr_standard tap *
  page88_i21
#ISCELL
  mstr_standard tap *
  page88_i22
#ISCELL
  mstr_standard tap *
  page88_i23
#CELL
  mstr_sconn sconn288_h44441003 *
  page88_i25
#ISCELL
  mstr_symbols gnd *
  page88_i26
#ISCELL
  mstr_standard tap *
  page88_i27
#ISCELL
  mstr_standard tap *
  page88_i28
#ISCELL
  mstr_standard tap *
  page88_i29
#ISCELL
  mstr_standard tap *
  page88_i3
#ISCELL
  mstr_standard tap *
  page88_i30
#ISCELL
  mstr_standard tap *
  page88_i31
#ISCELL
  mstr_standard tap *
  page88_i32
#ISCELL
  mstr_standard tap *
  page88_i33
#ISCELL
  mstr_standard offpage *
  page88_i34
#ISCELL
  mstr_standard tap *
  page88_i35
#ISCELL
  mstr_standard tap *
  page88_i36
#ISCELL
  mstr_standard tap *
  page88_i37
#ISCELL
  mstr_standard tap *
  page88_i38
#ISCELL
  mstr_standard tap *
  page88_i39
#ISCELL
  mstr_standard tap *
  page88_i4
#ISCELL
  mstr_standard tap *
  page88_i40
#ISCELL
  mstr_standard tap *
  page88_i41
#ISCELL
  mstr_standard tap *
  page88_i42
#ISCELL
  mstr_standard tap *
  page88_i43
#ISCELL
  mstr_standard tap *
  page88_i44
#ISCELL
  mstr_standard tap *
  page88_i45
#ISCELL
  mstr_standard tap *
  page88_i46
#ISCELL
  mstr_standard tap *
  page88_i47
#ISCELL
  mstr_standard tap *
  page88_i48
#ISCELL
  mstr_standard tap *
  page88_i49
#ISCELL
  mstr_standard tap *
  page88_i5
#ISCELL
  mstr_standard tap *
  page88_i50
#ISCELL
  mstr_standard tap *
  page88_i51
#ISCELL
  mstr_standard tap *
  page88_i52
#ISCELL
  mstr_standard tap *
  page88_i53
#ISCELL
  mstr_standard tap *
  page88_i54
#ISCELL
  mstr_standard tap *
  page88_i55
#ISCELL
  mstr_standard tap *
  page88_i56
#ISCELL
  mstr_standard tap *
  page88_i57
#ISCELL
  mstr_standard tap *
  page88_i58
#ISCELL
  mstr_standard tap *
  page88_i59
#ISCELL
  mstr_standard tap *
  page88_i6
#ISCELL
  mstr_standard tap *
  page88_i60
#ISCELL
  mstr_standard tap *
  page88_i61
#ISCELL
  mstr_standard tap *
  page88_i62
#ISCELL
  mstr_standard tap *
  page88_i63
#ISCELL
  mstr_standard tap *
  page88_i64
#ISCELL
  mstr_standard tap *
  page88_i65
#ISCELL
  mstr_standard tap *
  page88_i66
#ISCELL
  mstr_standard tap *
  page88_i67
#ISCELL
  mstr_standard tap *
  page88_i68
#ISCELL
  mstr_standard tap *
  page88_i69
#ISCELL
  mstr_standard tap *
  page88_i7
#ISCELL
  mstr_standard tap *
  page88_i70
#ISCELL
  mstr_standard tap *
  page88_i71
#ISCELL
  mstr_standard tap *
  page88_i72
#ISCELL
  mstr_standard tap *
  page88_i73
#ISCELL
  mstr_standard tap *
  page88_i74
#ISCELL
  mstr_standard tap *
  page88_i75
#ISCELL
  mstr_standard tap *
  page88_i76
#ISCELL
  mstr_standard tap *
  page88_i77
#ISCELL
  mstr_standard tap *
  page88_i78
#ISCELL
  mstr_standard tap *
  page88_i79
#ISCELL
  mstr_standard tap *
  page88_i8
#ISCELL
  mstr_standard tap *
  page88_i80
#ISCELL
  mstr_standard tap *
  page88_i81
#ISCELL
  mstr_standard tap *
  page88_i82
#ISCELL
  mstr_standard tap *
  page88_i83
#ISCELL
  mstr_standard tap *
  page88_i84
#ISCELL
  mstr_standard tap *
  page88_i85
#ISCELL
  mstr_standard tap *
  page88_i86
#CELL
  mstr_sconn sconn288_h44441003 *
  page88_i87
#ISCELL
  mstr_standard tap *
  page88_i88
#ISCELL
  mstr_standard tap *
  page88_i89
#ISCELL
  mstr_symbols pvtt_klm *
  page88_i9
#ISCELL
  mstr_standard tap *
  page88_i90
#ISCELL
  mstr_standard tap *
  page88_i91
#ISCELL
  mstr_standard tap *
  page88_i92
#ISCELL
  mstr_standard tap *
  page88_i93
#ISCELL
  mstr_standard tap *
  page88_i94
#ISCELL
  mstr_standard tap *
  page88_i95
#ISCELL
  mstr_standard tap *
  page88_i96
#ISCELL
  mstr_standard tap *
  page88_i97
#ISCELL
  mstr_standard tap *
  page88_i98
#ISCELL
  mstr_standard tap *
  page88_i99
#ISCELL
  mstr_misc dns *
  *
#ISCELL
  mstr_symbols intel_corp_bpage *
  *
#CELL
  mstr_discrete res *
  page89_i1
#ISCELL
  mstr_standard offpage *
  page89_i10
#ISCELL
  mstr_standard offpage *
  page89_i11
#ISCELL
  mstr_standard offpage *
  page89_i12
#ISCELL
  mstr_standard offpage *
  page89_i13
#ISCELL
  mstr_standard offpage *
  page89_i14
#ISCELL
  mstr_symbols gnd *
  page89_i16
#ISCELL
  mstr_symbols pvpp_abc *
  page89_i17
#CELL
  mstr_discrete fet_n *
  page89_i18
#CELL
  mstr_discrete res *
  page89_i2
#ISCELL
  mstr_standard offpage *
  page89_i22
#CELL
  mstr_discrete res *
  page89_i23
#CELL
  mstr_discrete res *
  page89_i26
#CELL
  mstr_discrete res *
  page89_i27
#ISCELL
  mstr_symbols p3v3_stby *
  page89_i28
#ISCELL
  mstr_symbols p3v3_stby *
  page89_i29
#CELL
  mstr_discrete res *
  page89_i3
#ISCELL
  mstr_symbols gnd *
  page89_i30
#ISCELL
  mstr_symbols gnd *
  page89_i31
#ISCELL
  mstr_standard offpage *
  page89_i33
#CELL
  mstr_discrete res *
  page89_i34
#CELL
  mstr_discrete npn_dual *
  page89_i35
#CELL
  mstr_discrete npn_dual *
  page89_i36
#CELL
  mstr_discrete res *
  page89_i4
#CELL
  mstr_discrete res *
  page89_i5
#CELL
  mstr_discrete res *
  page89_i6
#CELL
  mstr_discrete res *
  page89_i7
#ISCELL
  mstr_standard offpage *
  page89_i9
#ISCELL
  mstr_misc dns *
  *
#ISCELL
  mstr_symbols cad_note *
  *
#ISCELL
  mstr_symbols design_note *
  *
#ISCELL
  mstr_symbols intel_corp_bpage *
  *
#ISCELL
  mstr_standard offpage *
  page90_i1
#ISCELL
  mstr_standard offpage *
  page90_i10
#CELL
  mstr_discrete res *
  page90_i11
#CELL
  mstr_discrete res *
  page90_i12
#ISCELL
  mstr_standard offpage *
  page90_i14
#ISCELL
  mstr_standard offpage *
  page90_i16
#CELL
  mstr_discrete res *
  page90_i17
#ISCELL
  mstr_symbols gnd *
  page90_i18
#ISCELL
  mstr_standard offpage *
  page90_i19
#ISCELL
  mstr_standard offpage *
  page90_i2
#ISCELL
  mstr_standard offpage *
  page90_i20
#ISCELL
  mstr_standard offpage *
  page90_i23
#CELL
  mstr_discrete res *
  page90_i24
#CELL
  mstr_discrete res *
  page90_i25
#CELL
  mstr_discrete res *
  page90_i28
#CELL
  mstr_discrete res *
  page90_i29
#CELL
  mstr_discrete res *
  page90_i3
#ISCELL
  mstr_symbols pvccio_cpu0 *
  page90_i30
#CELL
  mstr_discrete res *
  page90_i31
#CELL
  mstr_discrete res *
  page90_i32
#CELL
  mstr_discrete res *
  page90_i33
#CELL
  mstr_discrete res *
  page90_i4
#ISCELL
  mstr_standard offpage *
  page90_i45
#ISCELL
  mstr_standard offpage *
  page90_i46
#CELL
  mstr_discrete res *
  page90_i48
#CELL
  mstr_discrete res *
  page90_i49
#ISCELL
  mstr_symbols gnd *
  page90_i5
#ISCELL
  mstr_symbols pvccio_cpu0 *
  page90_i51
#CELL
  mstr_discrete res *
  page90_i52
#CELL
  mstr_discrete res *
  page90_i53
#ISCELL
  mstr_standard offpage *
  page90_i54
#ISCELL
  mstr_standard offpage *
  page90_i55
#ISCELL
  mstr_standard offpage *
  page90_i56
#ISCELL
  mstr_standard offpage *
  page90_i57
#CELL
  mstr_discrete res *
  page90_i59
#ISCELL
  mstr_standard offpage *
  page90_i6
#CELL
  mstr_discrete res *
  page90_i60
#ISCELL
  mstr_symbols pvccio_cpu1 *
  page90_i62
#ISCELL
  mstr_symbols pvccio_cpu1 *
  page90_i63
#ISCELL
  mstr_standard offpage *
  page90_i64
#CELL
  mstr_discrete res *
  page90_i66
#CELL
  mstr_discrete res *
  page90_i68
#ISCELL
  mstr_standard offpage *
  page90_i69
#ISCELL
  mstr_standard offpage *
  page90_i7
#CELL
  mstr_discrete res *
  page90_i70
#ISCELL
  mstr_standard offpage *
  page90_i71
#CELL
  mstr_discrete res *
  page90_i72
#ISCELL
  mstr_standard offpage *
  page90_i73
#CELL
  mstr_discrete res *
  page90_i74
#ISCELL
  mstr_standard offpage *
  page90_i75
#CELL
  mstr_discrete res *
  page90_i76
#ISCELL
  mstr_standard offpage *
  page90_i77
#ISCELL
  mstr_symbols gnd *
  page90_i78
#CELL
  mstr_discrete res *
  page90_i79
#ISCELL
  mstr_standard offpage *
  page90_i8
#CELL
  mstr_discrete res *
  page90_i80
#CELL
  mstr_discrete res *
  page90_i81
#ISCELL
  mstr_standard offpage *
  page90_i82
#ISCELL
  mstr_standard offpage *
  page90_i83
#ISCELL
  mstr_standard offpage *
  page90_i84
#CELL
  mstr_discrete res *
  page90_i85
#CELL
  mstr_discrete res *
  page90_i86
#ISCELL
  mstr_symbols gnd *
  page90_i87
#CELL
  mstr_discrete res *
  page90_i88
#ISCELL
  mstr_standard offpage *
  page90_i89
#ISCELL
  mstr_standard offpage *
  page90_i9
#ISCELL
  mstr_standard offpage *
  page90_i90
#ISCELL
  mstr_standard offpage *
  page90_i91
#ISCELL
  mstr_symbols design_note *
  *
#ISCELL
  mstr_symbols intel_corp_bpage *
  *
#CELL
  mstr_sconn sconn24_h46321001 *
  page91_i1
#ISCELL
  mstr_standard offpage *
  page91_i10
#ISCELL
  mstr_standard offpage *
  page91_i11
#ISCELL
  mstr_standard offpage *
  page91_i12
#CELL
  mstr_discrete res *
  page91_i14
#CELL
  mstr_discrete res *
  page91_i16
#CELL
  mstr_discrete res *
  page91_i17
#CELL
  mstr_discrete res *
  page91_i18
#ISCELL
  mstr_symbols gnd *
  page91_i2
#CELL
  mstr_discrete res *
  page91_i20
#CELL
  mstr_discrete res *
  page91_i21
#CELL
  mstr_discrete res *
  page91_i22
#CELL
  mstr_discrete res *
  page91_i24
#ISCELL
  mstr_standard offpage *
  page91_i25
#ISCELL
  mstr_standard offpage *
  page91_i26
#ISCELL
  mstr_standard offpage *
  page91_i27
#ISCELL
  mstr_standard offpage *
  page91_i28
#ISCELL
  mstr_standard offpage *
  page91_i29
#ISCELL
  mstr_standard offpage *
  page91_i3
#ISCELL
  mstr_symbols pvpp_abc *
  page91_i30
#ISCELL
  mstr_symbols pvpp_abc *
  page91_i31
#ISCELL
  mstr_symbols pvpp_abc *
  page91_i32
#ISCELL
  mstr_symbols p3v3 *
  page91_i33
#CELL
  mstr_discrete res *
  page91_i34
#CELL
  mstr_discrete res *
  page91_i35
#CELL
  mstr_discrete res *
  page91_i36
#CELL
  mstr_discrete res *
  page91_i37
#ISCELL
  mstr_symbols gnd *
  page91_i38
#ISCELL
  mstr_standard offpage *
  page91_i4
#ISCELL
  mstr_standard offpage *
  page91_i5
#ISCELL
  mstr_standard offpage *
  page91_i6
#ISCELL
  mstr_standard offpage *
  page91_i7
#ISCELL
  mstr_standard offpage *
  page91_i8
#ISCELL
  mstr_standard offpage *
  page91_i9
#ISCELL
  mstr_symbols cad_note *
  *
#ISCELL
  mstr_symbols design_note *
  *
#ISCELL
  mstr_symbols intel_corp_bpage *
  *
#CELL
  mstr_digital gtl2014 *
  page92_i1
#ISCELL
  mstr_symbols pvccio_cpu1 *
  page92_i10
#CELL
  mstr_discrete res *
  page92_i100
#CELL
  mstr_discrete res *
  page92_i101
#ISCELL
  mstr_standard offpage *
  page92_i102
#ISCELL
  mstr_standard offpage *
  page92_i103
#ISCELL
  mstr_symbols pvccio_cpu0 *
  page92_i104
#CELL
  mstr_discrete res *
  page92_i12
#CELL
  mstr_discrete res *
  page92_i13
#CELL
  mstr_discrete res *
  page92_i14
#ISCELL
  mstr_standard offpage *
  page92_i16
#ISCELL
  mstr_standard offpage *
  page92_i18
#CELL
  mstr_discrete res *
  page92_i19
#ISCELL
  mstr_symbols gnd *
  page92_i2
#ISCELL
  mstr_standard offpage *
  page92_i20
#ISCELL
  mstr_standard offpage *
  page92_i22
#CELL
  mstr_discrete res *
  page92_i24
#ISCELL
  mstr_standard offpage *
  page92_i27
#CELL
  mstr_discrete res *
  page92_i29
#ISCELL
  mstr_standard offpage *
  page92_i3
#CELL
  mstr_discrete res *
  page92_i30
#CELL
  mstr_digital gtl2014 *
  page92_i32
#ISCELL
  mstr_symbols gnd *
  page92_i33
#ISCELL
  mstr_standard offpage *
  page92_i36
#CELL
  dev_discrete cap_a *
  page92_i37
#CELL
  mstr_discrete res *
  page92_i38
#CELL
  mstr_discrete res *
  page92_i39
#ISCELL
  mstr_symbols gnd *
  page92_i41
#ISCELL
  mstr_symbols p3v3 *
  page92_i42
#CELL
  mstr_discrete res *
  page92_i46
#ISCELL
  mstr_symbols gnd *
  page92_i47
#CELL
  mstr_discrete res *
  page92_i48
#ISCELL
  mstr_symbols gnd *
  page92_i49
#ISCELL
  mstr_standard offpage *
  page92_i5
#ISCELL
  mstr_symbols pvccio_cpu0 *
  page92_i50
#CELL
  mstr_discrete res *
  page92_i51
#CELL
  dev_discrete cap_a *
  page92_i52
#ISCELL
  mstr_symbols gnd *
  page92_i53
#CELL
  mstr_discrete res *
  page92_i54
#ISCELL
  mstr_symbols p3v3 *
  page92_i58
#ISCELL
  mstr_standard offpage *
  page92_i59
#ISCELL
  mstr_standard offpage *
  page92_i60
#CELL
  mstr_discrete res *
  page92_i61
#ISCELL
  mstr_standard offpage *
  page92_i62
#ISCELL
  mstr_standard offpage *
  page92_i63
#CELL
  mstr_discrete res *
  page92_i64
#CELL
  mstr_discrete res *
  page92_i65
#ISCELL
  mstr_symbols pvccio_cpu0 *
  page92_i66
#CELL
  mstr_discrete res *
  page92_i67
#CELL
  mstr_discrete res *
  page92_i68
#ISCELL
  mstr_standard offpage *
  page92_i69
#CELL
  mstr_discrete res *
  page92_i70
#CELL
  mstr_discrete res *
  page92_i75
#ISCELL
  mstr_symbols gnd *
  page92_i76
#CELL
  mstr_discrete cap *
  page92_i79
#ISCELL
  mstr_symbols gnd *
  page92_i80
#ISCELL
  mstr_symbols pvccio_cpu0 *
  page92_i82
#CELL
  mstr_discrete cap *
  page92_i84
#ISCELL
  mstr_symbols gnd *
  page92_i85
#ISCELL
  mstr_standard offpage *
  page92_i88
#ISCELL
  mstr_standard offpage *
  page92_i89
#CELL
  mstr_discrete res *
  page92_i9
#ISCELL
  mstr_standard offpage *
  page92_i90
#ISCELL
  mstr_standard offpage *
  page92_i91
#CELL
  mstr_discrete res *
  page92_i92
#CELL
  mstr_discrete res *
  page92_i93
#CELL
  mstr_discrete res *
  page92_i94
#ISCELL
  mstr_symbols pvccio_cpu0 *
  page92_i95
#CELL
  mstr_discrete res *
  page92_i96
#CELL
  mstr_discrete res *
  page92_i97
#CELL
  mstr_discrete res *
  page92_i98
#ISCELL
  mstr_symbols pvccio_cpu0 *
  page92_i99
#ISCELL
  mstr_misc dns *
  *
#ISCELL
  mstr_symbols cad_note *
  *
#ISCELL
  mstr_symbols design_note *
  *
#ISCELL
  mstr_symbols intel_corp_bpage *
  *
#ISCELL
  mstr_standard offpage *
  page93_i100
#ISCELL
  mstr_standard offpage *
  page93_i101
#CELL
  mstr_discrete res *
  page93_i102
#CELL
  mstr_discrete res *
  page93_i103
#ISCELL
  mstr_symbols pvccio_cpu1 *
  page93_i105
#CELL
  mstr_discrete res *
  page93_i106
#CELL
  mstr_discrete res *
  page93_i107
#CELL
  mstr_discrete res *
  page93_i108
#CELL
  mstr_discrete res *
  page93_i109
#CELL
  mstr_discrete res *
  page93_i110
#CELL
  mstr_discrete res *
  page93_i111
#CELL
  mstr_discrete res *
  page93_i112
#CELL
  mstr_discrete res *
  page93_i113
#CELL
  mstr_discrete res *
  page93_i114
#ISCELL
  mstr_standard offpage *
  page93_i115
#ISCELL
  mstr_standard offpage *
  page93_i116
#ISCELL
  mstr_standard offpage *
  page93_i117
#ISCELL
  mstr_standard offpage *
  page93_i118
#CELL
  mstr_discrete res *
  page93_i119
#ISCELL
  mstr_standard offpage *
  page93_i120
#CELL
  mstr_discrete res *
  page93_i121
#CELL
  mstr_discrete res *
  page93_i122
#CELL
  mstr_discrete res *
  page93_i123
#ISCELL
  mstr_standard offpage *
  page93_i124
#ISCELL
  mstr_standard offpage *
  page93_i125
#ISCELL
  mstr_standard offpage *
  page93_i126
#CELL
  mstr_discrete res *
  page93_i127
#ISCELL
  mstr_symbols gnd *
  page93_i128
#ISCELL
  mstr_standard offpage *
  page93_i129
#CELL
  mstr_discrete res *
  page93_i13
#ISCELL
  mstr_standard offpage *
  page93_i130
#CELL
  mstr_discrete res *
  page93_i131
#ISCELL
  mstr_standard offpage *
  page93_i132
#CELL
  mstr_discrete res *
  page93_i133
#ISCELL
  mstr_standard offpage *
  page93_i134
#CELL
  mstr_discrete res *
  page93_i135
#ISCELL
  mstr_standard offpage *
  page93_i136
#CELL
  mstr_discrete res *
  page93_i137
#ISCELL
  mstr_standard offpage *
  page93_i138
#CELL
  mstr_discrete res *
  page93_i143
#CELL
  mstr_discrete res *
  page93_i144
#CELL
  mstr_discrete res *
  page93_i15
#CELL
  mstr_discrete res *
  page93_i16
#ISCELL
  mstr_standard offpage *
  page93_i19
#CELL
  mstr_discrete res *
  page93_i23
#ISCELL
  mstr_symbols gnd *
  page93_i29
#CELL
  mstr_digital gtl2014 *
  page93_i30
#CELL
  mstr_discrete res *
  page93_i39
#ISCELL
  mstr_standard offpage *
  page93_i4
#CELL
  mstr_discrete res *
  page93_i40
#CELL
  mstr_discrete res *
  page93_i42
#ISCELL
  mstr_standard offpage *
  page93_i47
#ISCELL
  mstr_standard offpage *
  page93_i48
#ISCELL
  mstr_standard offpage *
  page93_i5
#ISCELL
  mstr_standard offpage *
  page93_i6
#CELL
  mstr_discrete res *
  page93_i62
#CELL
  mstr_discrete res *
  page93_i63
#ISCELL
  mstr_symbols pvccio_cpu0 *
  page93_i64
#CELL
  mstr_discrete res *
  page93_i67
#CELL
  mstr_discrete res *
  page93_i68
#ISCELL
  mstr_symbols p3v3 *
  page93_i70
#CELL
  dev_discrete cap_a *
  page93_i72
#ISCELL
  mstr_symbols gnd *
  page93_i73
#ISCELL
  mstr_standard offpage *
  page93_i76
#ISCELL
  mstr_standard offpage *
  page93_i77
#ISCELL
  mstr_symbols pvccio_cpu0 *
  page93_i78
#CELL
  mstr_discrete res *
  page93_i79
#ISCELL
  mstr_standard offpage *
  page93_i81
#ISCELL
  mstr_standard offpage *
  page93_i83
#CELL
  mstr_discrete res *
  page93_i87
#CELL
  mstr_discrete res *
  page93_i88
#CELL
  mstr_discrete res *
  page93_i89
#CELL
  mstr_discrete res *
  page93_i93
#CELL
  mstr_discrete res *
  page93_i94
#CELL
  dev_discrete cap_a *
  page93_i95
#ISCELL
  mstr_symbols pvccio_cpu0 *
  page93_i96
#CELL
  mstr_discrete res *
  page93_i97
#CELL
  mstr_discrete res *
  page93_i98
#ISCELL
  mstr_symbols gnd *
  page93_i99
#ISCELL
  mstr_symbols intel_corp_bpage *
  *
#CELL
  mstr_discrete res *
  page94_i100
#ISCELL
  mstr_standard offpage *
  page94_i101
#CELL
  mstr_discrete fet_n_dual *
  page94_i102
#ISCELL
  mstr_symbols pvpp_abc *
  page94_i103
#CELL
  mstr_discrete res *
  page94_i104
#ISCELL
  mstr_symbols gnd *
  page94_i105
#ISCELL
  mstr_standard offpage *
  page94_i39
#ISCELL
  mstr_symbols gnd *
  page94_i47
#CELL
  mstr_discrete fet_n_dual *
  page94_i49
#ISCELL
  mstr_symbols p3v3 *
  page94_i50
#CELL
  mstr_discrete res *
  page94_i51
#ISCELL
  mstr_symbols gnd *
  page94_i56
#ISCELL
  mstr_standard offpage *
  page94_i59
#CELL
  mstr_discrete fet_n_dual *
  page94_i60
#ISCELL
  mstr_standard offpage *
  page94_i61
#ISCELL
  mstr_symbols gnd *
  page94_i63
#CELL
  mstr_discrete fet_n_dual *
  page94_i64
#ISCELL
  mstr_symbols p3v3 *
  page94_i65
#CELL
  mstr_discrete res *
  page94_i66
#ISCELL
  mstr_symbols gnd *
  page94_i67
#ISCELL
  mstr_standard offpage *
  page94_i68
#CELL
  mstr_discrete fet_n_dual *
  page94_i69
#ISCELL
  mstr_standard offpage *
  page94_i70
#ISCELL
  mstr_standard offpage *
  page94_i71
#ISCELL
  mstr_symbols gnd *
  page94_i74
#CELL
  mstr_discrete fet_n_dual *
  page94_i75
#ISCELL
  mstr_symbols gnd *
  page94_i76
#CELL
  mstr_discrete fet_n_dual *
  page94_i77
#ISCELL
  mstr_symbols p3v3 *
  page94_i78
#CELL
  mstr_discrete res *
  page94_i79
#ISCELL
  mstr_symbols gnd *
  page94_i80
#ISCELL
  mstr_symbols p3v3 *
  page94_i81
#CELL
  mstr_discrete res *
  page94_i82
#ISCELL
  mstr_symbols gnd *
  page94_i83
#CELL
  mstr_discrete fet_n_dual *
  page94_i84
#ISCELL
  mstr_standard offpage *
  page94_i85
#ISCELL
  mstr_standard offpage *
  page94_i86
#CELL
  mstr_discrete fet_n_dual *
  page94_i89
#ISCELL
  mstr_standard offpage *
  page94_i90
#CELL
  mstr_discrete res *
  page94_i91
#ISCELL
  mstr_symbols p3v3_stby *
  page94_i92
#CELL
  mstr_discrete res *
  page94_i94
#ISCELL
  mstr_symbols gnd *
  page94_i95
#ISCELL
  mstr_symbols gnd *
  page94_i97
#CELL
  mstr_discrete fet_n_dual *
  page94_i98
#ISCELL
  mstr_symbols pvpp_abc *
  page94_i99
#ISCELL
  mstr_symbols cad_note *
  *
#ISCELL
  mstr_symbols intel_corp_bpage *
  *
#ISCELL
  mstr_symbols gnd *
  page95_i1
#CELL
  mstr_discrete fet_n *
  page95_i104
#ISCELL
  mstr_symbols gnd *
  page95_i105
#CELL
  mstr_discrete res *
  page95_i106
#ISCELL
  mstr_symbols p3v3 *
  page95_i107
#CELL
  mstr_discrete res *
  page95_i108
#ISCELL
  mstr_standard offpage *
  page95_i109
#ISCELL
  mstr_standard offpage *
  page95_i110
#CELL
  mstr_discrete fet_n_dual *
  page95_i111
#CELL
  mstr_discrete fet_n_dual *
  page95_i112
#CELL
  mstr_discrete fet_n_dual *
  page95_i113
#ISCELL
  mstr_symbols p3v3_stby *
  page95_i114
#CELL
  dev_discrete cap_a *
  page95_i115
#ISCELL
  mstr_symbols gnd *
  page95_i116
#CELL
  mstr_ttl ttl1g08 *
  page95_i117
#CELL
  mstr_ttl ttl1g08 *
  page95_i118
#CELL
  mstr_discrete fet_n *
  page95_i119
#ISCELL
  mstr_standard offpage *
  page95_i12
#ISCELL
  mstr_symbols gnd *
  page95_i120
#ISCELL
  mstr_standard offpage *
  page95_i121
#ISCELL
  mstr_standard offpage *
  page95_i13
#ISCELL
  mstr_standard offpage *
  page95_i14
#ISCELL
  mstr_standard offpage *
  page95_i18
#ISCELL
  mstr_standard offpage *
  page95_i19
#ISCELL
  mstr_standard offpage *
  page95_i22
#ISCELL
  mstr_symbols gnd *
  page95_i23
#ISCELL
  mstr_symbols gnd *
  page95_i26
#ISCELL
  mstr_symbols gnd *
  page95_i27
#CELL
  mstr_discrete fet_n_dual *
  page95_i28
#ISCELL
  mstr_symbols gnd *
  page95_i29
#ISCELL
  mstr_symbols gnd *
  page95_i30
#CELL
  mstr_discrete fet_n_dual *
  page95_i32
#CELL
  mstr_discrete fet_n_dual *
  page95_i33
#CELL
  mstr_discrete fet_n_dual *
  page95_i51
#CELL
  mstr_discrete fet_n_dual *
  page95_i52
#ISCELL
  mstr_standard offpage *
  page95_i58
#CELL
  mstr_discrete fet_n_dual *
  page95_i59
#ISCELL
  mstr_standard offpage *
  page95_i6
#ISCELL
  mstr_symbols gnd *
  page95_i60
#ISCELL
  mstr_symbols p3v3 *
  page95_i61
#CELL
  mstr_discrete res *
  page95_i62
#ISCELL
  mstr_symbols gnd *
  page95_i63
#ISCELL
  mstr_standard offpage *
  page95_i66
#ISCELL
  mstr_standard offpage *
  page95_i67
#ISCELL
  mstr_standard offpage *
  page95_i68
#CELL
  mstr_discrete fet_n_dual *
  page95_i69
#ISCELL
  mstr_symbols gnd *
  page95_i70
#ISCELL
  mstr_symbols p3v3 *
  page95_i71
#CELL
  mstr_discrete res *
  page95_i72
#ISCELL
  mstr_symbols gnd *
  page95_i73
#ISCELL
  mstr_standard offpage *
  page95_i76
#ISCELL
  mstr_standard offpage *
  page95_i77
#CELL
  dev_discrete cap_a *
  page95_i92
#ISCELL
  mstr_symbols gnd *
  page95_i94
#ISCELL
  mstr_symbols p3v3_stby *
  page95_i98
#ISCELL
  mstr_symbols cad_note *
  *
#ISCELL
  mstr_symbols design_note *
  *
#ISCELL
  mstr_symbols intel_corp_bpage *
  *
#ISCELL
  mstr_symbols pvccio_cpu0 *
  page96_i1
#ISCELL
  mstr_standard offpage *
  page96_i10
#ISCELL
  mstr_standard offpage *
  page96_i11
#ISCELL
  mstr_standard offpage *
  page96_i14
#ISCELL
  mstr_standard offpage *
  page96_i15
#ISCELL
  mstr_standard offpage *
  page96_i16
#ISCELL
  mstr_standard offpage *
  page96_i17
#CELL
  mstr_discrete res *
  page96_i2
#ISCELL
  mstr_symbols pvccio_cpu1 *
  page96_i24
#CELL
  mstr_discrete res *
  page96_i25
#CELL
  mstr_discrete res *
  page96_i26
#ISCELL
  mstr_symbols pvddq_klm *
  page96_i27
#CELL
  mstr_discrete res *
  page96_i28
#ISCELL
  mstr_symbols pvddq_ghj *
  page96_i29
#CELL
  mstr_discrete res *
  page96_i3
#CELL
  mstr_discrete res *
  page96_i30
#CELL
  mstr_discrete res *
  page96_i36
#ISCELL
  mstr_symbols pvddq_def *
  page96_i4
#ISCELL
  mstr_symbols gnd *
  page96_i41
#CELL
  mstr_digital gtl2014 *
  page96_i42
#ISCELL
  mstr_symbols gnd *
  page96_i45
#CELL
  mstr_digital gtl2014 *
  page96_i46
#CELL
  mstr_discrete res *
  page96_i5
#ISCELL
  mstr_standard offpage *
  page96_i51
#ISCELL
  mstr_standard offpage *
  page96_i52
#ISCELL
  mstr_standard offpage *
  page96_i53
#CELL
  mstr_discrete res *
  page96_i55
#ISCELL
  mstr_standard offpage *
  page96_i59
#ISCELL
  mstr_symbols pvddq_abc *
  page96_i6
#ISCELL
  mstr_standard offpage *
  page96_i60
#ISCELL
  mstr_standard offpage *
  page96_i61
#ISCELL
  mstr_symbols p3v3_stby *
  page96_i65
#ISCELL
  mstr_symbols p3v3_stby *
  page96_i68
#CELL
  mstr_discrete res *
  page96_i69
#CELL
  mstr_discrete res *
  page96_i7
#ISCELL
  mstr_symbols gnd *
  page96_i70
#CELL
  mstr_discrete res *
  page96_i71
#ISCELL
  mstr_symbols gnd *
  page96_i72
#CELL
  dev_discrete cap_a *
  page96_i73
#ISCELL
  mstr_symbols gnd *
  page96_i74
#CELL
  dev_discrete cap_a *
  page96_i75
#ISCELL
  mstr_symbols gnd *
  page96_i76
#ISCELL
  mstr_standard offpage *
  page96_i8
#ISCELL
  mstr_standard offpage *
  page96_i9
#ISCELL
  mstr_symbols cad_note *
  *
#ISCELL
  mstr_symbols intel_corp_bpage *
  *
#ISCELL
  mstr_standard offpage *
  page97_i22
#CELL
  mstr_discrete res *
  page97_i33
#ISCELL
  mstr_standard offpage *
  page97_i34
#ISCELL
  mstr_symbols pvccio_cpu0 *
  page97_i41
#CELL
  mstr_discrete res *
  page97_i42
#CELL
  mstr_discrete res *
  page97_i44
#ISCELL
  mstr_symbols pvccio_cpu0 *
  page97_i71
#CELL
  mstr_discrete res *
  page97_i72
#ISCELL
  mstr_standard offpage *
  page97_i74
#CELL
  mstr_discrete res *
  page97_i76
#ISCELL
  mstr_standard offpage *
  page97_i77
#ISCELL
  mstr_symbols pvccio_cpu1 *
  page97_i78
#CELL
  mstr_discrete res *
  page97_i80
#CELL
  mstr_discrete res *
  page97_i81
#ISCELL
  mstr_symbols gnd *
  page97_i82
#ISCELL
  mstr_standard offpage *
  page97_i83
#ISCELL
  mstr_standard offpage *
  page97_i84
#ISCELL
  mstr_symbols pvccio_cpu0 *
  page97_i85
#ISCELL
  mstr_symbols cad_note *
  *
#ISCELL
  mstr_symbols intel_corp_bpage *
  *
#ISCELL
  mstr_symbols pvddq_abc *
  page98_i1
#ISCELL
  mstr_symbols pvddq_def *
  page98_i10
#ISCELL
  mstr_standard offpage *
  page98_i11
#CELL
  mstr_discrete res *
  page98_i12
#ISCELL
  mstr_symbols gnd *
  page98_i13
#CELL
  mstr_discrete res *
  page98_i14
#ISCELL
  mstr_standard offpage *
  page98_i16
#ISCELL
  mstr_standard offpage *
  page98_i3
#CELL
  dev_discrete cap_a *
  page98_i33
#CELL
  mstr_discrete res *
  page98_i36
#ISCELL
  mstr_symbols pvddq_abc *
  page98_i37
#CELL
  mstr_discrete res *
  page98_i38
#ISCELL
  mstr_standard offpage *
  page98_i39
#CELL
  mstr_discrete res *
  page98_i4
#CELL
  mstr_discrete res *
  page98_i40
#ISCELL
  mstr_symbols gnd *
  page98_i41
#CELL
  mstr_discrete res *
  page98_i42
#CELL
  dev_discrete cap_a *
  page98_i43
#ISCELL
  mstr_standard offpage *
  page98_i44
#ISCELL
  mstr_symbols pvddq_abc *
  page98_i45
#CELL
  mstr_discrete res *
  page98_i46
#ISCELL
  mstr_standard offpage *
  page98_i47
#CELL
  mstr_discrete res *
  page98_i48
#ISCELL
  mstr_symbols gnd *
  page98_i49
#CELL
  mstr_discrete res *
  page98_i5
#CELL
  mstr_discrete res *
  page98_i50
#CELL
  dev_discrete cap_a *
  page98_i51
#ISCELL
  mstr_standard offpage *
  page98_i52
#CELL
  mstr_discrete res *
  page98_i54
#ISCELL
  mstr_standard offpage *
  page98_i55
#CELL
  mstr_discrete res *
  page98_i56
#ISCELL
  mstr_symbols gnd *
  page98_i57
#CELL
  mstr_discrete res *
  page98_i58
#CELL
  dev_discrete cap_a *
  page98_i59
#ISCELL
  mstr_symbols gnd *
  page98_i6
#ISCELL
  mstr_standard offpage *
  page98_i60
#CELL
  mstr_discrete res *
  page98_i62
#ISCELL
  mstr_standard offpage *
  page98_i63
#CELL
  mstr_discrete res *
  page98_i64
#ISCELL
  mstr_symbols gnd *
  page98_i65
#CELL
  mstr_discrete res *
  page98_i66
#CELL
  dev_discrete cap_a *
  page98_i67
#ISCELL
  mstr_standard offpage *
  page98_i68
#ISCELL
  mstr_symbols pvddq_def *
  page98_i69
#CELL
  dev_discrete cap_a *
  page98_i7
#ISCELL
  mstr_symbols pvddq_def *
  page98_i70
#ISCELL
  mstr_standard offpage *
  page98_i8
#CELL
  mstr_discrete res *
  page98_i9
#ISCELL
  mstr_symbols intel_corp_bpage *
  *
#ISCELL
  mstr_symbols pvccio_cpu0 *
  page99_i1
#CELL
  mstr_discrete res *
  page99_i10
#ISCELL
  mstr_standard offpage *
  page99_i100
#CELL
  mstr_discrete res *
  page99_i101
#ISCELL
  mstr_symbols pvpp_def *
  page99_i102
#CELL
  mstr_discrete res *
  page99_i103
#CELL
  mstr_discrete res *
  page99_i104
#ISCELL
  mstr_symbols pvpp_ghj *
  page99_i105
#CELL
  mstr_discrete res *
  page99_i106
#CELL
  mstr_discrete res *
  page99_i107
#ISCELL
  mstr_symbols pvpp_klm *
  page99_i108
#CELL
  mstr_discrete res *
  page99_i109
#CELL
  mstr_discrete res *
  page99_i11
#CELL
  mstr_discrete res *
  page99_i110
#CELL
  mstr_discrete res *
  page99_i111
#CELL
  mstr_discrete res *
  page99_i112
#ISCELL
  mstr_symbols pvpp_abc *
  page99_i113
#ISCELL
  mstr_symbols pvpp_abc *
  page99_i114
#ISCELL
  mstr_symbols pvpp_abc *
  page99_i12
#CELL
  mstr_discrete res *
  page99_i13
#CELL
  mstr_digital pca9617 *
  page99_i15
#ISCELL
  mstr_symbols pvccio_cpu0 *
  page99_i16
#CELL
  mstr_discrete res *
  page99_i17
#ISCELL
  mstr_symbols pvccio_cpu0 *
  page99_i18
#CELL
  mstr_discrete res *
  page99_i19
#CELL
  dev_discrete cap_a *
  page99_i2
#CELL
  mstr_discrete res *
  page99_i20
#ISCELL
  mstr_symbols pvccio_cpu0 *
  page99_i21
#ISCELL
  mstr_symbols gnd *
  page99_i22
#CELL
  dev_discrete cap_a *
  page99_i23
#ISCELL
  mstr_standard offpage *
  page99_i24
#ISCELL
  mstr_standard offpage *
  page99_i25
#ISCELL
  mstr_symbols pvccio_cpu1 *
  page99_i26
#CELL
  dev_discrete cap_a *
  page99_i27
#ISCELL
  mstr_symbols gnd *
  page99_i28
#ISCELL
  mstr_standard offpage *
  page99_i29
#ISCELL
  mstr_symbols gnd *
  page99_i3
#ISCELL
  mstr_standard offpage *
  page99_i30
#ISCELL
  mstr_symbols pvpp_def *
  page99_i31
#CELL
  dev_discrete cap_a *
  page99_i32
#ISCELL
  mstr_symbols gnd *
  page99_i33
#CELL
  mstr_discrete res *
  page99_i34
#CELL
  mstr_discrete res *
  page99_i35
#ISCELL
  mstr_symbols pvpp_ghj *
  page99_i39
#ISCELL
  mstr_standard offpage *
  page99_i4
#ISCELL
  mstr_symbols gnd *
  page99_i40
#CELL
  dev_discrete cap_a *
  page99_i41
#CELL
  mstr_discrete res *
  page99_i42
#CELL
  mstr_discrete res *
  page99_i43
#CELL
  dev_discrete cap_a *
  page99_i47
#ISCELL
  mstr_symbols pvccio_cpu1 *
  page99_i48
#ISCELL
  mstr_symbols gnd *
  page99_i49
#ISCELL
  mstr_standard offpage *
  page99_i5
#ISCELL
  mstr_standard offpage *
  page99_i50
#ISCELL
  mstr_standard offpage *
  page99_i51
#ISCELL
  mstr_symbols pvpp_klm *
  page99_i52
#CELL
  dev_discrete cap_a *
  page99_i53
#ISCELL
  mstr_symbols gnd *
  page99_i54
#CELL
  mstr_discrete res *
  page99_i55
#CELL
  mstr_discrete res *
  page99_i56
#ISCELL
  mstr_symbols pvpp_def *
  page99_i60
#CELL
  mstr_digital pca9617 *
  page99_i61
#ISCELL
  mstr_symbols pvpp_ghj *
  page99_i62
#CELL
  mstr_digital pca9617 *
  page99_i63
#ISCELL
  mstr_symbols pvccio_cpu0 *
  page99_i64
#CELL
  mstr_discrete res *
  page99_i65
#ISCELL
  mstr_symbols pvccio_cpu0 *
  page99_i66
#CELL
  mstr_discrete res *
  page99_i67
#ISCELL
  mstr_symbols pvccio_cpu1 *
  page99_i69
#CELL
  dev_discrete cap_a *
  page99_i7
#CELL
  mstr_discrete res *
  page99_i70
#ISCELL
  mstr_symbols pvccio_cpu1 *
  page99_i71
#CELL
  mstr_discrete res *
  page99_i72
#ISCELL
  mstr_symbols pvpp_klm *
  page99_i74
#CELL
  mstr_digital pca9617 *
  page99_i75
#ISCELL
  mstr_symbols pvccio_cpu1 *
  page99_i76
#CELL
  mstr_discrete res *
  page99_i77
#ISCELL
  mstr_symbols pvccio_cpu1 *
  page99_i78
#CELL
  mstr_discrete res *
  page99_i79
#ISCELL
  mstr_symbols gnd *
  page99_i8
#CELL
  mstr_discrete res *
  page99_i83
#ISCELL
  mstr_standard offpage *
  page99_i84
#ISCELL
  mstr_standard offpage *
  page99_i85
#CELL
  mstr_discrete res *
  page99_i88
#ISCELL
  mstr_standard offpage *
  page99_i89
#CELL
  mstr_discrete res *
  page99_i9
#CELL
  mstr_discrete res *
  page99_i92
#ISCELL
  mstr_standard offpage *
  page99_i93
#ISCELL
  mstr_standard offpage *
  page99_i94
#ISCELL
  mstr_standard offpage *
  page99_i95
#CELL
  mstr_discrete res *
  page99_i98
#ISCELL
  mstr_standard offpage *
  page99_i99
#ISCELL
  mstr_symbols cad_note *
  *
#ISCELL
  mstr_symbols intel_corp_bpage *
  *
#ISCELL
  mstr_standard offpage *
  page100_i1
#ISCELL
  mstr_symbols pvddq_klm *
  page100_i10
#CELL
  mstr_discrete res *
  page100_i11
#ISCELL
  mstr_standard offpage *
  page100_i12
#CELL
  mstr_discrete res *
  page100_i13
#ISCELL
  mstr_symbols gnd *
  page100_i14
#CELL
  dev_discrete cap_a *
  page100_i15
#ISCELL
  mstr_standard offpage *
  page100_i16
#ISCELL
  mstr_symbols pvddq_ghj *
  page100_i17
#ISCELL
  mstr_standard offpage *
  page100_i18
#CELL
  mstr_discrete res *
  page100_i19
#CELL
  mstr_discrete res *
  page100_i2
#CELL
  mstr_discrete res *
  page100_i20
#ISCELL
  mstr_symbols pvddq_klm *
  page100_i21
#CELL
  mstr_discrete res *
  page100_i22
#ISCELL
  mstr_standard offpage *
  page100_i23
#CELL
  mstr_discrete res *
  page100_i24
#CELL
  mstr_discrete res *
  page100_i25
#CELL
  dev_discrete cap_a *
  page100_i26
#ISCELL
  mstr_standard offpage *
  page100_i27
#ISCELL
  mstr_symbols gnd *
  page100_i28
#CELL
  mstr_discrete res *
  page100_i29
#ISCELL
  mstr_standard offpage *
  page100_i3
#CELL
  dev_discrete cap_a *
  page100_i30
#ISCELL
  mstr_symbols gnd *
  page100_i31
#ISCELL
  mstr_standard offpage *
  page100_i32
#ISCELL
  mstr_symbols pvddq_ghj *
  page100_i33
#ISCELL
  mstr_standard offpage *
  page100_i34
#CELL
  mstr_discrete res *
  page100_i35
#CELL
  mstr_discrete res *
  page100_i36
#ISCELL
  mstr_symbols pvddq_klm *
  page100_i37
#CELL
  mstr_discrete res *
  page100_i38
#ISCELL
  mstr_standard offpage *
  page100_i39
#CELL
  mstr_discrete res *
  page100_i4
#CELL
  mstr_discrete res *
  page100_i40
#CELL
  mstr_discrete res *
  page100_i41
#CELL
  dev_discrete cap_a *
  page100_i42
#ISCELL
  mstr_standard offpage *
  page100_i43
#ISCELL
  mstr_symbols gnd *
  page100_i44
#CELL
  mstr_discrete res *
  page100_i45
#CELL
  dev_discrete cap_a *
  page100_i46
#ISCELL
  mstr_symbols gnd *
  page100_i47
#ISCELL
  mstr_standard offpage *
  page100_i48
#ISCELL
  mstr_symbols pvddq_ghj *
  page100_i5
#CELL
  mstr_discrete res *
  page100_i6
#CELL
  mstr_discrete res *
  page100_i7
#CELL
  dev_discrete cap_a *
  page100_i8
#ISCELL
  mstr_symbols gnd *
  page100_i9
#ISCELL
  mstr_symbols cad_note *
  *
#ISCELL
  mstr_symbols intel_corp_bpage *
  *
#ISCELL
  mstr_symbols vcc_core *
  page101_i100
#ISCELL
  mstr_symbols vcc_core *
  page101_i101
#ISCELL
  mstr_symbols vcc_core *
  page101_i102
#ISCELL
  mstr_symbols vcc_core *
  page101_i103
#CELL
  dev_discrete cap_a *
  page101_i104
#CELL
  mstr_discrete res *
  page101_i105
#CELL
  dev_discrete cap_a *
  page101_i106
#ISCELL
  mstr_symbols gnd *
  page101_i107
#ISCELL
  mstr_symbols gnd *
  page101_i108
#CELL
  dev_discrete cap_a *
  page101_i109
#CELL
  dev_discrete cap_a *
  page101_i110
#CELL
  dev_discrete cap_a *
  page101_i111
#CELL
  dev_discrete cap_a *
  page101_i112
#CELL
  mstr_discrete cap *
  page101_i113
#CELL
  mstr_discrete ferrite *
  page101_i114
#ISCELL
  mstr_symbols p3v3_stby *
  page101_i115
#CELL
  dev_discrete cap_a *
  page101_i116
#ISCELL
  mstr_symbols vcc_core *
  page101_i117
#ISCELL
  mstr_symbols vcc_core *
  page101_i118
#ISCELL
  mstr_symbols vcc_core *
  page101_i119
#ISCELL
  mstr_symbols vcc_core *
  page101_i120
#ISCELL
  mstr_symbols vcc_core *
  page101_i121
#ISCELL
  mstr_symbols vcc_core *
  page101_i122
#ISCELL
  mstr_symbols vcc_core *
  page101_i123
#CELL
  mstr_discrete res *
  page101_i124
#CELL
  mstr_discrete res *
  page101_i125
#CELL
  mstr_discrete res *
  page101_i129
#ISCELL
  mstr_standard offpage *
  page101_i13
#CELL
  mstr_discrete res *
  page101_i130
#CELL
  mstr_discrete res *
  page101_i131
#CELL
  mstr_discrete res *
  page101_i132
#CELL
  mstr_discrete res *
  page101_i133
#ISCELL
  mstr_standard offpage *
  page101_i14
#CELL
  mstr_discrete res *
  page101_i20
#CELL
  mstr_discrete res *
  page101_i28
#ISCELL
  mstr_symbols gnd *
  page101_i29
#ISCELL
  mstr_symbols gnd *
  page101_i33
#CELL
  mstr_clock ics9fgp204 *
  page101_i34
#CELL
  mstr_discrete res *
  page101_i48
#CELL
  mstr_discrete cap *
  page101_i49
#CELL
  mstr_discrete crystal *
  page101_i52
#CELL
  mstr_discrete cap *
  page101_i53
#ISCELL
  mstr_symbols gnd *
  page101_i54
#ISCELL
  mstr_standard offpage *
  page101_i55
#ISCELL
  mstr_symbols gnd *
  page101_i58
#ISCELL
  mstr_standard offpage *
  page101_i59
#ISCELL
  mstr_standard offpage *
  page101_i60
#ISCELL
  mstr_symbols gnd *
  page101_i64
#ISCELL
  mstr_standard offpage *
  page101_i71
#ISCELL
  mstr_standard offpage *
  page101_i72
#ISCELL
  mstr_standard offpage *
  page101_i79
#ISCELL
  mstr_standard offpage *
  page101_i80
#ISCELL
  mstr_standard offpage *
  page101_i81
#ISCELL
  mstr_standard offpage *
  page101_i87
#CELL
  dev_discrete cap_a *
  page101_i89
#CELL
  dev_discrete cap_a *
  page101_i90
#CELL
  mstr_discrete res *
  page101_i94
#CELL
  mstr_discrete res *
  page101_i95
#ISCELL
  mstr_symbols gnd *
  page101_i96
#CELL
  dev_discrete cap_a *
  page101_i97
#ISCELL
  mstr_symbols gnd *
  page101_i98
#CELL
  dev_discrete cap_a *
  page101_i99
#ISCELL
  mstr_misc dns *
  *
#ISCELL
  mstr_symbols design_note *
  *
#ISCELL
  mstr_symbols intel_corp_bpage *
  *
#CELL
  mstr_clock nb3w1200l *
  page102_i1
#CELL
  mstr_discrete cap *
  page102_i10
#CELL
  dev_discrete cap_a *
  page102_i11
#CELL
  dev_discrete cap_a *
  page102_i12
#CELL
  dev_discrete cap_a *
  page102_i13
#CELL
  dev_discrete cap_a *
  page102_i14
#CELL
  dev_discrete cap_a *
  page102_i15
#CELL
  dev_discrete cap_a *
  page102_i16
#ISCELL
  mstr_symbols gnd *
  page102_i17
#CELL
  dev_discrete cap_a *
  page102_i18
#CELL
  dev_discrete cap_a *
  page102_i19
#CELL
  mstr_discrete res *
  page102_i21
#ISCELL
  mstr_symbols gnd *
  page102_i22
#ISCELL
  mstr_symbols vcc_core *
  page102_i23
#ISCELL
  mstr_symbols vcc_core *
  page102_i24
#ISCELL
  mstr_symbols vcc_core *
  page102_i25
#CELL
  mstr_discrete res *
  page102_i26
#ISCELL
  mstr_symbols vcc_core *
  page102_i27
#CELL
  dev_discrete cap_a *
  page102_i28
#ISCELL
  mstr_symbols gnd *
  page102_i29
#CELL
  dev_discrete cap_a *
  page102_i30
#ISCELL
  mstr_standard offpage *
  page102_i31
#ISCELL
  mstr_standard offpage *
  page102_i32
#ISCELL
  mstr_standard offpage *
  page102_i33
#ISCELL
  mstr_standard offpage *
  page102_i34
#ISCELL
  mstr_standard offpage *
  page102_i35
#ISCELL
  mstr_standard offpage *
  page102_i36
#CELL
  mstr_discrete res *
  page102_i37
#CELL
  mstr_discrete res *
  page102_i38
#ISCELL
  mstr_standard offpage *
  page102_i4
#ISCELL
  mstr_standard offpage *
  page102_i41
#ISCELL
  mstr_standard offpage *
  page102_i42
#ISCELL
  mstr_symbols vcc_core *
  page102_i43
#ISCELL
  mstr_symbols gnd *
  page102_i44
#CELL
  mstr_discrete res *
  page102_i45
#CELL
  mstr_discrete res *
  page102_i46
#CELL
  mstr_discrete res *
  page102_i47
#ISCELL
  mstr_symbols vcc_core *
  page102_i49
#ISCELL
  mstr_standard offpage *
  page102_i5
#ISCELL
  mstr_symbols gnd *
  page102_i50
#ISCELL
  mstr_standard offpage *
  page102_i51
#ISCELL
  mstr_standard offpage *
  page102_i52
#CELL
  mstr_discrete res *
  page102_i53
#ISCELL
  mstr_standard offpage *
  page102_i54
#ISCELL
  mstr_standard offpage *
  page102_i55
#ISCELL
  mstr_standard offpage *
  page102_i56
#ISCELL
  mstr_standard offpage *
  page102_i57
#ISCELL
  mstr_standard offpage *
  page102_i58
#ISCELL
  mstr_standard offpage *
  page102_i59
#ISCELL
  mstr_symbols gnd *
  page102_i6
#ISCELL
  mstr_standard offpage *
  page102_i60
#ISCELL
  mstr_standard offpage *
  page102_i61
#ISCELL
  mstr_standard offpage *
  page102_i62
#ISCELL
  mstr_standard offpage *
  page102_i63
#ISCELL
  mstr_standard offpage *
  page102_i64
#ISCELL
  mstr_standard offpage *
  page102_i65
#ISCELL
  mstr_standard offpage *
  page102_i66
#ISCELL
  mstr_standard offpage *
  page102_i67
#ISCELL
  mstr_standard offpage *
  page102_i68
#ISCELL
  mstr_standard offpage *
  page102_i69
#ISCELL
  mstr_standard offpage *
  page102_i7
#ISCELL
  mstr_standard offpage *
  page102_i70
#ISCELL
  mstr_standard offpage *
  page102_i71
#ISCELL
  mstr_standard offpage *
  page102_i72
#ISCELL
  mstr_standard offpage *
  page102_i73
#ISCELL
  mstr_standard offpage *
  page102_i74
#ISCELL
  mstr_standard offpage *
  page102_i75
#ISCELL
  mstr_standard offpage *
  page102_i76
#ISCELL
  mstr_standard offpage *
  page102_i77
#CELL
  dev_discrete cap_a *
  page102_i79
#CELL
  mstr_discrete ferrite *
  page102_i8
#CELL
  mstr_discrete res *
  page102_i80
#CELL
  mstr_discrete res *
  page102_i81
#CELL
  mstr_discrete res *
  page102_i82
#ISCELL
  mstr_standard offpage *
  page102_i83
#ISCELL
  mstr_standard offpage *
  page102_i84
#ISCELL
  mstr_standard offpage *
  page102_i85
#ISCELL
  mstr_standard offpage *
  page102_i86
#CELL
  mstr_discrete res *
  page102_i87
#ISCELL
  mstr_standard offpage *
  page102_i89
#ISCELL
  mstr_symbols p3v3 *
  page102_i9
#ISCELL
  mstr_standard offpage *
  page102_i90
#CELL
  mstr_discrete res *
  page102_i91
#CELL
  mstr_discrete res *
  page102_i93
#CELL
  mstr_discrete res *
  page102_i94
#ISCELL
  mstr_symbols p3v3 *
  page102_i95
#ISCELL
  mstr_standard offpage *
  page102_i96
#ISCELL
  mstr_standard offpage *
  page102_i97
#ISCELL
  mstr_standard offpage *
  page102_i98
#ISCELL
  mstr_standard offpage *
  page102_i99
#ISCELL
  mstr_misc dns *
  *
#ISCELL
  mstr_symbols cad_note *
  *
#ISCELL
  mstr_symbols design_note *
  *
#ISCELL
  mstr_symbols intel_corp_bpage *
  *
#CELL
  mstr_discrete res *
  page103_i1
#ISCELL
  mstr_standard offpage *
  page103_i10
#ISCELL
  mstr_standard offpage *
  page103_i100
#ISCELL
  mstr_standard offpage *
  page103_i102
#CELL
  mstr_discrete res *
  page103_i104
#ISCELL
  mstr_standard offpage *
  page103_i105
#ISCELL
  mstr_standard offpage *
  page103_i108
#CELL
  mstr_discrete res *
  page103_i109
#ISCELL
  mstr_standard offpage *
  page103_i11
#ISCELL
  mstr_standard offpage *
  page103_i110
#ISCELL
  mstr_standard offpage *
  page103_i113
#CELL
  mstr_discrete res *
  page103_i114
#ISCELL
  mstr_standard offpage *
  page103_i115
#ISCELL
  mstr_standard offpage *
  page103_i118
#CELL
  mstr_discrete res *
  page103_i119
#ISCELL
  mstr_standard offpage *
  page103_i120
#CELL
  mstr_discrete res *
  page103_i121
#CELL
  mstr_discrete res *
  page103_i123
#CELL
  mstr_discrete res *
  page103_i125
#ISCELL
  mstr_symbols gnd *
  page103_i126
#CELL
  mstr_discrete res *
  page103_i127
#ISCELL
  mstr_symbols gnd *
  page103_i128
#CELL
  mstr_discrete res *
  page103_i129
#ISCELL
  mstr_symbols gnd *
  page103_i130
#CELL
  mstr_discrete res *
  page103_i131
#ISCELL
  mstr_symbols gnd *
  page103_i132
#CELL
  mstr_discrete res *
  page103_i133
#ISCELL
  mstr_symbols gnd *
  page103_i134
#CELL
  mstr_discrete res *
  page103_i135
#ISCELL
  mstr_symbols gnd *
  page103_i136
#CELL
  mstr_discrete res *
  page103_i137
#ISCELL
  mstr_symbols gnd *
  page103_i138
#CELL
  mstr_discrete res *
  page103_i139
#CELL
  mstr_discrete res *
  page103_i14
#ISCELL
  mstr_symbols gnd *
  page103_i140
#CELL
  mstr_discrete res *
  page103_i141
#ISCELL
  mstr_symbols gnd *
  page103_i142
#CELL
  mstr_discrete res *
  page103_i143
#ISCELL
  mstr_symbols gnd *
  page103_i144
#CELL
  mstr_discrete res *
  page103_i145
#ISCELL
  mstr_symbols gnd *
  page103_i146
#CELL
  mstr_discrete res *
  page103_i147
#ISCELL
  mstr_symbols gnd *
  page103_i148
#CELL
  mstr_discrete res *
  page103_i149
#ISCELL
  mstr_standard offpage *
  page103_i15
#ISCELL
  mstr_symbols gnd *
  page103_i150
#CELL
  mstr_discrete res *
  page103_i151
#ISCELL
  mstr_symbols gnd *
  page103_i152
#CELL
  mstr_discrete res *
  page103_i153
#ISCELL
  mstr_symbols gnd *
  page103_i154
#CELL
  mstr_discrete res *
  page103_i155
#ISCELL
  mstr_symbols gnd *
  page103_i156
#CELL
  mstr_discrete res *
  page103_i157
#ISCELL
  mstr_symbols gnd *
  page103_i158
#CELL
  mstr_discrete res *
  page103_i159
#ISCELL
  mstr_standard offpage *
  page103_i16
#ISCELL
  mstr_symbols gnd *
  page103_i160
#CELL
  mstr_discrete res *
  page103_i161
#ISCELL
  mstr_symbols gnd *
  page103_i162
#CELL
  mstr_discrete res *
  page103_i163
#ISCELL
  mstr_symbols gnd *
  page103_i164
#CELL
  mstr_discrete res *
  page103_i165
#ISCELL
  mstr_symbols gnd *
  page103_i166
#CELL
  mstr_discrete res *
  page103_i167
#ISCELL
  mstr_symbols gnd *
  page103_i168
#ISCELL
  mstr_symbols gnd *
  page103_i169
#ISCELL
  mstr_symbols gnd *
  page103_i170
#CELL
  mstr_discrete res *
  page103_i19
#ISCELL
  mstr_standard offpage *
  page103_i20
#ISCELL
  mstr_standard offpage *
  page103_i21
#CELL
  mstr_discrete res *
  page103_i24
#ISCELL
  mstr_standard offpage *
  page103_i25
#ISCELL
  mstr_standard offpage *
  page103_i26
#CELL
  mstr_discrete res *
  page103_i29
#ISCELL
  mstr_standard offpage *
  page103_i30
#ISCELL
  mstr_standard offpage *
  page103_i31
#CELL
  mstr_discrete res *
  page103_i34
#ISCELL
  mstr_standard offpage *
  page103_i35
#ISCELL
  mstr_standard offpage *
  page103_i36
#CELL
  mstr_discrete res *
  page103_i39
#ISCELL
  mstr_standard offpage *
  page103_i4
#ISCELL
  mstr_standard offpage *
  page103_i40
#ISCELL
  mstr_standard offpage *
  page103_i41
#CELL
  mstr_discrete res *
  page103_i44
#ISCELL
  mstr_standard offpage *
  page103_i45
#ISCELL
  mstr_standard offpage *
  page103_i46
#CELL
  mstr_discrete res *
  page103_i49
#ISCELL
  mstr_standard offpage *
  page103_i5
#ISCELL
  mstr_standard offpage *
  page103_i50
#ISCELL
  mstr_standard offpage *
  page103_i51
#CELL
  mstr_discrete res *
  page103_i54
#ISCELL
  mstr_standard offpage *
  page103_i55
#ISCELL
  mstr_standard offpage *
  page103_i56
#CELL
  mstr_discrete res *
  page103_i59
#ISCELL
  mstr_standard offpage *
  page103_i6
#ISCELL
  mstr_standard offpage *
  page103_i60
#ISCELL
  mstr_standard offpage *
  page103_i61
#CELL
  mstr_discrete res *
  page103_i64
#ISCELL
  mstr_standard offpage *
  page103_i65
#ISCELL
  mstr_standard offpage *
  page103_i66
#CELL
  mstr_discrete res *
  page103_i69
#ISCELL
  mstr_standard offpage *
  page103_i70
#ISCELL
  mstr_standard offpage *
  page103_i71
#CELL
  mstr_discrete res *
  page103_i74
#ISCELL
  mstr_standard offpage *
  page103_i75
#ISCELL
  mstr_standard offpage *
  page103_i77
#CELL
  mstr_discrete res *
  page103_i79
#ISCELL
  mstr_standard offpage *
  page103_i80
#ISCELL
  mstr_standard offpage *
  page103_i82
#CELL
  mstr_discrete res *
  page103_i84
#ISCELL
  mstr_standard offpage *
  page103_i85
#ISCELL
  mstr_standard offpage *
  page103_i87
#CELL
  mstr_discrete res *
  page103_i89
#CELL
  mstr_discrete res *
  page103_i9
#ISCELL
  mstr_standard offpage *
  page103_i90
#ISCELL
  mstr_standard offpage *
  page103_i92
#CELL
  mstr_discrete res *
  page103_i94
#ISCELL
  mstr_standard offpage *
  page103_i95
#ISCELL
  mstr_standard offpage *
  page103_i97
#CELL
  mstr_discrete res *
  page103_i99
#ISCELL
  mstr_misc dns *
  *
#ISCELL
  mstr_symbols cad_note *
  *
#ISCELL
  mstr_symbols intel_corp_bpage *
  *
#ISCELL
  mstr_standard offpage *
  page104_i100
#ISCELL
  mstr_standard offpage *
  page104_i101
#ISCELL
  mstr_standard offpage *
  page104_i102
#ISCELL
  mstr_symbols p3v3 *
  page104_i24
#CELL
  dev_discrete cap_a *
  page104_i25
#ISCELL
  mstr_symbols gnd *
  page104_i26
#ISCELL
  mstr_symbols gnd *
  page104_i27
#ISCELL
  mstr_standard offpage *
  page104_i29
#ISCELL
  mstr_symbols gnd *
  page104_i31
#ISCELL
  mstr_symbols p3v3 *
  page104_i32
#ISCELL
  mstr_symbols gnd *
  page104_i33
#CELL
  dev_discrete cap_a *
  page104_i34
#ISCELL
  mstr_standard offpage *
  page104_i36
#CELL
  mstr_discrete res *
  page104_i37
#ISCELL
  mstr_standard offpage *
  page104_i38
#CELL
  mstr_discrete res *
  page104_i41
#ISCELL
  mstr_standard offpage *
  page104_i42
#ISCELL
  mstr_standard offpage *
  page104_i44
#ISCELL
  mstr_standard offpage *
  page104_i46
#ISCELL
  mstr_standard offpage *
  page104_i48
#CELL
  mstr_discrete res *
  page104_i51
#CELL
  mstr_discrete res *
  page104_i53
#ISCELL
  mstr_standard offpage *
  page104_i54
#ISCELL
  mstr_standard offpage *
  page104_i55
#ISCELL
  mstr_standard offpage *
  page104_i56
#ISCELL
  mstr_standard offpage *
  page104_i57
#ISCELL
  mstr_standard offpage *
  page104_i58
#ISCELL
  mstr_standard offpage *
  page104_i59
#ISCELL
  mstr_standard offpage *
  page104_i60
#CELL
  mstr_discrete res *
  page104_i67
#CELL
  mstr_discrete res *
  page104_i68
#CELL
  mstr_discrete res *
  page104_i69
#CELL
  mstr_discrete res *
  page104_i70
#CELL
  mstr_discrete osc_c *
  page104_i71
#CELL
  mstr_discrete osc_c *
  page104_i72
#ISCELL
  mstr_standard offpage *
  page104_i74
#ISCELL
  mstr_standard offpage *
  page104_i76
#ISCELL
  mstr_standard offpage *
  page104_i77
#CELL
  mstr_discrete res *
  page104_i78
#CELL
  mstr_discrete res *
  page104_i79
#ISCELL
  mstr_standard offpage *
  page104_i80
#ISCELL
  mstr_standard offpage *
  page104_i81
#ISCELL
  mstr_standard offpage *
  page104_i83
#CELL
  mstr_discrete res *
  page104_i84
#ISCELL
  mstr_standard offpage *
  page104_i86
#ISCELL
  mstr_standard offpage *
  page104_i87
#CELL
  mstr_discrete res *
  page104_i88
#ISCELL
  mstr_standard offpage *
  page104_i89
#ISCELL
  mstr_standard offpage *
  page104_i90
#ISCELL
  mstr_standard offpage *
  page104_i91
#ISCELL
  mstr_standard offpage *
  page104_i92
#CELL
  mstr_discrete res *
  page104_i93
#CELL
  mstr_discrete res *
  page104_i94
#CELL
  mstr_discrete res *
  page104_i95
#CELL
  mstr_discrete res *
  page104_i96
#CELL
  mstr_discrete res *
  page104_i97
#CELL
  mstr_discrete res *
  page104_i98
#ISCELL
  mstr_standard offpage *
  page104_i99
#ISCELL
  mstr_symbols cad_note *
  *
#ISCELL
  mstr_symbols intel_corp_bpage *
  *
#CELL
  mstr_discrete cap *
  page105_i1
#ISCELL
  mstr_standard tap *
  page105_i10
#ISCELL
  mstr_standard tap *
  page105_i11
#CELL
  mstr_discrete cap *
  page105_i12
#CELL
  mstr_discrete cap *
  page105_i13
#ISCELL
  mstr_standard tap *
  page105_i14
#ISCELL
  mstr_standard tap *
  page105_i15
#ISCELL
  mstr_standard tap *
  page105_i151
#ISCELL
  mstr_standard tap *
  page105_i152
#CELL
  mstr_discrete cap *
  page105_i153
#ISCELL
  mstr_standard tap *
  page105_i154
#ISCELL
  mstr_standard tap *
  page105_i155
#ISCELL
  mstr_standard tap *
  page105_i156
#ISCELL
  mstr_standard tap *
  page105_i157
#ISCELL
  mstr_standard tap *
  page105_i158
#ISCELL
  mstr_standard tap *
  page105_i159
#ISCELL
  mstr_standard tap *
  page105_i16
#CELL
  mstr_discrete cap *
  page105_i160
#ISCELL
  mstr_standard tap *
  page105_i161
#ISCELL
  mstr_standard tap *
  page105_i162
#CELL
  mstr_discrete cap *
  page105_i163
#ISCELL
  mstr_standard tap *
  page105_i164
#ISCELL
  mstr_standard tap *
  page105_i165
#CELL
  mstr_discrete cap *
  page105_i166
#ISCELL
  mstr_standard tap *
  page105_i167
#ISCELL
  mstr_standard tap *
  page105_i168
#CELL
  mstr_discrete cap *
  page105_i169
#ISCELL
  mstr_standard tap *
  page105_i17
#ISCELL
  mstr_standard tap *
  page105_i170
#ISCELL
  mstr_standard offpage *
  page105_i171
#ISCELL
  mstr_standard tap *
  page105_i172
#CELL
  mstr_discrete cap *
  page105_i173
#ISCELL
  mstr_standard tap *
  page105_i174
#CELL
  mstr_discrete cap *
  page105_i175
#ISCELL
  mstr_standard tap *
  page105_i176
#ISCELL
  mstr_standard tap *
  page105_i177
#ISCELL
  mstr_standard tap *
  page105_i178
#ISCELL
  mstr_standard tap *
  page105_i179
#ISCELL
  mstr_standard tap *
  page105_i18
#CELL
  mstr_discrete cap *
  page105_i180
#CELL
  mstr_discrete cap *
  page105_i181
#ISCELL
  mstr_standard tap *
  page105_i182
#ISCELL
  mstr_standard tap *
  page105_i183
#ISCELL
  mstr_standard tap *
  page105_i184
#CELL
  mstr_discrete cap *
  page105_i185
#ISCELL
  mstr_standard tap *
  page105_i186
#CELL
  mstr_discrete cap *
  page105_i187
#ISCELL
  mstr_standard tap *
  page105_i188
#CELL
  mstr_discrete cap *
  page105_i189
#ISCELL
  mstr_standard tap *
  page105_i19
#ISCELL
  mstr_standard tap *
  page105_i190
#ISCELL
  mstr_standard tap *
  page105_i191
#ISCELL
  mstr_standard tap *
  page105_i192
#CELL
  mstr_discrete cap *
  page105_i193
#ISCELL
  mstr_standard tap *
  page105_i194
#ISCELL
  mstr_standard tap *
  page105_i195
#CELL
  mstr_discrete cap *
  page105_i196
#ISCELL
  mstr_standard tap *
  page105_i197
#CELL
  mstr_discrete cap *
  page105_i198
#ISCELL
  mstr_standard offpage *
  page105_i199
#CELL
  mstr_discrete cap *
  page105_i20
#ISCELL
  mstr_standard tap *
  page105_i200
#CELL
  mstr_discrete cap *
  page105_i201
#ISCELL
  mstr_standard tap *
  page105_i202
#ISCELL
  mstr_standard offpage *
  page105_i203
#ISCELL
  mstr_standard offpage *
  page105_i204
#CELL
  mstr_discrete cap *
  page105_i205
#CELL
  mstr_discrete cap *
  page105_i206
#ISCELL
  mstr_standard offpage *
  page105_i207
#ISCELL
  mstr_standard offpage *
  page105_i208
#ISCELL
  mstr_standard tap *
  page105_i209
#CELL
  mstr_discrete cap *
  page105_i21
#ISCELL
  mstr_standard tap *
  page105_i210
#ISCELL
  mstr_standard tap *
  page105_i211
#CELL
  mstr_discrete cap *
  page105_i212
#ISCELL
  mstr_standard tap *
  page105_i213
#ISCELL
  mstr_standard tap *
  page105_i214
#ISCELL
  mstr_standard tap *
  page105_i215
#ISCELL
  mstr_standard tap *
  page105_i216
#CELL
  mstr_discrete cap *
  page105_i217
#CELL
  mstr_discrete cap *
  page105_i218
#ISCELL
  mstr_standard tap *
  page105_i219
#CELL
  mstr_discrete cap *
  page105_i22
#ISCELL
  mstr_standard tap *
  page105_i220
#ISCELL
  mstr_standard tap *
  page105_i221
#ISCELL
  mstr_standard tap *
  page105_i222
#CELL
  mstr_discrete cap *
  page105_i223
#ISCELL
  mstr_standard tap *
  page105_i224
#CELL
  mstr_discrete cap *
  page105_i225
#ISCELL
  mstr_standard tap *
  page105_i226
#ISCELL
  mstr_standard tap *
  page105_i227
#ISCELL
  mstr_standard tap *
  page105_i228
#CELL
  mstr_discrete cap *
  page105_i229
#ISCELL
  mstr_standard tap *
  page105_i23
#ISCELL
  mstr_standard tap *
  page105_i230
#ISCELL
  mstr_standard tap *
  page105_i231
#CELL
  mstr_discrete cap *
  page105_i232
#ISCELL
  mstr_standard tap *
  page105_i233
#CELL
  mstr_discrete cap *
  page105_i234
#ISCELL
  mstr_standard tap *
  page105_i235
#ISCELL
  mstr_standard tap *
  page105_i236
#ISCELL
  mstr_standard offpage *
  page105_i237
#ISCELL
  mstr_standard tap *
  page105_i238
#CELL
  mstr_discrete cap *
  page105_i239
#ISCELL
  mstr_standard tap *
  page105_i24
#ISCELL
  mstr_standard tap *
  page105_i240
#ISCELL
  mstr_standard tap *
  page105_i241
#ISCELL
  mstr_standard tap *
  page105_i242
#ISCELL
  mstr_standard tap *
  page105_i243
#CELL
  mstr_discrete cap *
  page105_i244
#ISCELL
  mstr_standard tap *
  page105_i245
#CELL
  mstr_discrete cap *
  page105_i246
#CELL
  mstr_discrete cap *
  page105_i247
#ISCELL
  mstr_standard tap *
  page105_i248
#ISCELL
  mstr_standard offpage *
  page105_i249
#ISCELL
  mstr_standard tap *
  page105_i25
#ISCELL
  mstr_standard tap *
  page105_i250
#ISCELL
  mstr_standard tap *
  page105_i251
#ISCELL
  mstr_standard tap *
  page105_i252
#CELL
  mstr_discrete cap *
  page105_i253
#ISCELL
  mstr_standard tap *
  page105_i254
#CELL
  mstr_discrete cap *
  page105_i255
#ISCELL
  mstr_standard tap *
  page105_i256
#ISCELL
  mstr_standard tap *
  page105_i26
#CELL
  mstr_discrete cap *
  page105_i27
#CELL
  mstr_discrete cap *
  page105_i28
#ISCELL
  mstr_standard tap *
  page105_i29
#ISCELL
  mstr_standard offpage *
  page105_i3
#ISCELL
  mstr_standard tap *
  page105_i30
#CELL
  mstr_discrete cap *
  page105_i31
#CELL
  mstr_discrete cap *
  page105_i32
#ISCELL
  mstr_standard tap *
  page105_i33
#CELL
  mstr_discrete cap *
  page105_i34
#ISCELL
  mstr_standard tap *
  page105_i35
#ISCELL
  mstr_standard tap *
  page105_i36
#CELL
  mstr_discrete cap *
  page105_i37
#ISCELL
  mstr_standard tap *
  page105_i38
#ISCELL
  mstr_standard tap *
  page105_i39
#ISCELL
  mstr_standard tap *
  page105_i4
#ISCELL
  mstr_standard tap *
  page105_i40
#ISCELL
  mstr_standard tap *
  page105_i41
#ISCELL
  mstr_standard tap *
  page105_i42
#ISCELL
  mstr_standard tap *
  page105_i43
#CELL
  mstr_discrete cap *
  page105_i44
#CELL
  mstr_discrete cap *
  page105_i45
#CELL
  mstr_discrete cap *
  page105_i46
#ISCELL
  mstr_standard tap *
  page105_i47
#ISCELL
  mstr_standard tap *
  page105_i48
#ISCELL
  mstr_standard tap *
  page105_i49
#ISCELL
  mstr_standard tap *
  page105_i5
#ISCELL
  mstr_standard tap *
  page105_i50
#CELL
  mstr_discrete cap *
  page105_i51
#CELL
  mstr_discrete cap *
  page105_i52
#ISCELL
  mstr_standard tap *
  page105_i53
#ISCELL
  mstr_standard tap *
  page105_i54
#CELL
  mstr_discrete cap *
  page105_i55
#CELL
  mstr_discrete cap *
  page105_i56
#ISCELL
  mstr_standard tap *
  page105_i57
#CELL
  mstr_discrete cap *
  page105_i58
#ISCELL
  mstr_standard tap *
  page105_i59
#CELL
  mstr_discrete cap *
  page105_i6
#ISCELL
  mstr_standard tap *
  page105_i60
#CELL
  mstr_discrete cap *
  page105_i61
#CELL
  mstr_discrete cap *
  page105_i62
#ISCELL
  mstr_standard tap *
  page105_i63
#ISCELL
  mstr_standard tap *
  page105_i64
#ISCELL
  mstr_standard tap *
  page105_i65
#ISCELL
  mstr_standard tap *
  page105_i66
#ISCELL
  mstr_standard tap *
  page105_i67
#ISCELL
  mstr_standard tap *
  page105_i68
#CELL
  mstr_discrete cap *
  page105_i69
#CELL
  mstr_discrete cap *
  page105_i7
#CELL
  mstr_discrete cap *
  page105_i70
#CELL
  mstr_discrete cap *
  page105_i71
#ISCELL
  mstr_standard tap *
  page105_i72
#ISCELL
  mstr_standard tap *
  page105_i73
#ISCELL
  mstr_standard tap *
  page105_i74
#CELL
  mstr_discrete cap *
  page105_i75
#CELL
  mstr_discrete cap *
  page105_i76
#ISCELL
  mstr_standard offpage *
  page105_i77
#ISCELL
  mstr_standard tap *
  page105_i78
#ISCELL
  mstr_standard tap *
  page105_i79
#CELL
  mstr_discrete cap *
  page105_i8
#ISCELL
  mstr_standard tap *
  page105_i80
#ISCELL
  mstr_standard tap *
  page105_i81
#ISCELL
  mstr_standard tap *
  page105_i82
#ISCELL
  mstr_standard tap *
  page105_i83
#ISCELL
  mstr_standard tap *
  page105_i84
#ISCELL
  mstr_standard tap *
  page105_i85
#ISCELL
  mstr_standard tap *
  page105_i86
#ISCELL
  mstr_standard tap *
  page105_i87
#ISCELL
  mstr_standard tap *
  page105_i88
#ISCELL
  mstr_standard tap *
  page105_i89
#ISCELL
  mstr_standard tap *
  page105_i9
#ISCELL
  mstr_standard tap *
  page105_i90
#ISCELL
  mstr_standard tap *
  page105_i91
#ISCELL
  mstr_standard tap *
  page105_i92
#CELL
  mstr_discrete cap *
  page105_i93
#ISCELL
  mstr_standard tap *
  page105_i94
#ISCELL
  mstr_standard offpage *
  page105_i95
#CELL
  mstr_discrete cap *
  page105_i96
#ISCELL
  mstr_standard tap *
  page105_i97
#ISCELL
  mstr_standard tap *
  page105_i98
#ISCELL
  mstr_standard offpage *
  page105_i99
#ISCELL
  mstr_symbols cad_note *
  *
#ISCELL
  mstr_symbols intel_corp_bpage *
  *
#CELL
  mstr_discrete cap *
  page106_i10
#CELL
  mstr_discrete cap *
  page106_i100
#ISCELL
  mstr_standard tap *
  page106_i101
#CELL
  mstr_discrete cap *
  page106_i102
#ISCELL
  mstr_standard tap *
  page106_i103
#ISCELL
  mstr_standard tap *
  page106_i104
#CELL
  mstr_discrete cap *
  page106_i105
#ISCELL
  mstr_standard tap *
  page106_i106
#ISCELL
  mstr_standard offpage *
  page106_i107
#ISCELL
  mstr_standard tap *
  page106_i108
#CELL
  mstr_discrete cap *
  page106_i109
#ISCELL
  mstr_standard tap *
  page106_i11
#ISCELL
  mstr_standard tap *
  page106_i110
#CELL
  mstr_discrete cap *
  page106_i111
#ISCELL
  mstr_standard tap *
  page106_i112
#ISCELL
  mstr_standard tap *
  page106_i113
#CELL
  mstr_discrete cap *
  page106_i114
#ISCELL
  mstr_standard tap *
  page106_i115
#ISCELL
  mstr_standard tap *
  page106_i116
#CELL
  mstr_discrete cap *
  page106_i117
#ISCELL
  mstr_standard tap *
  page106_i118
#ISCELL
  mstr_standard tap *
  page106_i119
#ISCELL
  mstr_standard offpage *
  page106_i120
#ISCELL
  mstr_standard tap *
  page106_i121
#CELL
  mstr_discrete cap *
  page106_i122
#CELL
  mstr_discrete cap *
  page106_i123
#ISCELL
  mstr_standard tap *
  page106_i124
#ISCELL
  mstr_standard tap *
  page106_i125
#ISCELL
  mstr_standard tap *
  page106_i126
#ISCELL
  mstr_standard tap *
  page106_i127
#CELL
  mstr_discrete cap *
  page106_i128
#ISCELL
  mstr_standard tap *
  page106_i129
#CELL
  mstr_discrete cap *
  page106_i130
#ISCELL
  mstr_standard tap *
  page106_i131
#ISCELL
  mstr_standard tap *
  page106_i133
#CELL
  mstr_discrete cap *
  page106_i134
#ISCELL
  mstr_standard tap *
  page106_i135
#ISCELL
  mstr_standard tap *
  page106_i136
#CELL
  mstr_discrete cap *
  page106_i137
#ISCELL
  mstr_standard tap *
  page106_i138
#ISCELL
  mstr_standard tap *
  page106_i140
#CELL
  mstr_discrete cap *
  page106_i141
#CELL
  mstr_discrete cap *
  page106_i142
#ISCELL
  mstr_standard tap *
  page106_i143
#ISCELL
  mstr_standard tap *
  page106_i144
#ISCELL
  mstr_standard tap *
  page106_i145
#ISCELL
  mstr_standard tap *
  page106_i146
#CELL
  mstr_discrete cap *
  page106_i147
#ISCELL
  mstr_standard tap *
  page106_i148
#ISCELL
  mstr_standard offpage *
  page106_i151
#ISCELL
  mstr_standard offpage *
  page106_i152
#ISCELL
  mstr_standard tap *
  page106_i25
#CELL
  mstr_discrete cap *
  page106_i26
#ISCELL
  mstr_standard tap *
  page106_i27
#ISCELL
  mstr_standard tap *
  page106_i28
#CELL
  mstr_discrete cap *
  page106_i29
#ISCELL
  mstr_standard tap *
  page106_i30
#ISCELL
  mstr_standard tap *
  page106_i36
#CELL
  mstr_discrete cap *
  page106_i37
#ISCELL
  mstr_standard tap *
  page106_i38
#ISCELL
  mstr_standard tap *
  page106_i39
#CELL
  mstr_discrete cap *
  page106_i40
#ISCELL
  mstr_standard tap *
  page106_i41
#ISCELL
  mstr_standard tap *
  page106_i54
#CELL
  mstr_discrete cap *
  page106_i55
#ISCELL
  mstr_standard tap *
  page106_i56
#ISCELL
  mstr_standard tap *
  page106_i58
#CELL
  mstr_discrete cap *
  page106_i59
#ISCELL
  mstr_standard tap *
  page106_i60
#ISCELL
  mstr_standard tap *
  page106_i69
#CELL
  mstr_discrete cap *
  page106_i70
#ISCELL
  mstr_standard tap *
  page106_i72
#ISCELL
  mstr_standard tap *
  page106_i73
#ISCELL
  mstr_standard tap *
  page106_i74
#ISCELL
  mstr_standard tap *
  page106_i75
#CELL
  mstr_discrete cap *
  page106_i76
#ISCELL
  mstr_standard tap *
  page106_i77
#CELL
  mstr_discrete cap *
  page106_i78
#ISCELL
  mstr_standard tap *
  page106_i79
#ISCELL
  mstr_standard tap *
  page106_i80
#ISCELL
  mstr_standard tap *
  page106_i81
#CELL
  mstr_discrete cap *
  page106_i82
#ISCELL
  mstr_standard tap *
  page106_i83
#ISCELL
  mstr_standard tap *
  page106_i84
#CELL
  mstr_discrete cap *
  page106_i85
#CELL
  mstr_discrete cap *
  page106_i86
#ISCELL
  mstr_standard tap *
  page106_i87
#ISCELL
  mstr_standard tap *
  page106_i88
#ISCELL
  mstr_standard tap *
  page106_i89
#ISCELL
  mstr_standard tap *
  page106_i9
#CELL
  mstr_discrete cap *
  page106_i90
#ISCELL
  mstr_standard tap *
  page106_i91
#CELL
  mstr_discrete cap *
  page106_i92
#ISCELL
  mstr_standard tap *
  page106_i93
#ISCELL
  mstr_standard tap *
  page106_i94
#CELL
  mstr_discrete cap *
  page106_i95
#ISCELL
  mstr_standard tap *
  page106_i96
#ISCELL
  mstr_standard tap *
  page106_i97
#ISCELL
  mstr_standard tap *
  page106_i98
#ISCELL
  mstr_standard tap *
  page106_i99
#ISCELL
  mstr_misc dns *
  *
#ISCELL
  mstr_symbols bom_note *
  *
#ISCELL
  mstr_symbols cad_note *
  *
#ISCELL
  mstr_symbols intel_corp_bpage *
  *
#ISCELL
  mstr_standard tap *
  page107_i198
#ISCELL
  mstr_standard tap *
  page107_i199
#ISCELL
  mstr_standard tap *
  page107_i200
#ISCELL
  mstr_standard tap *
  page107_i201
#ISCELL
  mstr_standard tap *
  page107_i202
#ISCELL
  mstr_standard tap *
  page107_i203
#ISCELL
  mstr_standard tap *
  page107_i204
#ISCELL
  mstr_standard tap *
  page107_i205
#ISCELL
  mstr_standard offpage *
  page107_i206
#CELL
  mstr_discrete cap *
  page107_i207
#CELL
  mstr_discrete cap *
  page107_i208
#ISCELL
  mstr_standard offpage *
  page107_i209
#ISCELL
  mstr_standard tap *
  page107_i210
#ISCELL
  mstr_standard tap *
  page107_i211
#CELL
  mstr_discrete cap *
  page107_i212
#ISCELL
  mstr_standard tap *
  page107_i213
#ISCELL
  mstr_standard tap *
  page107_i214
#CELL
  mstr_discrete cap *
  page107_i215
#CELL
  mstr_discrete cap *
  page107_i216
#ISCELL
  mstr_standard tap *
  page107_i217
#ISCELL
  mstr_standard tap *
  page107_i218
#CELL
  mstr_discrete cap *
  page107_i219
#ISCELL
  mstr_standard tap *
  page107_i220
#ISCELL
  mstr_standard tap *
  page107_i221
#ISCELL
  mstr_standard tap *
  page107_i222
#CELL
  mstr_discrete cap *
  page107_i223
#ISCELL
  mstr_standard tap *
  page107_i224
#ISCELL
  mstr_standard offpage *
  page107_i225
#CELL
  mstr_discrete cap *
  page107_i226
#ISCELL
  mstr_standard tap *
  page107_i227
#ISCELL
  mstr_standard tap *
  page107_i228
#CELL
  mstr_discrete cap *
  page107_i229
#ISCELL
  mstr_standard tap *
  page107_i230
#ISCELL
  mstr_standard tap *
  page107_i231
#CELL
  mstr_discrete cap *
  page107_i232
#ISCELL
  mstr_standard tap *
  page107_i233
#CELL
  mstr_discrete cap *
  page107_i234
#CELL
  mstr_discrete cap *
  page107_i235
#ISCELL
  mstr_standard tap *
  page107_i236
#ISCELL
  mstr_standard tap *
  page107_i237
#ISCELL
  mstr_standard tap *
  page107_i238
#ISCELL
  mstr_standard tap *
  page107_i239
#CELL
  mstr_discrete cap *
  page107_i240
#CELL
  mstr_discrete cap *
  page107_i241
#ISCELL
  mstr_standard tap *
  page107_i242
#ISCELL
  mstr_standard tap *
  page107_i243
#ISCELL
  mstr_standard offpage *
  page107_i244
#CELL
  mstr_discrete cap *
  page107_i245
#ISCELL
  mstr_standard tap *
  page107_i246
#ISCELL
  mstr_standard tap *
  page107_i247
#CELL
  mstr_discrete cap *
  page107_i248
#ISCELL
  mstr_standard tap *
  page107_i249
#ISCELL
  mstr_standard tap *
  page107_i250
#ISCELL
  mstr_standard tap *
  page107_i251
#ISCELL
  mstr_standard tap *
  page107_i252
#ISCELL
  mstr_standard tap *
  page107_i253
#ISCELL
  mstr_standard tap *
  page107_i254
#ISCELL
  mstr_standard offpage *
  page107_i255
#ISCELL
  mstr_standard offpage *
  page107_i256
#CELL
  mstr_discrete cap *
  page107_i257
#ISCELL
  mstr_standard tap *
  page107_i258
#ISCELL
  mstr_standard tap *
  page107_i259
#CELL
  mstr_discrete cap *
  page107_i260
#ISCELL
  mstr_standard tap *
  page107_i261
#ISCELL
  mstr_standard tap *
  page107_i262
#ISCELL
  mstr_standard tap *
  page107_i263
#CELL
  mstr_discrete cap *
  page107_i264
#CELL
  mstr_discrete cap *
  page107_i265
#ISCELL
  mstr_standard tap *
  page107_i266
#CELL
  mstr_discrete cap *
  page107_i267
#ISCELL
  mstr_standard tap *
  page107_i268
#ISCELL
  mstr_standard tap *
  page107_i269
#ISCELL
  mstr_standard tap *
  page107_i270
#ISCELL
  mstr_standard tap *
  page107_i271
#CELL
  mstr_discrete cap *
  page107_i272
#ISCELL
  mstr_standard tap *
  page107_i273
#CELL
  mstr_discrete cap *
  page107_i274
#ISCELL
  mstr_standard tap *
  page107_i275
#ISCELL
  mstr_standard tap *
  page107_i276
#CELL
  mstr_discrete cap *
  page107_i277
#CELL
  mstr_discrete cap *
  page107_i278
#CELL
  mstr_discrete cap *
  page107_i279
#ISCELL
  mstr_standard tap *
  page107_i280
#ISCELL
  mstr_standard tap *
  page107_i281
#ISCELL
  mstr_standard tap *
  page107_i282
#ISCELL
  mstr_standard tap *
  page107_i283
#ISCELL
  mstr_standard tap *
  page107_i284
#ISCELL
  mstr_standard offpage *
  page107_i285
#CELL
  mstr_discrete cap *
  page107_i286
#CELL
  mstr_discrete cap *
  page107_i287
#ISCELL
  mstr_standard tap *
  page107_i288
#ISCELL
  mstr_standard tap *
  page107_i289
#ISCELL
  mstr_standard tap *
  page107_i290
#ISCELL
  mstr_standard tap *
  page107_i291
#ISCELL
  mstr_standard tap *
  page107_i292
#ISCELL
  mstr_standard tap *
  page107_i293
#CELL
  mstr_discrete cap *
  page107_i294
#ISCELL
  mstr_standard offpage *
  page107_i295
#CELL
  mstr_discrete cap *
  page107_i296
#CELL
  mstr_discrete cap *
  page107_i297
#ISCELL
  mstr_standard tap *
  page107_i298
#ISCELL
  mstr_standard tap *
  page107_i299
#CELL
  mstr_discrete cap *
  page107_i300
#ISCELL
  mstr_standard tap *
  page107_i301
#ISCELL
  mstr_standard tap *
  page107_i355
#ISCELL
  mstr_standard tap *
  page107_i356
#ISCELL
  mstr_standard tap *
  page107_i357
#ISCELL
  mstr_standard tap *
  page107_i359
#ISCELL
  mstr_standard tap *
  page107_i360
#ISCELL
  mstr_standard tap *
  page107_i361
#ISCELL
  mstr_standard tap *
  page107_i363
#ISCELL
  mstr_standard tap *
  page107_i365
#ISCELL
  mstr_standard offpage *
  page107_i366
#ISCELL
  mstr_standard tap *
  page107_i367
#ISCELL
  mstr_standard offpage *
  page107_i368
#ISCELL
  mstr_standard offpage *
  page107_i369
#ISCELL
  mstr_standard tap *
  page107_i371
#ISCELL
  mstr_standard tap *
  page107_i372
#ISCELL
  mstr_standard tap *
  page107_i373
#ISCELL
  mstr_standard tap *
  page107_i375
#ISCELL
  mstr_standard tap *
  page107_i376
#ISCELL
  mstr_standard tap *
  page107_i379
#ISCELL
  mstr_standard tap *
  page107_i380
#ISCELL
  mstr_standard tap *
  page107_i382
#ISCELL
  mstr_standard tap *
  page107_i383
#ISCELL
  mstr_standard tap *
  page107_i384
#ISCELL
  mstr_standard tap *
  page107_i386
#ISCELL
  mstr_standard tap *
  page107_i388
#ISCELL
  mstr_standard tap *
  page107_i389
#ISCELL
  mstr_standard tap *
  page107_i391
#ISCELL
  mstr_standard tap *
  page107_i392
#ISCELL
  mstr_standard tap *
  page107_i393
#ISCELL
  mstr_standard tap *
  page107_i395
#ISCELL
  mstr_standard tap *
  page107_i396
#ISCELL
  mstr_standard tap *
  page107_i397
#ISCELL
  mstr_standard tap *
  page107_i399
#ISCELL
  mstr_standard offpage *
  page107_i400
#ISCELL
  mstr_standard tap *
  page107_i402
#ISCELL
  mstr_standard tap *
  page107_i403
#ISCELL
  mstr_standard tap *
  page107_i405
#ISCELL
  mstr_standard tap *
  page107_i406
#ISCELL
  mstr_standard tap *
  page107_i407
#ISCELL
  mstr_standard tap *
  page107_i408
#ISCELL
  mstr_standard tap *
  page107_i409
#ISCELL
  mstr_standard tap *
  page107_i410
#ISCELL
  mstr_standard tap *
  page107_i411
#ISCELL
  mstr_standard tap *
  page107_i412
#ISCELL
  mstr_standard tap *
  page107_i413
#ISCELL
  mstr_standard tap *
  page107_i414
#CELL
  mstr_discrete cap *
  page107_i415
#ISCELL
  mstr_standard offpage *
  page107_i416
#CELL
  mstr_discrete cap *
  page107_i417
#ISCELL
  mstr_standard tap *
  page107_i418
#ISCELL
  mstr_standard tap *
  page107_i419
#ISCELL
  mstr_standard tap *
  page107_i420
#ISCELL
  mstr_standard tap *
  page107_i421
#CELL
  mstr_discrete cap *
  page107_i422
#CELL
  mstr_discrete cap *
  page107_i423
#CELL
  mstr_discrete cap *
  page107_i424
#ISCELL
  mstr_standard tap *
  page107_i425
#ISCELL
  mstr_standard tap *
  page107_i426
#CELL
  mstr_discrete cap *
  page107_i427
#ISCELL
  mstr_standard tap *
  page107_i428
#ISCELL
  mstr_standard tap *
  page107_i429
#ISCELL
  mstr_standard tap *
  page107_i430
#CELL
  mstr_discrete cap *
  page107_i431
#ISCELL
  mstr_standard tap *
  page107_i432
#ISCELL
  mstr_standard offpage *
  page107_i433
#ISCELL
  mstr_standard tap *
  page107_i434
#CELL
  mstr_discrete cap *
  page107_i435
#ISCELL
  mstr_standard tap *
  page107_i436
#CELL
  mstr_discrete cap *
  page107_i437
#CELL
  mstr_discrete cap *
  page107_i438
#CELL
  mstr_discrete cap *
  page107_i439
#ISCELL
  mstr_standard tap *
  page107_i440
#ISCELL
  mstr_standard tap *
  page107_i441
#ISCELL
  mstr_standard tap *
  page107_i442
#ISCELL
  mstr_standard tap *
  page107_i443
#CELL
  mstr_discrete cap *
  page107_i444
#ISCELL
  mstr_standard tap *
  page107_i445
#ISCELL
  mstr_standard tap *
  page107_i446
#CELL
  mstr_discrete cap *
  page107_i447
#CELL
  mstr_discrete cap *
  page107_i448
#ISCELL
  mstr_standard tap *
  page107_i449
#ISCELL
  mstr_standard tap *
  page107_i450
#ISCELL
  mstr_standard tap *
  page107_i451
#CELL
  mstr_discrete cap *
  page107_i452
#ISCELL
  mstr_standard tap *
  page107_i453
#ISCELL
  mstr_standard tap *
  page107_i454
#CELL
  mstr_discrete cap *
  page107_i455
#ISCELL
  mstr_standard offpage *
  page107_i456
#ISCELL
  mstr_standard offpage *
  page107_i457
#CELL
  mstr_discrete res *
  page107_i458
#CELL
  mstr_discrete res *
  page107_i459
#CELL
  mstr_discrete res *
  page107_i460
#CELL
  mstr_discrete res *
  page107_i461
#CELL
  mstr_discrete res *
  page107_i462
#CELL
  mstr_discrete res *
  page107_i463
#CELL
  mstr_discrete res *
  page107_i464
#CELL
  mstr_discrete res *
  page107_i465
#CELL
  mstr_discrete res *
  page107_i466
#CELL
  mstr_discrete res *
  page107_i467
#CELL
  mstr_discrete res *
  page107_i468
#CELL
  mstr_discrete res *
  page107_i469
#CELL
  mstr_discrete res *
  page107_i470
#CELL
  mstr_discrete res *
  page107_i471
#CELL
  mstr_discrete res *
  page107_i472
#CELL
  mstr_discrete res *
  page107_i473
#ISCELL
  mstr_misc dns *
  *
#ISCELL
  mstr_symbols cad_note *
  *
#ISCELL
  mstr_symbols intel_corp_bpage *
  *
#CELL
  dev_discrete cap_a *
  page108_i1
#ISCELL
  mstr_symbols p12v *
  page108_i165
#ISCELL
  mstr_symbols p12v *
  page108_i167
#ISCELL
  mstr_symbols gnd *
  page108_i168
#ISCELL
  mstr_symbols p3v3 *
  page108_i172
#CELL
  mstr_discrete res *
  page108_i173
#ISCELL
  mstr_standard offpage *
  page108_i174
#ISCELL
  mstr_standard offpage *
  page108_i175
#ISCELL
  mstr_standard offpage *
  page108_i176
#CELL
  dev_discrete cap_a *
  page108_i2
#ISCELL
  mstr_symbols gnd *
  page108_i236
#ISCELL
  mstr_symbols p3v3 *
  page108_i238
#ISCELL
  mstr_standard offpage *
  page108_i243
#ISCELL
  mstr_symbols gnd *
  page108_i250
#ISCELL
  mstr_symbols p3v3 *
  page108_i251
#ISCELL
  mstr_symbols gnd *
  page108_i252
#CELL
  mstr_sconn sconn200_h68296001 *
  page108_i258
#ISCELL
  mstr_standard offpage *
  page108_i259
#ISCELL
  mstr_standard offpage *
  page108_i260
#ISCELL
  mstr_standard offpage *
  page108_i261
#ISCELL
  mstr_symbols p3v3_stby *
  page108_i262
#ISCELL
  mstr_standard offpage *
  page108_i264
#ISCELL
  mstr_standard offpage *
  page108_i265
#ISCELL
  mstr_standard offpage *
  page108_i266
#ISCELL
  mstr_standard offpage *
  page108_i267
#ISCELL
  mstr_standard offpage *
  page108_i269
#ISCELL
  mstr_standard offpage *
  page108_i270
#ISCELL
  mstr_standard tap *
  page108_i271
#ISCELL
  mstr_standard tap *
  page108_i272
#ISCELL
  mstr_standard tap *
  page108_i273
#ISCELL
  mstr_standard tap *
  page108_i274
#ISCELL
  mstr_standard tap *
  page108_i275
#ISCELL
  mstr_standard tap *
  page108_i276
#ISCELL
  mstr_standard tap *
  page108_i277
#ISCELL
  mstr_standard tap *
  page108_i278
#ISCELL
  mstr_standard tap *
  page108_i279
#ISCELL
  mstr_standard tap *
  page108_i280
#ISCELL
  mstr_standard tap *
  page108_i281
#ISCELL
  mstr_standard tap *
  page108_i282
#ISCELL
  mstr_standard tap *
  page108_i283
#ISCELL
  mstr_standard tap *
  page108_i284
#ISCELL
  mstr_standard tap *
  page108_i285
#ISCELL
  mstr_standard tap *
  page108_i286
#ISCELL
  mstr_standard offpage *
  page108_i287
#ISCELL
  mstr_standard offpage *
  page108_i288
#ISCELL
  mstr_standard offpage *
  page108_i289
#ISCELL
  mstr_standard offpage *
  page108_i290
#ISCELL
  mstr_standard offpage *
  page108_i291
#ISCELL
  mstr_standard offpage *
  page108_i292
#ISCELL
  mstr_standard offpage *
  page108_i293
#ISCELL
  mstr_standard offpage *
  page108_i294
#ISCELL
  mstr_standard tap *
  page108_i295
#ISCELL
  mstr_standard tap *
  page108_i296
#ISCELL
  mstr_standard tap *
  page108_i297
#ISCELL
  mstr_standard tap *
  page108_i298
#ISCELL
  mstr_standard tap *
  page108_i299
#ISCELL
  mstr_standard tap *
  page108_i300
#ISCELL
  mstr_standard tap *
  page108_i301
#ISCELL
  mstr_standard tap *
  page108_i302
#ISCELL
  mstr_standard tap *
  page108_i303
#ISCELL
  mstr_standard tap *
  page108_i304
#ISCELL
  mstr_standard tap *
  page108_i305
#ISCELL
  mstr_standard tap *
  page108_i306
#ISCELL
  mstr_standard tap *
  page108_i307
#ISCELL
  mstr_standard tap *
  page108_i308
#ISCELL
  mstr_standard offpage *
  page108_i310
#ISCELL
  mstr_standard offpage *
  page108_i314
#CELL
  dev_discrete cap_a *
  page108_i315
#ISCELL
  mstr_symbols gnd *
  page108_i316
#CELL
  dev_discrete cap_a *
  page108_i318
#ISCELL
  mstr_symbols p3v3_stby *
  page108_i319
#CELL
  mstr_discrete res *
  page108_i320
#ISCELL
  mstr_standard offpage *
  page108_i322
#ISCELL
  mstr_standard offpage *
  page108_i323
#ISCELL
  mstr_standard offpage *
  page108_i324
#ISCELL
  mstr_standard offpage *
  page108_i325
#ISCELL
  mstr_standard offpage *
  page108_i328
#ISCELL
  mstr_standard offpage *
  page108_i329
#CELL
  mstr_discrete res *
  page108_i330
#ISCELL
  mstr_standard offpage *
  page108_i333
#ISCELL
  mstr_standard offpage *
  page108_i334
#ISCELL
  mstr_standard offpage *
  page108_i335
#ISCELL
  mstr_standard offpage *
  page108_i336
#ISCELL
  mstr_standard offpage *
  page108_i337
#ISCELL
  mstr_standard offpage *
  page108_i338
#CELL
  mstr_discrete res *
  page108_i339
#CELL
  mstr_discrete res *
  page108_i340
#CELL
  mstr_discrete res *
  page108_i341
#ISCELL
  mstr_standard offpage *
  page108_i342
#CELL
  mstr_discrete res *
  page108_i343
#ISCELL
  mstr_symbols p3v3 *
  page108_i344
#ISCELL
  mstr_standard tap *
  page108_i345
#ISCELL
  mstr_symbols p12v *
  page108_i4
#CELL
  dev_discrete cap_a *
  page108_i5
#CELL
  dev_discrete cap_a *
  page108_i7
#ISCELL
  mstr_symbols intel_corp_bpage *
  *
#ISCELL
  mstr_standard offpage *
  page109_i1
#ISCELL
  mstr_standard tap *
  page109_i10
#ISCELL
  mstr_standard tap *
  page109_i11
#ISCELL
  mstr_standard tap *
  page109_i12
#ISCELL
  mstr_standard tap *
  page109_i13
#ISCELL
  mstr_standard tap *
  page109_i14
#ISCELL
  mstr_standard tap *
  page109_i15
#ISCELL
  mstr_standard tap *
  page109_i16
#ISCELL
  mstr_standard tap *
  page109_i17
#ISCELL
  mstr_standard tap *
  page109_i18
#ISCELL
  mstr_standard tap *
  page109_i19
#ISCELL
  mstr_standard offpage *
  page109_i2
#ISCELL
  mstr_standard tap *
  page109_i20
#ISCELL
  mstr_standard tap *
  page109_i21
#ISCELL
  mstr_standard tap *
  page109_i22
#ISCELL
  mstr_standard tap *
  page109_i23
#ISCELL
  mstr_standard tap *
  page109_i24
#ISCELL
  mstr_symbols gnd *
  page109_i25
#ISCELL
  mstr_symbols gnd *
  page109_i26
#ISCELL
  mstr_standard tap *
  page109_i27
#ISCELL
  mstr_standard tap *
  page109_i28
#ISCELL
  mstr_standard tap *
  page109_i29
#ISCELL
  mstr_standard offpage *
  page109_i3
#ISCELL
  mstr_standard tap *
  page109_i30
#ISCELL
  mstr_standard tap *
  page109_i31
#ISCELL
  mstr_standard tap *
  page109_i32
#ISCELL
  mstr_standard tap *
  page109_i33
#ISCELL
  mstr_standard tap *
  page109_i34
#ISCELL
  mstr_standard tap *
  page109_i35
#ISCELL
  mstr_standard tap *
  page109_i36
#ISCELL
  mstr_standard tap *
  page109_i37
#ISCELL
  mstr_standard tap *
  page109_i38
#ISCELL
  mstr_standard tap *
  page109_i39
#ISCELL
  mstr_standard offpage *
  page109_i4
#ISCELL
  mstr_standard tap *
  page109_i40
#ISCELL
  mstr_standard tap *
  page109_i41
#ISCELL
  mstr_standard tap *
  page109_i42
#ISCELL
  mstr_standard tap *
  page109_i43
#ISCELL
  mstr_standard tap *
  page109_i44
#ISCELL
  mstr_standard offpage *
  page109_i45
#ISCELL
  mstr_standard offpage *
  page109_i46
#ISCELL
  mstr_standard tap *
  page109_i47
#ISCELL
  mstr_standard tap *
  page109_i48
#ISCELL
  mstr_standard tap *
  page109_i49
#ISCELL
  mstr_standard offpage *
  page109_i5
#ISCELL
  mstr_standard tap *
  page109_i50
#ISCELL
  mstr_standard tap *
  page109_i51
#ISCELL
  mstr_standard tap *
  page109_i52
#ISCELL
  mstr_standard tap *
  page109_i53
#ISCELL
  mstr_standard tap *
  page109_i54
#ISCELL
  mstr_standard tap *
  page109_i55
#ISCELL
  mstr_standard tap *
  page109_i56
#ISCELL
  mstr_standard tap *
  page109_i57
#ISCELL
  mstr_standard tap *
  page109_i58
#ISCELL
  mstr_standard tap *
  page109_i59
#ISCELL
  mstr_standard tap *
  page109_i6
#ISCELL
  mstr_standard tap *
  page109_i60
#ISCELL
  mstr_standard tap *
  page109_i61
#ISCELL
  mstr_standard tap *
  page109_i62
#ISCELL
  mstr_standard tap *
  page109_i63
#ISCELL
  mstr_standard tap *
  page109_i64
#ISCELL
  mstr_standard tap *
  page109_i65
#ISCELL
  mstr_standard tap *
  page109_i66
#ISCELL
  mstr_standard tap *
  page109_i67
#ISCELL
  mstr_standard tap *
  page109_i68
#ISCELL
  mstr_standard tap *
  page109_i69
#ISCELL
  mstr_standard tap *
  page109_i7
#ISCELL
  mstr_standard tap *
  page109_i70
#ISCELL
  mstr_standard tap *
  page109_i71
#ISCELL
  mstr_standard tap *
  page109_i72
#ISCELL
  mstr_standard offpage *
  page109_i73
#ISCELL
  mstr_standard offpage *
  page109_i74
#ISCELL
  mstr_standard offpage *
  page109_i75
#ISCELL
  mstr_standard tap *
  page109_i76
#ISCELL
  mstr_standard tap *
  page109_i77
#CELL
  mstr_sconn sconn200_h68296001 *
  page109_i78
#ISCELL
  mstr_standard tap *
  page109_i8
#ISCELL
  mstr_standard tap *
  page109_i9
#ISCELL
  mstr_misc dns *
  *
#ISCELL
  mstr_symbols bom_note *
  *
#ISCELL
  mstr_symbols design_note *
  *
#ISCELL
  mstr_symbols intel_corp_bpage *
  *
#CELL
  mstr_misc rcc_dfx1940 *
  page110_i1
#ISCELL
  mstr_symbols gnd *
  page110_i10
#CELL
  mstr_misc snlabel_a *
  page110_i11
#CELL
  mstr_misc snlabel_a *
  page110_i12
#CELL
  mstr_misc snlabel_a *
  page110_i13
#CELL
  mstr_misc snlabel_a *
  page110_i14
#CELL
  mstr_misc snlabel_a *
  page110_i15
#ISCELL
  mstr_symbols gnd *
  page110_i2
#CELL
  mstr_misc rcc_dfx1940 *
  page110_i3
#ISCELL
  mstr_symbols gnd *
  page110_i4
#CELL
  mstr_misc rcc_dfx1940 *
  page110_i7
#ISCELL
  mstr_symbols gnd *
  page110_i8
#CELL
  mstr_misc rcc_dfx1940 *
  page110_i9
#ISCELL
  mstr_misc dns *
  *
#ISCELL
  mstr_symbols cad_note *
  *
#ISCELL
  mstr_symbols intel_corp_bpage *
  *
#CELL
  dev_discrete cap_a *
  page111_i10
#CELL
  mstr_discrete res *
  page111_i11
#CELL
  dev_discrete cap_a *
  page111_i12
#CELL
  mstr_discrete res *
  page111_i13
#CELL
  dev_discrete cap_a *
  page111_i14
#ISCELL
  mstr_standard offpage *
  page111_i15
#ISCELL
  mstr_standard offpage *
  page111_i16
#ISCELL
  mstr_standard offpage *
  page111_i17
#ISCELL
  mstr_standard offpage *
  page111_i18
#ISCELL
  mstr_standard offpage *
  page111_i19
#ISCELL
  mstr_standard offpage *
  page111_i2
#ISCELL
  mstr_standard offpage *
  page111_i20
#ISCELL
  mstr_standard offpage *
  page111_i21
#ISCELL
  mstr_standard offpage *
  page111_i22
#ISCELL
  mstr_standard offpage *
  page111_i23
#ISCELL
  mstr_symbols gnd *
  page111_i24
#CELL
  dev_discrete cap_a *
  page111_i25
#CELL
  mstr_sconn sconn60_c21100002 *
  page111_i26
#ISCELL
  mstr_standard offpage *
  page111_i27
#ISCELL
  mstr_standard offpage *
  page111_i28
#CELL
  dev_discrete cap_a *
  page111_i30
#ISCELL
  mstr_standard offpage *
  page111_i31
#ISCELL
  mstr_standard offpage *
  page111_i32
#CELL
  mstr_discrete res *
  page111_i37
#ISCELL
  mstr_standard offpage *
  page111_i38
#ISCELL
  mstr_symbols gnd *
  page111_i39
#ISCELL
  mstr_standard offpage *
  page111_i4
#ISCELL
  mstr_standard offpage *
  page111_i46
#ISCELL
  mstr_standard offpage *
  page111_i47
#ISCELL
  mstr_standard offpage *
  page111_i48
#ISCELL
  mstr_standard offpage *
  page111_i49
#ISCELL
  mstr_standard offpage *
  page111_i50
#ISCELL
  mstr_standard offpage *
  page111_i51
#ISCELL
  mstr_standard offpage *
  page111_i52
#ISCELL
  mstr_symbols pvccio_cpu0 *
  page111_i54
#CELL
  mstr_discrete res *
  page111_i55
#CELL
  mstr_discrete res *
  page111_i56
#CELL
  mstr_discrete res *
  page111_i57
#ISCELL
  mstr_symbols gnd *
  page111_i58
#CELL
  dev_discrete cap_a *
  page111_i59
#CELL
  mstr_discrete res *
  page111_i6
#CELL
  mstr_discrete res *
  page111_i60
#ISCELL
  mstr_standard offpage *
  page111_i61
#ISCELL
  mstr_standard offpage *
  page111_i62
#ISCELL
  mstr_standard offpage *
  page111_i63
#ISCELL
  mstr_standard offpage *
  page111_i64
#ISCELL
  mstr_symbols p3v3_stby *
  page111_i65
#CELL
  mstr_discrete res *
  page111_i66
#ISCELL
  mstr_symbols p3v3_stby *
  page111_i67
#CELL
  mstr_discrete res *
  page111_i68
#ISCELL
  mstr_symbols p1v05_pch_stby *
  page111_i69
#ISCELL
  mstr_symbols gnd *
  page111_i7
#ISCELL
  mstr_symbols p1v05_pch_stby *
  page111_i70
#ISCELL
  mstr_symbols p1v05_pch_stby *
  page111_i71
#CELL
  mstr_discrete res *
  page111_i74
#ISCELL
  mstr_standard offpage *
  page111_i75
#ISCELL
  mstr_symbols gnd *
  page111_i8
#CELL
  mstr_discrete res *
  page111_i83
#CELL
  mstr_ttl ttl1g07_a *
  page111_i85
#ISCELL
  mstr_symbols p3v3_stby *
  page111_i86
#CELL
  dev_discrete cap_a *
  page111_i87
#ISCELL
  mstr_symbols gnd *
  page111_i88
#CELL
  mstr_discrete res *
  page111_i89
#ISCELL
  mstr_symbols gnd *
  page111_i9
#ISCELL
  mstr_standard offpage *
  page111_i90
#ISCELL
  mstr_standard offpage *
  page111_i91
#ISCELL
  mstr_standard offpage *
  page111_i92
#CELL
  mstr_discrete npn_dual *
  page111_i93
#CELL
  mstr_discrete npn_dual *
  page111_i94
#CELL
  mstr_discrete res *
  page111_i95
#ISCELL
  mstr_symbols p3v3 *
  page111_i96
#ISCELL
  mstr_symbols cad_note *
  *
#ISCELL
  mstr_symbols intel_corp_bpage *
  *
#ISCELL
  mstr_standard offpage *
  page112_i100
#ISCELL
  mstr_standard offpage *
  page112_i101
#ISCELL
  mstr_standard offpage *
  page112_i102
#ISCELL
  mstr_standard offpage *
  page112_i103
#ISCELL
  mstr_standard offpage *
  page112_i104
#ISCELL
  mstr_standard offpage *
  page112_i105
#ISCELL
  mstr_standard offpage *
  page112_i106
#ISCELL
  mstr_standard offpage *
  page112_i107
#CELL
  mstr_ttl ttl3126 *
  page112_i108
#CELL
  mstr_ttl ttl3126 *
  page112_i109
#ISCELL
  mstr_standard offpage *
  page112_i110
#ISCELL
  mstr_standard offpage *
  page112_i111
#ISCELL
  mstr_standard offpage *
  page112_i112
#ISCELL
  mstr_standard offpage *
  page112_i113
#ISCELL
  mstr_standard offpage *
  page112_i114
#ISCELL
  mstr_standard offpage *
  page112_i115
#CELL
  mstr_discrete res *
  page112_i120
#CELL
  mstr_discrete res *
  page112_i121
#ISCELL
  mstr_symbols pvccio_cpu0 *
  page112_i122
#ISCELL
  mstr_symbols pvccio_cpu0 *
  page112_i123
#ISCELL
  mstr_symbols p1v05_pch_stby *
  page112_i126
#CELL
  mstr_ttl 74cbtlv1g125 *
  page112_i127
#ISCELL
  mstr_standard offpage *
  page112_i128
#ISCELL
  mstr_standard offpage *
  page112_i129
#ISCELL
  mstr_standard offpage *
  page112_i130
#CELL
  dev_discrete cap_a *
  page112_i131
#ISCELL
  mstr_symbols gnd *
  page112_i133
#ISCELL
  mstr_symbols pvccio_cpu0 *
  page112_i134
#ISCELL
  mstr_symbols pvccio_cpu1 *
  page112_i135
#CELL
  mstr_discrete cap *
  page112_i136
#ISCELL
  mstr_symbols gnd *
  page112_i138
#CELL
  mstr_discrete cap *
  page112_i140
#ISCELL
  mstr_symbols gnd *
  page112_i141
#ISCELL
  mstr_symbols p3v3_stby *
  page112_i143
#ISCELL
  mstr_symbols p3v3_stby *
  page112_i144
#ISCELL
  mstr_standard offpage *
  page112_i145
#ISCELL
  mstr_standard offpage *
  page112_i146
#ISCELL
  mstr_symbols pvccio_cpu0 *
  page112_i147
#ISCELL
  mstr_symbols p3v3_stby *
  page112_i148
#ISCELL
  mstr_symbols p3v3_stby *
  page112_i149
#ISCELL
  mstr_standard offpage *
  page112_i36
#ISCELL
  mstr_symbols gnd *
  page112_i39
#CELL
  mstr_analog nc7sb3157 *
  page112_i40
#ISCELL
  mstr_standard offpage *
  page112_i41
#CELL
  dev_discrete cap_a *
  page112_i42
#CELL
  dev_discrete cap_a *
  page112_i47
#ISCELL
  mstr_symbols gnd *
  page112_i48
#CELL
  mstr_discrete res *
  page112_i49
#CELL
  mstr_discrete res *
  page112_i50
#CELL
  mstr_discrete res *
  page112_i51
#ISCELL
  mstr_symbols pvccio_cpu0 *
  page112_i52
#CELL
  mstr_discrete res *
  page112_i53
#CELL
  mstr_discrete res *
  page112_i54
#CELL
  mstr_discrete res *
  page112_i55
#CELL
  mstr_discrete res *
  page112_i56
#CELL
  mstr_discrete res *
  page112_i57
#CELL
  mstr_discrete res *
  page112_i58
#CELL
  mstr_discrete res *
  page112_i59
#CELL
  mstr_discrete res *
  page112_i60
#CELL
  mstr_discrete res *
  page112_i61
#CELL
  mstr_discrete res *
  page112_i62
#ISCELL
  mstr_standard offpage *
  page112_i63
#ISCELL
  mstr_standard offpage *
  page112_i64
#ISCELL
  mstr_standard offpage *
  page112_i65
#ISCELL
  mstr_standard offpage *
  page112_i66
#ISCELL
  mstr_standard offpage *
  page112_i67
#ISCELL
  mstr_standard offpage *
  page112_i68
#ISCELL
  mstr_standard offpage *
  page112_i69
#ISCELL
  mstr_standard offpage *
  page112_i70
#ISCELL
  mstr_standard offpage *
  page112_i71
#ISCELL
  mstr_standard offpage *
  page112_i72
#ISCELL
  mstr_standard offpage *
  page112_i73
#ISCELL
  mstr_symbols gnd *
  page112_i74
#CELL
  mstr_discrete res *
  page112_i76
#CELL
  mstr_discrete res *
  page112_i77
#CELL
  mstr_discrete res *
  page112_i78
#CELL
  mstr_discrete res *
  page112_i79
#CELL
  mstr_discrete res *
  page112_i80
#ISCELL
  mstr_standard offpage *
  page112_i81
#ISCELL
  mstr_standard offpage *
  page112_i82
#ISCELL
  mstr_standard offpage *
  page112_i83
#ISCELL
  mstr_standard offpage *
  page112_i84
#CELL
  mstr_discrete res *
  page112_i85
#ISCELL
  mstr_standard offpage *
  page112_i86
#ISCELL
  mstr_standard offpage *
  page112_i87
#ISCELL
  mstr_standard offpage *
  page112_i88
#ISCELL
  mstr_standard offpage *
  page112_i89
#ISCELL
  mstr_standard offpage *
  page112_i90
#ISCELL
  mstr_standard offpage *
  page112_i91
#ISCELL
  mstr_standard offpage *
  page112_i92
#ISCELL
  mstr_standard offpage *
  page112_i93
#CELL
  mstr_discrete res *
  page112_i94
#CELL
  mstr_discrete res *
  page112_i95
#ISCELL
  mstr_symbols gnd *
  page112_i96
#ISCELL
  mstr_standard offpage *
  page112_i97
#ISCELL
  mstr_standard offpage *
  page112_i98
#ISCELL
  mstr_standard offpage *
  page112_i99
#ISCELL
  mstr_misc dns *
  *
#ISCELL
  mstr_symbols bom_note *
  *
#ISCELL
  mstr_symbols cad_note *
  *
#ISCELL
  mstr_symbols design_note *
  *
#ISCELL
  mstr_symbols intel_corp_bpage *
  *
#CELL
  mstr_analog nc7sb3157 *
  page113_i107
#ISCELL
  mstr_symbols gnd *
  page113_i109
#ISCELL
  mstr_symbols gnd *
  page113_i110
#ISCELL
  mstr_standard offpage *
  page113_i111
#ISCELL
  mstr_standard offpage *
  page113_i112
#ISCELL
  mstr_standard offpage *
  page113_i113
#CELL
  dev_discrete cap_a *
  page113_i116
#CELL
  dev_discrete cap_a *
  page113_i117
#ISCELL
  mstr_symbols gnd *
  page113_i118
#CELL
  dev_discrete cap_a *
  page113_i119
#ISCELL
  mstr_symbols gnd *
  page113_i121
#ISCELL
  mstr_standard offpage *
  page113_i124
#ISCELL
  mstr_standard offpage *
  page113_i126
#CELL
  mstr_ttl 74cbtlv1g125 *
  page113_i127
#ISCELL
  mstr_standard offpage *
  page113_i128
#CELL
  mstr_discrete res *
  page113_i134
#ISCELL
  mstr_standard offpage *
  page113_i143
#ISCELL
  mstr_symbols gnd *
  page113_i146
#CELL
  dev_discrete cap_a *
  page113_i147
#ISCELL
  mstr_standard offpage *
  page113_i153
#ISCELL
  mstr_standard offpage *
  page113_i154
#ISCELL
  mstr_standard offpage *
  page113_i155
#ISCELL
  mstr_symbols p3v3_stby *
  page113_i160
#ISCELL
  mstr_symbols p3v3_stby *
  page113_i161
#ISCELL
  mstr_standard offpage *
  page113_i162
#ISCELL
  mstr_standard offpage *
  page113_i163
#CELL
  mstr_discrete res *
  page113_i168
#ISCELL
  mstr_standard offpage *
  page113_i169
#ISCELL
  mstr_symbols vcc_core *
  page113_i171
#ISCELL
  mstr_standard offpage *
  page113_i172
#CELL
  mstr_sconn sconn10_c12536004 *
  page113_i175
#ISCELL
  mstr_standard offpage *
  page113_i176
#CELL
  mstr_discrete res *
  page113_i179
#CELL
  mstr_discrete res *
  page113_i180
#ISCELL
  mstr_symbols gnd *
  page113_i182
#CELL
  mstr_ttl 74cbtlv1g125 *
  page113_i185
#ISCELL
  mstr_symbols gnd *
  page113_i186
#CELL
  mstr_discrete res *
  page113_i188
#CELL
  mstr_ttl 74cbtlv1g125 *
  page113_i190
#ISCELL
  mstr_standard offpage *
  page113_i192
#ISCELL
  mstr_standard offpage *
  page113_i193
#CELL
  mstr_discrete res *
  page113_i195
#CELL
  mstr_ttl 74cbtlv1g125 *
  page113_i196
#ISCELL
  mstr_standard offpage *
  page113_i197
#CELL
  mstr_discrete res *
  page113_i199
#ISCELL
  mstr_symbols gnd *
  page113_i200
#ISCELL
  mstr_symbols vcc_core *
  page113_i201
#CELL
  mstr_discrete res *
  page113_i202
#CELL
  mstr_discrete res *
  page113_i203
#CELL
  mstr_discrete res *
  page113_i204
#CELL
  mstr_discrete res *
  page113_i205
#CELL
  mstr_ttl 74cbtlv1g125 *
  page113_i206
#ISCELL
  mstr_standard offpage *
  page113_i212
#ISCELL
  mstr_standard offpage *
  page113_i213
#ISCELL
  mstr_standard offpage *
  page113_i214
#ISCELL
  mstr_standard offpage *
  page113_i215
#ISCELL
  mstr_symbols vcc_core *
  page113_i236
#ISCELL
  mstr_standard offpage *
  page113_i238
#CELL
  mstr_discrete res *
  page113_i239
#CELL
  mstr_discrete res *
  page113_i240
#ISCELL
  mstr_symbols vcc_core *
  page113_i241
#ISCELL
  mstr_standard offpage *
  page113_i242
#ISCELL
  mstr_standard offpage *
  page113_i243
#ISCELL
  mstr_standard offpage *
  page113_i244
#ISCELL
  mstr_symbols vcc_core *
  page113_i245
#CELL
  dev_discrete cap_a *
  page113_i246
#ISCELL
  mstr_symbols gnd *
  page113_i247
#CELL
  dev_discrete cap_a *
  page113_i248
#ISCELL
  mstr_symbols gnd *
  page113_i249
#CELL
  dev_discrete cap_a *
  page113_i250
#ISCELL
  mstr_symbols gnd *
  page113_i251
#CELL
  mstr_analog nc7sb3157 *
  page113_i255
#ISCELL
  mstr_standard offpage *
  page113_i256
#ISCELL
  mstr_standard offpage *
  page113_i257
#ISCELL
  mstr_standard offpage *
  page113_i258
#ISCELL
  mstr_symbols p3v3_stby *
  page113_i259
#ISCELL
  mstr_symbols gnd *
  page113_i261
#ISCELL
  mstr_symbols gnd *
  page113_i263
#ISCELL
  mstr_standard offpage *
  page113_i264
#CELL
  dev_discrete cap_a *
  page113_i265
#CELL
  dev_discrete cap_a *
  page113_i266
#CELL
  dev_discrete cap_a *
  page113_i267
#ISCELL
  mstr_symbols gnd *
  page113_i268
#ISCELL
  mstr_symbols p3v3_stby *
  page113_i269
#ISCELL
  mstr_misc dns *
  *
#ISCELL
  mstr_symbols cad_note *
  *
#ISCELL
  mstr_symbols design_note *
  *
#ISCELL
  mstr_symbols intel_corp_bpage *
  *
#ISCELL
  mstr_standard offpage *
  page114_i103
#ISCELL
  mstr_standard offpage *
  page114_i104
#CELL
  mstr_discrete res *
  page114_i110
#CELL
  mstr_discrete res *
  page114_i124
#ISCELL
  mstr_symbols gnd *
  page114_i125
#ISCELL
  mstr_standard offpage *
  page114_i128
#ISCELL
  mstr_standard offpage *
  page114_i129
#ISCELL
  mstr_standard offpage *
  page114_i130
#ISCELL
  mstr_standard offpage *
  page114_i133
#ISCELL
  mstr_standard offpage *
  page114_i138
#CELL
  mstr_discrete res *
  page114_i141
#CELL
  mstr_discrete res *
  page114_i142
#ISCELL
  mstr_standard offpage *
  page114_i143
#CELL
  mstr_discrete res *
  page114_i149
#ISCELL
  mstr_symbols gnd *
  page114_i150
#ISCELL
  mstr_standard offpage *
  page114_i166
#ISCELL
  mstr_standard offpage *
  page114_i167
#ISCELL
  mstr_standard offpage *
  page114_i168
#ISCELL
  mstr_standard offpage *
  page114_i169
#ISCELL
  mstr_standard offpage *
  page114_i170
#ISCELL
  mstr_standard offpage *
  page114_i171
#ISCELL
  mstr_standard offpage *
  page114_i172
#ISCELL
  mstr_standard offpage *
  page114_i173
#ISCELL
  mstr_standard offpage *
  page114_i174
#ISCELL
  mstr_standard offpage *
  page114_i175
#ISCELL
  mstr_standard offpage *
  page114_i180
#ISCELL
  mstr_standard offpage *
  page114_i181
#ISCELL
  mstr_standard offpage *
  page114_i182
#ISCELL
  mstr_standard offpage *
  page114_i183
#ISCELL
  mstr_standard offpage *
  page114_i184
#ISCELL
  mstr_standard offpage *
  page114_i185
#ISCELL
  mstr_standard offpage *
  page114_i186
#ISCELL
  mstr_standard offpage *
  page114_i187
#ISCELL
  mstr_standard offpage *
  page114_i188
#ISCELL
  mstr_standard offpage *
  page114_i189
#ISCELL
  mstr_standard offpage *
  page114_i190
#ISCELL
  mstr_standard offpage *
  page114_i35
#ISCELL
  mstr_standard offpage *
  page114_i36
#CELL
  mstr_u_proc lbg_core_qat_ext_d *
  page114_i40
#ISCELL
  mstr_standard offpage *
  page114_i43
#ISCELL
  mstr_standard offpage *
  page114_i45
#CELL
  mstr_discrete cap *
  page114_i46
#CELL
  mstr_discrete cap *
  page114_i47
#CELL
  mstr_discrete res *
  page114_i48
#CELL
  mstr_discrete crystal *
  page114_i49
#CELL
  mstr_discrete cap *
  page114_i50
#ISCELL
  mstr_standard offpage *
  page114_i51
#ISCELL
  mstr_symbols gnd *
  page114_i53
#CELL
  mstr_discrete res *
  page114_i54
#CELL
  mstr_discrete crystal *
  page114_i55
#CELL
  mstr_discrete cap *
  page114_i56
#ISCELL
  mstr_symbols gnd *
  page114_i57
#ISCELL
  mstr_standard offpage *
  page114_i58
#ISCELL
  mstr_standard offpage *
  page114_i59
#ISCELL
  mstr_standard offpage *
  page114_i60
#ISCELL
  mstr_standard offpage *
  page114_i62
#ISCELL
  mstr_standard offpage *
  page114_i63
#ISCELL
  mstr_standard offpage *
  page114_i64
#ISCELL
  mstr_standard offpage *
  page114_i89
#ISCELL
  mstr_standard offpage *
  page114_i90
#ISCELL
  mstr_standard offpage *
  page114_i93
#ISCELL
  mstr_standard offpage *
  page114_i94
#ISCELL
  mstr_standard offpage *
  page114_i95
#ISCELL
  mstr_standard offpage *
  page114_i96
#ISCELL
  mstr_symbols cad_note *
  *
#ISCELL
  mstr_symbols design_note *
  *
#ISCELL
  mstr_symbols intel_corp_bpage *
  *
#ISCELL
  mstr_standard offpage *
  page115_i102
#ISCELL
  mstr_standard offpage *
  page115_i103
#ISCELL
  mstr_standard offpage *
  page115_i104
#ISCELL
  mstr_standard offpage *
  page115_i105
#ISCELL
  mstr_standard offpage *
  page115_i106
#ISCELL
  mstr_standard offpage *
  page115_i107
#ISCELL
  mstr_standard offpage *
  page115_i110
#ISCELL
  mstr_standard offpage *
  page115_i111
#ISCELL
  mstr_standard offpage *
  page115_i112
#ISCELL
  mstr_standard offpage *
  page115_i113
#CELL
  mstr_discrete res *
  page115_i114
#ISCELL
  mstr_symbols gnd *
  page115_i115
#ISCELL
  mstr_standard offpage *
  page115_i116
#ISCELL
  mstr_standard offpage *
  page115_i117
#CELL
  mstr_u_proc lbg_core_qat_ext_d *
  page115_i74
#CELL
  mstr_discrete res *
  page115_i90
#ISCELL
  mstr_symbols gnd *
  page115_i91
#ISCELL
  mstr_misc dns *
  *
#ISCELL
  mstr_symbols cad_note *
  *
#ISCELL
  mstr_symbols design_note *
  *
#ISCELL
  mstr_symbols intel_corp_bpage *
  *
#ISCELL
  mstr_standard offpage *
  page116_i101
#ISCELL
  mstr_standard offpage *
  page116_i102
#ISCELL
  mstr_standard offpage *
  page116_i103
#ISCELL
  mstr_standard offpage *
  page116_i104
#ISCELL
  mstr_standard offpage *
  page116_i105
#ISCELL
  mstr_standard offpage *
  page116_i106
#ISCELL
  mstr_standard offpage *
  page116_i107
#CELL
  mstr_discrete res *
  page116_i108
#ISCELL
  mstr_standard tap *
  page116_i122
#ISCELL
  mstr_standard tap *
  page116_i123
#ISCELL
  mstr_standard tap *
  page116_i125
#ISCELL
  mstr_standard tap *
  page116_i128
#ISCELL
  mstr_standard tap *
  page116_i129
#ISCELL
  mstr_standard tap *
  page116_i130
#ISCELL
  mstr_standard tap *
  page116_i131
#ISCELL
  mstr_standard tap *
  page116_i132
#ISCELL
  mstr_standard tap *
  page116_i133
#ISCELL
  mstr_standard tap *
  page116_i134
#ISCELL
  mstr_standard tap *
  page116_i135
#ISCELL
  mstr_standard tap *
  page116_i136
#ISCELL
  mstr_standard tap *
  page116_i137
#ISCELL
  mstr_standard tap *
  page116_i138
#ISCELL
  mstr_standard tap *
  page116_i139
#ISCELL
  mstr_standard tap *
  page116_i140
#ISCELL
  mstr_standard tap *
  page116_i141
#ISCELL
  mstr_standard tap *
  page116_i142
#ISCELL
  mstr_standard tap *
  page116_i143
#ISCELL
  mstr_standard tap *
  page116_i144
#ISCELL
  mstr_standard tap *
  page116_i145
#ISCELL
  mstr_standard tap *
  page116_i146
#ISCELL
  mstr_standard tap *
  page116_i147
#ISCELL
  mstr_standard tap *
  page116_i148
#ISCELL
  mstr_standard tap *
  page116_i149
#ISCELL
  mstr_standard tap *
  page116_i150
#ISCELL
  mstr_standard tap *
  page116_i151
#ISCELL
  mstr_standard tap *
  page116_i152
#ISCELL
  mstr_standard tap *
  page116_i153
#ISCELL
  mstr_standard tap *
  page116_i154
#ISCELL
  mstr_standard tap *
  page116_i155
#ISCELL
  mstr_standard tap *
  page116_i156
#CELL
  mstr_discrete res *
  page116_i181
#CELL
  dev_discrete cap_a *
  page116_i182
#CELL
  dev_discrete cap_a *
  page116_i183
#ISCELL
  mstr_standard tap *
  page116_i186
#ISCELL
  mstr_standard tap *
  page116_i187
#ISCELL
  mstr_standard tap *
  page116_i188
#ISCELL
  mstr_standard tap *
  page116_i189
#ISCELL
  mstr_standard tap *
  page116_i190
#ISCELL
  mstr_standard tap *
  page116_i191
#ISCELL
  mstr_standard tap *
  page116_i192
#ISCELL
  mstr_standard tap *
  page116_i193
#ISCELL
  mstr_standard tap *
  page116_i196
#ISCELL
  mstr_standard tap *
  page116_i197
#ISCELL
  mstr_standard tap *
  page116_i198
#ISCELL
  mstr_standard tap *
  page116_i199
#ISCELL
  mstr_standard tap *
  page116_i200
#ISCELL
  mstr_standard tap *
  page116_i201
#ISCELL
  mstr_standard tap *
  page116_i202
#ISCELL
  mstr_standard tap *
  page116_i203
#ISCELL
  mstr_standard offpage *
  page116_i204
#ISCELL
  mstr_standard offpage *
  page116_i205
#ISCELL
  mstr_standard offpage *
  page116_i206
#ISCELL
  mstr_standard offpage *
  page116_i207
#ISCELL
  mstr_standard offpage *
  page116_i208
#ISCELL
  mstr_standard offpage *
  page116_i209
#ISCELL
  mstr_standard offpage *
  page116_i21
#ISCELL
  mstr_standard offpage *
  page116_i210
#ISCELL
  mstr_standard offpage *
  page116_i211
#ISCELL
  mstr_standard offpage *
  page116_i212
#ISCELL
  mstr_standard offpage *
  page116_i213
#ISCELL
  mstr_standard offpage *
  page116_i214
#ISCELL
  mstr_standard offpage *
  page116_i215
#ISCELL
  mstr_standard offpage *
  page116_i216
#ISCELL
  mstr_standard offpage *
  page116_i217
#ISCELL
  mstr_standard offpage *
  page116_i218
#ISCELL
  mstr_standard offpage *
  page116_i219
#CELL
  mstr_u_proc lbg_core_qat_ext_d *
  page116_i220
#ISCELL
  mstr_standard offpage *
  page116_i221
#ISCELL
  mstr_standard offpage *
  page116_i222
#ISCELL
  mstr_standard offpage *
  page116_i223
#ISCELL
  mstr_standard offpage *
  page116_i224
#ISCELL
  mstr_standard offpage *
  page116_i225
#ISCELL
  mstr_standard offpage *
  page116_i226
#ISCELL
  mstr_standard offpage *
  page116_i227
#ISCELL
  mstr_standard offpage *
  page116_i228
#CELL
  mstr_discrete res *
  page116_i229
#CELL
  mstr_discrete res *
  page116_i230
#ISCELL
  mstr_symbols gnd *
  page116_i231
#ISCELL
  mstr_standard offpage *
  page116_i232
#ISCELL
  mstr_standard offpage *
  page116_i233
#CELL
  mstr_discrete res *
  page116_i234
#CELL
  mstr_discrete res *
  page116_i235
#ISCELL
  mstr_symbols gnd *
  page116_i236
#ISCELL
  mstr_symbols gnd *
  page116_i237
#ISCELL
  mstr_standard offpage *
  page116_i26
#ISCELL
  mstr_standard offpage *
  page116_i27
#ISCELL
  mstr_standard offpage *
  page116_i28
#ISCELL
  mstr_standard offpage *
  page116_i29
#ISCELL
  mstr_standard offpage *
  page116_i30
#ISCELL
  mstr_standard offpage *
  page116_i31
#ISCELL
  mstr_standard offpage *
  page116_i32
#ISCELL
  mstr_standard offpage *
  page116_i97
#ISCELL
  mstr_symbols design_note *
  *
#ISCELL
  mstr_symbols intel_corp_bpage *
  *
#ISCELL
  mstr_standard tap *
  page117_i101
#ISCELL
  mstr_standard tap *
  page117_i102
#ISCELL
  mstr_standard tap *
  page117_i103
#ISCELL
  mstr_standard tap *
  page117_i104
#ISCELL
  mstr_standard tap *
  page117_i105
#ISCELL
  mstr_standard tap *
  page117_i106
#ISCELL
  mstr_standard tap *
  page117_i107
#ISCELL
  mstr_standard tap *
  page117_i109
#ISCELL
  mstr_standard tap *
  page117_i110
#ISCELL
  mstr_standard tap *
  page117_i111
#ISCELL
  mstr_standard tap *
  page117_i112
#ISCELL
  mstr_standard tap *
  page117_i113
#ISCELL
  mstr_standard tap *
  page117_i114
#ISCELL
  mstr_standard tap *
  page117_i115
#ISCELL
  mstr_standard tap *
  page117_i116
#ISCELL
  mstr_standard tap *
  page117_i117
#ISCELL
  mstr_standard tap *
  page117_i118
#ISCELL
  mstr_standard tap *
  page117_i119
#ISCELL
  mstr_standard tap *
  page117_i120
#ISCELL
  mstr_standard tap *
  page117_i121
#ISCELL
  mstr_standard tap *
  page117_i122
#ISCELL
  mstr_standard tap *
  page117_i123
#ISCELL
  mstr_standard tap *
  page117_i124
#ISCELL
  mstr_standard tap *
  page117_i125
#ISCELL
  mstr_standard tap *
  page117_i126
#ISCELL
  mstr_standard tap *
  page117_i127
#ISCELL
  mstr_standard tap *
  page117_i128
#ISCELL
  mstr_standard offpage *
  page117_i129
#ISCELL
  mstr_standard offpage *
  page117_i130
#ISCELL
  mstr_standard offpage *
  page117_i131
#ISCELL
  mstr_standard offpage *
  page117_i132
#ISCELL
  mstr_standard tap *
  page117_i133
#ISCELL
  mstr_standard tap *
  page117_i134
#ISCELL
  mstr_standard offpage *
  page117_i18
#ISCELL
  mstr_standard offpage *
  page117_i19
#ISCELL
  mstr_standard tap *
  page117_i21
#ISCELL
  mstr_standard tap *
  page117_i22
#ISCELL
  mstr_standard tap *
  page117_i23
#ISCELL
  mstr_standard tap *
  page117_i24
#ISCELL
  mstr_standard tap *
  page117_i25
#ISCELL
  mstr_standard tap *
  page117_i26
#ISCELL
  mstr_standard tap *
  page117_i27
#ISCELL
  mstr_standard tap *
  page117_i28
#ISCELL
  mstr_standard tap *
  page117_i29
#ISCELL
  mstr_standard tap *
  page117_i30
#ISCELL
  mstr_standard tap *
  page117_i31
#ISCELL
  mstr_standard tap *
  page117_i32
#ISCELL
  mstr_standard tap *
  page117_i33
#ISCELL
  mstr_standard tap *
  page117_i34
#ISCELL
  mstr_standard tap *
  page117_i35
#ISCELL
  mstr_standard tap *
  page117_i36
#ISCELL
  mstr_standard offpage *
  page117_i38
#ISCELL
  mstr_standard offpage *
  page117_i39
#ISCELL
  mstr_standard offpage *
  page117_i40
#ISCELL
  mstr_standard offpage *
  page117_i41
#ISCELL
  mstr_standard tap *
  page117_i42
#ISCELL
  mstr_standard tap *
  page117_i43
#ISCELL
  mstr_standard tap *
  page117_i44
#ISCELL
  mstr_standard tap *
  page117_i45
#ISCELL
  mstr_standard tap *
  page117_i46
#ISCELL
  mstr_standard tap *
  page117_i47
#ISCELL
  mstr_standard tap *
  page117_i48
#ISCELL
  mstr_standard tap *
  page117_i50
#ISCELL
  mstr_standard tap *
  page117_i58
#ISCELL
  mstr_standard tap *
  page117_i59
#ISCELL
  mstr_standard tap *
  page117_i60
#ISCELL
  mstr_standard tap *
  page117_i61
#ISCELL
  mstr_standard tap *
  page117_i62
#ISCELL
  mstr_standard tap *
  page117_i63
#ISCELL
  mstr_standard tap *
  page117_i64
#ISCELL
  mstr_standard tap *
  page117_i65
#ISCELL
  mstr_standard tap *
  page117_i74
#ISCELL
  mstr_standard tap *
  page117_i75
#ISCELL
  mstr_standard tap *
  page117_i76
#ISCELL
  mstr_standard tap *
  page117_i77
#ISCELL
  mstr_standard tap *
  page117_i78
#ISCELL
  mstr_standard tap *
  page117_i79
#ISCELL
  mstr_standard tap *
  page117_i80
#ISCELL
  mstr_standard tap *
  page117_i81
#ISCELL
  mstr_standard tap *
  page117_i82
#ISCELL
  mstr_standard tap *
  page117_i83
#ISCELL
  mstr_standard tap *
  page117_i84
#ISCELL
  mstr_standard tap *
  page117_i85
#ISCELL
  mstr_standard tap *
  page117_i86
#ISCELL
  mstr_standard tap *
  page117_i87
#CELL
  mstr_u_proc lbg_core_qat_ext_d *
  page117_i9
#ISCELL
  mstr_standard tap *
  page117_i90
#ISCELL
  mstr_standard tap *
  page117_i91
#ISCELL
  mstr_standard offpage *
  page117_i95
#ISCELL
  mstr_standard offpage *
  page117_i96
#ISCELL
  mstr_standard tap *
  page117_i97
#ISCELL
  mstr_standard tap *
  page117_i98
#ISCELL
  mstr_standard tap *
  page117_i99
#ISCELL
  mstr_misc dns *
  *
#ISCELL
  mstr_symbols cad_note *
  *
#ISCELL
  mstr_symbols intel_corp_bpage *
  *
#ISCELL
  mstr_standard offpage *
  page118_i115
#ISCELL
  mstr_symbols p1v05_pch_stby_kr_pll *
  page118_i117
#ISCELL
  mstr_symbols p1v05_pch_stby_kr_pll *
  page118_i118
#ISCELL
  mstr_standard offpage *
  page118_i119
#CELL
  mstr_discrete res *
  page118_i120
#ISCELL
  mstr_standard offpage *
  page118_i122
#ISCELL
  mstr_standard offpage *
  page118_i123
#ISCELL
  mstr_standard offpage *
  page118_i124
#CELL
  mstr_discrete res *
  page118_i125
#ISCELL
  mstr_standard offpage *
  page118_i126
#ISCELL
  mstr_standard offpage *
  page118_i127
#CELL
  mstr_discrete res *
  page118_i128
#ISCELL
  mstr_symbols p3v3_stby *
  page118_i129
#ISCELL
  mstr_standard offpage *
  page118_i130
#CELL
  mstr_discrete res *
  page118_i131
#ISCELL
  mstr_standard offpage *
  page118_i132
#ISCELL
  mstr_standard offpage *
  page118_i133
#ISCELL
  mstr_symbols p3v3_stby *
  page118_i135
#CELL
  dev_discrete cap_a *
  page118_i136
#ISCELL
  mstr_symbols gnd *
  page118_i137
#ISCELL
  mstr_standard offpage *
  page118_i138
#ISCELL
  mstr_standard offpage *
  page118_i140
#ISCELL
  mstr_standard offpage *
  page118_i141
#CELL
  mstr_ttl 74cbtlv1g125 *
  page118_i142
#CELL
  mstr_discrete res *
  page118_i144
#ISCELL
  mstr_symbols p3v3_stby *
  page118_i145
#ISCELL
  mstr_standard offpage *
  page118_i146
#ISCELL
  mstr_standard offpage *
  page118_i147
#ISCELL
  mstr_standard offpage *
  page118_i148
#ISCELL
  mstr_standard offpage *
  page118_i149
#ISCELL
  mstr_standard offpage *
  page118_i150
#ISCELL
  mstr_standard offpage *
  page118_i151
#ISCELL
  mstr_standard offpage *
  page118_i152
#ISCELL
  mstr_standard offpage *
  page118_i153
#ISCELL
  mstr_standard offpage *
  page118_i154
#ISCELL
  mstr_standard offpage *
  page118_i155
#ISCELL
  mstr_standard offpage *
  page118_i156
#ISCELL
  mstr_standard offpage *
  page118_i157
#ISCELL
  mstr_standard offpage *
  page118_i158
#ISCELL
  mstr_standard offpage *
  page118_i159
#ISCELL
  mstr_standard offpage *
  page118_i160
#ISCELL
  mstr_standard offpage *
  page118_i161
#ISCELL
  mstr_standard offpage *
  page118_i164
#ISCELL
  mstr_standard offpage *
  page118_i165
#ISCELL
  mstr_standard offpage *
  page118_i19
#ISCELL
  mstr_standard offpage *
  page118_i25
#ISCELL
  mstr_standard offpage *
  page118_i26
#ISCELL
  mstr_standard offpage *
  page118_i27
#ISCELL
  mstr_standard offpage *
  page118_i34
#ISCELL
  mstr_standard offpage *
  page118_i35
#ISCELL
  mstr_standard offpage *
  page118_i36
#ISCELL
  mstr_standard offpage *
  page118_i37
#ISCELL
  mstr_standard offpage *
  page118_i38
#ISCELL
  mstr_standard offpage *
  page118_i40
#ISCELL
  mstr_standard offpage *
  page118_i41
#ISCELL
  mstr_standard offpage *
  page118_i42
#ISCELL
  mstr_standard offpage *
  page118_i44
#ISCELL
  mstr_standard offpage *
  page118_i46
#ISCELL
  mstr_standard offpage *
  page118_i47
#ISCELL
  mstr_standard offpage *
  page118_i48
#ISCELL
  mstr_standard offpage *
  page118_i49
#ISCELL
  mstr_standard offpage *
  page118_i50
#ISCELL
  mstr_standard offpage *
  page118_i53
#ISCELL
  mstr_standard offpage *
  page118_i54
#ISCELL
  mstr_standard offpage *
  page118_i55
#ISCELL
  mstr_standard offpage *
  page118_i56
#CELL
  mstr_discrete res *
  page118_i66
#CELL
  mstr_discrete res *
  page118_i67
#ISCELL
  mstr_standard offpage *
  page118_i68
#ISCELL
  mstr_symbols gnd *
  page118_i69
#CELL
  mstr_discrete res *
  page118_i71
#ISCELL
  mstr_symbols p3v3_stby *
  page118_i72
#CELL
  mstr_u_proc lbg_core_qat_ext_d *
  page118_i73
#CELL
  mstr_discrete crystal *
  page118_i76
#CELL
  mstr_discrete cap *
  page118_i77
#ISCELL
  mstr_symbols gnd *
  page118_i78
#CELL
  mstr_discrete cap *
  page118_i79
#ISCELL
  mstr_symbols gnd *
  page118_i80
#ISCELL
  mstr_standard offpage *
  page118_i86
#ISCELL
  mstr_standard offpage *
  page118_i87
#ISCELL
  mstr_standard offpage *
  page118_i89
#ISCELL
  mstr_standard offpage *
  page118_i91
#CELL
  mstr_discrete res *
  page118_i96
#CELL
  mstr_discrete res *
  page118_i99
#ISCELL
  mstr_misc dns *
  *
#ISCELL
  mstr_symbols cad_note *
  *
#ISCELL
  mstr_symbols design_note *
  *
#ISCELL
  mstr_symbols intel_corp_bpage *
  *
#ISCELL
  mstr_standard offpage *
  page119_i10
#ISCELL
  mstr_standard offpage *
  page119_i100
#ISCELL
  mstr_standard offpage *
  page119_i101
#CELL
  mstr_u_proc lbg_core_qat_ext_d *
  page119_i115
#ISCELL
  mstr_standard offpage *
  page119_i119
#ISCELL
  mstr_standard tap *
  page119_i120
#ISCELL
  mstr_standard tap *
  page119_i121
#ISCELL
  mstr_standard tap *
  page119_i122
#ISCELL
  mstr_standard tap *
  page119_i123
#ISCELL
  mstr_standard offpage *
  page119_i124
#ISCELL
  mstr_standard offpage *
  page119_i125
#ISCELL
  mstr_standard offpage *
  page119_i127
#ISCELL
  mstr_standard offpage *
  page119_i128
#ISCELL
  mstr_standard offpage *
  page119_i129
#ISCELL
  mstr_standard offpage *
  page119_i13
#ISCELL
  mstr_standard offpage *
  page119_i130
#ISCELL
  mstr_standard offpage *
  page119_i131
#ISCELL
  mstr_standard offpage *
  page119_i132
#ISCELL
  mstr_standard offpage *
  page119_i136
#ISCELL
  mstr_standard offpage *
  page119_i137
#ISCELL
  mstr_standard offpage *
  page119_i139
#ISCELL
  mstr_standard offpage *
  page119_i14
#ISCELL
  mstr_standard offpage *
  page119_i140
#ISCELL
  mstr_standard offpage *
  page119_i141
#ISCELL
  mstr_standard offpage *
  page119_i142
#ISCELL
  mstr_standard offpage *
  page119_i143
#ISCELL
  mstr_standard offpage *
  page119_i144
#ISCELL
  mstr_standard offpage *
  page119_i145
#ISCELL
  mstr_standard offpage *
  page119_i146
#ISCELL
  mstr_standard offpage *
  page119_i148
#ISCELL
  mstr_standard offpage *
  page119_i150
#ISCELL
  mstr_standard offpage *
  page119_i151
#ISCELL
  mstr_standard offpage *
  page119_i154
#ISCELL
  mstr_standard offpage *
  page119_i155
#ISCELL
  mstr_standard offpage *
  page119_i156
#ISCELL
  mstr_standard offpage *
  page119_i158
#ISCELL
  mstr_standard offpage *
  page119_i159
#ISCELL
  mstr_standard offpage *
  page119_i161
#ISCELL
  mstr_standard offpage *
  page119_i164
#ISCELL
  mstr_standard offpage *
  page119_i165
#ISCELL
  mstr_standard offpage *
  page119_i166
#ISCELL
  mstr_standard offpage *
  page119_i170
#ISCELL
  mstr_standard offpage *
  page119_i171
#CELL
  mstr_discrete res *
  page119_i172
#CELL
  mstr_discrete res *
  page119_i173
#CELL
  mstr_discrete res *
  page119_i174
#CELL
  mstr_discrete fet_n_dual *
  page119_i175
#ISCELL
  mstr_standard offpage *
  page119_i176
#ISCELL
  mstr_symbols p3v3_stby *
  page119_i177
#CELL
  mstr_discrete res *
  page119_i178
#CELL
  mstr_discrete led *
  page119_i179
#CELL
  mstr_discrete fet_n_dual *
  page119_i180
#ISCELL
  mstr_symbols gnd *
  page119_i181
#ISCELL
  mstr_symbols p3v3_stby *
  page119_i182
#CELL
  mstr_discrete res *
  page119_i183
#ISCELL
  mstr_symbols gnd *
  page119_i184
#ISCELL
  mstr_symbols p3v3_stby *
  page119_i185
#CELL
  mstr_discrete res *
  page119_i186
#ISCELL
  mstr_standard offpage *
  page119_i187
#ISCELL
  mstr_standard offpage *
  page119_i188
#CELL
  mstr_discrete res *
  page119_i189
#ISCELL
  mstr_standard offpage *
  page119_i190
#ISCELL
  mstr_standard offpage *
  page119_i191
#ISCELL
  mstr_standard offpage *
  page119_i196
#ISCELL
  mstr_standard offpage *
  page119_i197
#ISCELL
  mstr_standard offpage *
  page119_i198
#ISCELL
  mstr_standard offpage *
  page119_i2
#ISCELL
  mstr_standard offpage *
  page119_i202
#ISCELL
  mstr_standard offpage *
  page119_i203
#ISCELL
  mstr_standard offpage *
  page119_i205
#ISCELL
  mstr_standard offpage *
  page119_i208
#ISCELL
  mstr_standard offpage *
  page119_i209
#ISCELL
  mstr_standard offpage *
  page119_i21
#ISCELL
  mstr_standard offpage *
  page119_i211
#ISCELL
  mstr_standard offpage *
  page119_i212
#CELL
  mstr_discrete res *
  page119_i213
#ISCELL
  mstr_symbols p3v3_stby *
  page119_i214
#CELL
  mstr_discrete res *
  page119_i215
#ISCELL
  mstr_standard offpage *
  page119_i216
#ISCELL
  mstr_standard offpage *
  page119_i217
#ISCELL
  mstr_standard offpage *
  page119_i218
#ISCELL
  mstr_standard offpage *
  page119_i22
#ISCELL
  mstr_standard offpage *
  page119_i23
#ISCELL
  mstr_standard offpage *
  page119_i26
#ISCELL
  mstr_standard offpage *
  page119_i29
#ISCELL
  mstr_standard offpage *
  page119_i31
#ISCELL
  mstr_standard offpage *
  page119_i32
#ISCELL
  mstr_standard offpage *
  page119_i33
#ISCELL
  mstr_standard offpage *
  page119_i34
#ISCELL
  mstr_standard offpage *
  page119_i35
#ISCELL
  mstr_standard offpage *
  page119_i37
#ISCELL
  mstr_standard offpage *
  page119_i39
#ISCELL
  mstr_standard offpage *
  page119_i40
#ISCELL
  mstr_standard offpage *
  page119_i42
#ISCELL
  mstr_standard offpage *
  page119_i46
#ISCELL
  mstr_standard offpage *
  page119_i47
#ISCELL
  mstr_standard offpage *
  page119_i48
#ISCELL
  mstr_standard offpage *
  page119_i49
#ISCELL
  mstr_standard offpage *
  page119_i50
#ISCELL
  mstr_standard offpage *
  page119_i51
#ISCELL
  mstr_standard offpage *
  page119_i52
#ISCELL
  mstr_standard offpage *
  page119_i53
#ISCELL
  mstr_standard offpage *
  page119_i54
#ISCELL
  mstr_standard offpage *
  page119_i55
#ISCELL
  mstr_standard offpage *
  page119_i56
#ISCELL
  mstr_standard offpage *
  page119_i57
#ISCELL
  mstr_standard offpage *
  page119_i61
#ISCELL
  mstr_standard offpage *
  page119_i63
#ISCELL
  mstr_standard offpage *
  page119_i67
#ISCELL
  mstr_standard offpage *
  page119_i7
#ISCELL
  mstr_standard offpage *
  page119_i8
#ISCELL
  mstr_standard offpage *
  page119_i86
#ISCELL
  mstr_standard offpage *
  page119_i87
#ISCELL
  mstr_standard offpage *
  page119_i88
#ISCELL
  mstr_standard offpage *
  page119_i9
#ISCELL
  mstr_standard offpage *
  page119_i95
#ISCELL
  mstr_symbols cad_note *
  *
#ISCELL
  mstr_symbols design_note *
  *
#ISCELL
  mstr_symbols intel_corp_bpage *
  *
#ISCELL
  mstr_standard offpage *
  page120_i10
#ISCELL
  mstr_standard offpage *
  page120_i111
#ISCELL
  mstr_standard offpage *
  page120_i113
#ISCELL
  mstr_standard offpage *
  page120_i115
#ISCELL
  mstr_standard offpage *
  page120_i116
#ISCELL
  mstr_standard offpage *
  page120_i117
#ISCELL
  mstr_standard offpage *
  page120_i118
#ISCELL
  mstr_standard offpage *
  page120_i119
#ISCELL
  mstr_standard offpage *
  page120_i140
#ISCELL
  mstr_standard offpage *
  page120_i141
#ISCELL
  mstr_standard offpage *
  page120_i142
#ISCELL
  mstr_standard offpage *
  page120_i143
#ISCELL
  mstr_standard offpage *
  page120_i145
#ISCELL
  mstr_standard offpage *
  page120_i146
#CELL
  mstr_u_proc lbg_core_qat_ext_d *
  page120_i147
#CELL
  mstr_discrete res *
  page120_i148
#ISCELL
  mstr_standard offpage *
  page120_i15
#ISCELL
  mstr_standard offpage *
  page120_i150
#ISCELL
  mstr_standard offpage *
  page120_i151
#ISCELL
  mstr_standard offpage *
  page120_i152
#ISCELL
  mstr_standard offpage *
  page120_i154
#ISCELL
  mstr_standard offpage *
  page120_i155
#ISCELL
  mstr_standard offpage *
  page120_i156
#ISCELL
  mstr_standard offpage *
  page120_i157
#ISCELL
  mstr_standard offpage *
  page120_i158
#ISCELL
  mstr_standard offpage *
  page120_i159
#ISCELL
  mstr_standard offpage *
  page120_i16
#ISCELL
  mstr_standard offpage *
  page120_i160
#ISCELL
  mstr_standard offpage *
  page120_i161
#ISCELL
  mstr_standard offpage *
  page120_i162
#ISCELL
  mstr_standard offpage *
  page120_i163
#ISCELL
  mstr_standard offpage *
  page120_i164
#ISCELL
  mstr_standard offpage *
  page120_i165
#ISCELL
  mstr_standard offpage *
  page120_i166
#ISCELL
  mstr_standard offpage *
  page120_i167
#ISCELL
  mstr_standard offpage *
  page120_i168
#ISCELL
  mstr_standard offpage *
  page120_i169
#ISCELL
  mstr_standard offpage *
  page120_i170
#ISCELL
  mstr_standard offpage *
  page120_i173
#ISCELL
  mstr_standard offpage *
  page120_i174
#ISCELL
  mstr_standard offpage *
  page120_i175
#ISCELL
  mstr_standard offpage *
  page120_i176
#ISCELL
  mstr_standard offpage *
  page120_i177
#ISCELL
  mstr_standard offpage *
  page120_i178
#ISCELL
  mstr_standard offpage *
  page120_i179
#ISCELL
  mstr_standard offpage *
  page120_i180
#ISCELL
  mstr_standard offpage *
  page120_i181
#ISCELL
  mstr_standard offpage *
  page120_i182
#ISCELL
  mstr_standard offpage *
  page120_i183
#ISCELL
  mstr_standard offpage *
  page120_i184
#ISCELL
  mstr_standard offpage *
  page120_i185
#ISCELL
  mstr_standard offpage *
  page120_i187
#ISCELL
  mstr_standard offpage *
  page120_i188
#ISCELL
  mstr_standard offpage *
  page120_i189
#ISCELL
  mstr_standard offpage *
  page120_i190
#ISCELL
  mstr_standard offpage *
  page120_i191
#ISCELL
  mstr_standard offpage *
  page120_i193
#ISCELL
  mstr_standard offpage *
  page120_i194
#ISCELL
  mstr_standard offpage *
  page120_i195
#ISCELL
  mstr_standard offpage *
  page120_i196
#ISCELL
  mstr_standard offpage *
  page120_i197
#ISCELL
  mstr_standard offpage *
  page120_i198
#ISCELL
  mstr_standard offpage *
  page120_i199
#ISCELL
  mstr_standard offpage *
  page120_i200
#ISCELL
  mstr_standard offpage *
  page120_i201
#ISCELL
  mstr_standard offpage *
  page120_i202
#ISCELL
  mstr_standard offpage *
  page120_i208
#ISCELL
  mstr_standard offpage *
  page120_i210
#ISCELL
  mstr_standard offpage *
  page120_i211
#ISCELL
  mstr_standard offpage *
  page120_i212
#ISCELL
  mstr_standard offpage *
  page120_i213
#ISCELL
  mstr_standard offpage *
  page120_i215
#ISCELL
  mstr_standard offpage *
  page120_i217
#CELL
  mstr_discrete res *
  page120_i218
#CELL
  mstr_discrete res *
  page120_i219
#ISCELL
  mstr_standard offpage *
  page120_i222
#ISCELL
  mstr_standard offpage *
  page120_i223
#ISCELL
  mstr_standard offpage *
  page120_i224
#ISCELL
  mstr_standard offpage *
  page120_i225
#ISCELL
  mstr_standard offpage *
  page120_i226
#ISCELL
  mstr_standard offpage *
  page120_i227
#ISCELL
  mstr_standard offpage *
  page120_i228
#ISCELL
  mstr_standard offpage *
  page120_i233
#ISCELL
  mstr_standard offpage *
  page120_i234
#ISCELL
  mstr_standard offpage *
  page120_i235
#ISCELL
  mstr_standard offpage *
  page120_i236
#ISCELL
  mstr_standard offpage *
  page120_i237
#ISCELL
  mstr_standard offpage *
  page120_i238
#ISCELL
  mstr_standard offpage *
  page120_i246
#ISCELL
  mstr_standard offpage *
  page120_i247
#ISCELL
  mstr_standard offpage *
  page120_i248
#ISCELL
  mstr_standard offpage *
  page120_i249
#ISCELL
  mstr_standard offpage *
  page120_i250
#ISCELL
  mstr_standard offpage *
  page120_i251
#ISCELL
  mstr_standard offpage *
  page120_i252
#ISCELL
  mstr_standard offpage *
  page120_i253
#ISCELL
  mstr_standard offpage *
  page120_i254
#ISCELL
  mstr_standard offpage *
  page120_i259
#ISCELL
  mstr_standard offpage *
  page120_i260
#ISCELL
  mstr_standard offpage *
  page120_i263
#ISCELL
  mstr_standard offpage *
  page120_i264
#ISCELL
  mstr_standard offpage *
  page120_i265
#ISCELL
  mstr_symbols gnd *
  page120_i266
#ISCELL
  mstr_standard offpage *
  page120_i4
#ISCELL
  mstr_standard offpage *
  page120_i43
#ISCELL
  mstr_standard offpage *
  page120_i5
#ISCELL
  mstr_standard offpage *
  page120_i53
#ISCELL
  mstr_standard offpage *
  page120_i54
#ISCELL
  mstr_standard offpage *
  page120_i68
#ISCELL
  mstr_standard offpage *
  page120_i69
#ISCELL
  mstr_standard offpage *
  page120_i7
#ISCELL
  mstr_standard offpage *
  page120_i70
#ISCELL
  mstr_standard offpage *
  page120_i71
#ISCELL
  mstr_standard offpage *
  page120_i72
#ISCELL
  mstr_standard offpage *
  page120_i73
#ISCELL
  mstr_standard offpage *
  page120_i74
#ISCELL
  mstr_standard offpage *
  page120_i75
#ISCELL
  mstr_standard offpage *
  page120_i76
#ISCELL
  mstr_standard offpage *
  page120_i77
#ISCELL
  mstr_standard offpage *
  page120_i9
#ISCELL
  mstr_symbols cad_note *
  *
#ISCELL
  mstr_symbols intel_corp_bpage *
  *
#ISCELL
  mstr_standard offpage *
  page121_i10
#ISCELL
  mstr_standard offpage *
  page121_i100
#CELL
  mstr_discrete res *
  page121_i101
#ISCELL
  mstr_standard offpage *
  page121_i102
#ISCELL
  mstr_standard offpage *
  page121_i103
#ISCELL
  mstr_standard offpage *
  page121_i104
#ISCELL
  mstr_standard offpage *
  page121_i105
#ISCELL
  mstr_standard offpage *
  page121_i106
#ISCELL
  mstr_standard offpage *
  page121_i107
#ISCELL
  mstr_standard offpage *
  page121_i108
#ISCELL
  mstr_standard offpage *
  page121_i109
#ISCELL
  mstr_standard offpage *
  page121_i11
#ISCELL
  mstr_standard offpage *
  page121_i110
#ISCELL
  mstr_standard offpage *
  page121_i111
#ISCELL
  mstr_standard offpage *
  page121_i21
#ISCELL
  mstr_standard offpage *
  page121_i24
#ISCELL
  mstr_standard offpage *
  page121_i25
#ISCELL
  mstr_standard offpage *
  page121_i27
#ISCELL
  mstr_standard offpage *
  page121_i28
#ISCELL
  mstr_standard offpage *
  page121_i29
#CELL
  mstr_discrete res *
  page121_i31
#ISCELL
  mstr_standard offpage *
  page121_i32
#CELL
  mstr_discrete res *
  page121_i33
#CELL
  mstr_u_proc lbg_core_qat_ext_d *
  page121_i34
#CELL
  mstr_discrete res *
  page121_i35
#CELL
  mstr_discrete res *
  page121_i37
#ISCELL
  mstr_symbols gnd *
  page121_i39
#ISCELL
  mstr_symbols p3v3_stby *
  page121_i40
#ISCELL
  mstr_standard offpage *
  page121_i41
#ISCELL
  mstr_standard offpage *
  page121_i42
#ISCELL
  mstr_standard offpage *
  page121_i43
#ISCELL
  mstr_standard offpage *
  page121_i49
#ISCELL
  mstr_standard offpage *
  page121_i50
#ISCELL
  mstr_standard offpage *
  page121_i51
#ISCELL
  mstr_standard offpage *
  page121_i52
#ISCELL
  mstr_standard offpage *
  page121_i53
#ISCELL
  mstr_standard offpage *
  page121_i54
#ISCELL
  mstr_standard offpage *
  page121_i55
#ISCELL
  mstr_standard offpage *
  page121_i6
#ISCELL
  mstr_standard offpage *
  page121_i7
#ISCELL
  mstr_standard offpage *
  page121_i72
#CELL
  mstr_discrete res *
  page121_i73
#ISCELL
  mstr_symbols gnd *
  page121_i74
#ISCELL
  mstr_standard offpage *
  page121_i75
#ISCELL
  mstr_standard offpage *
  page121_i76
#ISCELL
  mstr_standard offpage *
  page121_i77
#ISCELL
  mstr_standard offpage *
  page121_i78
#ISCELL
  mstr_standard offpage *
  page121_i79
#ISCELL
  mstr_standard offpage *
  page121_i8
#ISCELL
  mstr_standard offpage *
  page121_i80
#ISCELL
  mstr_standard offpage *
  page121_i85
#ISCELL
  mstr_standard offpage *
  page121_i86
#ISCELL
  mstr_standard offpage *
  page121_i87
#ISCELL
  mstr_standard offpage *
  page121_i88
#CELL
  mstr_discrete res *
  page121_i89
#CELL
  mstr_discrete res *
  page121_i90
#CELL
  mstr_discrete res *
  page121_i91
#ISCELL
  mstr_standard offpage *
  page121_i92
#ISCELL
  mstr_standard offpage *
  page121_i93
#ISCELL
  mstr_standard offpage *
  page121_i94
#ISCELL
  mstr_standard offpage *
  page121_i95
#ISCELL
  mstr_standard offpage *
  page121_i96
#ISCELL
  mstr_standard offpage *
  page121_i97
#CELL
  mstr_discrete res *
  page121_i98
#ISCELL
  mstr_standard offpage *
  page121_i99
#ISCELL
  mstr_symbols intel_corp_bpage *
  *
#ISCELL
  mstr_symbols p1v8_pch_stby *
  page122_i21
#ISCELL
  mstr_symbols p1v05_pch_stby *
  page122_i24
#ISCELL
  mstr_standard offpage *
  page122_i46
#CELL
  mstr_u_proc lbg_core_qat_ext_d *
  page122_i63
#ISCELL
  mstr_symbols p3v3_stby *
  page122_i65
#ISCELL
  mstr_symbols p1v05_pch_stby_wm26_pll *
  page122_i70
#ISCELL
  mstr_symbols p1v05_pch_stby_wm20_pll *
  page122_i71
#ISCELL
  mstr_symbols p1v05_pch_stby_kr_pll *
  page122_i72
#ISCELL
  mstr_symbols p1v05_pch_stby_isclk_pll *
  page122_i73
#ISCELL
  mstr_symbols p1v05_pch_stby_vcca_xtal *
  page122_i74
#ISCELL
  mstr_symbols p3v3_rtc_stby *
  page122_i75
#ISCELL
  mstr_symbols p1v05_pch_stby *
  page122_i76
#ISCELL
  mstr_symbols p1v05_pch_stby_vcca_pll0 *
  page122_i77
#ISCELL
  mstr_symbols p1v05_pch_stby_vcca_pll1 *
  page122_i78
#ISCELL
  mstr_symbols intel_corp_bpage *
  *
#CELL
  mstr_u_proc lbg_core_qat_ext_d *
  page123_i13
#ISCELL
  mstr_symbols gnd *
  page123_i14
#ISCELL
  mstr_symbols gnd *
  page123_i15
#ISCELL
  mstr_symbols pvnn_pch_stby *
  page123_i20
#CELL
  mstr_u_proc lbg_core_qat_ext_d *
  page123_i21
#ISCELL
  mstr_standard offpage *
  page123_i22
#ISCELL
  mstr_standard offpage *
  page123_i23
#ISCELL
  mstr_symbols pvnn_pch_stby *
  page123_i24
#ISCELL
  mstr_symbols p1v05_pch_stby *
  page123_i25
#ISCELL
  mstr_symbols intel_corp_bpage *
  *
#ISCELL
  mstr_symbols gnd *
  page124_i13
#ISCELL
  mstr_symbols gnd *
  page124_i14
#CELL
  mstr_u_proc lbg_core_qat_ext_d *
  page124_i15
#CELL
  mstr_u_proc lbg_core_qat_ext_d *
  page124_i16
#CELL
  mstr_u_proc lbg_core_qat_ext_d *
  page124_i17
#ISCELL
  mstr_symbols gnd *
  page124_i4
#ISCELL
  mstr_symbols gnd *
  page124_i6
#ISCELL
  mstr_symbols gnd *
  page124_i7
#ISCELL
  mstr_symbols gnd *
  page124_i9
#ISCELL
  mstr_misc dns *
  *
#ISCELL
  mstr_symbols design_note *
  *
#ISCELL
  mstr_symbols intel_corp_bpage *
  *
#CELL
  mstr_discrete res *
  page125_i11
#ISCELL
  mstr_symbols gnd *
  page125_i14
#CELL
  mstr_discrete res *
  page125_i15
#ISCELL
  mstr_symbols gnd *
  page125_i16
#ISCELL
  mstr_standard offpage *
  page125_i20
#CELL
  mstr_discrete res *
  page125_i21
#ISCELL
  mstr_standard offpage *
  page125_i23
#CELL
  mstr_discrete res *
  page125_i24
#ISCELL
  mstr_symbols gnd *
  page125_i25
#CELL
  mstr_discrete res *
  page125_i40
#CELL
  mstr_discrete res *
  page125_i41
#ISCELL
  mstr_standard offpage *
  page125_i43
#ISCELL
  mstr_symbols p3v3_stby *
  page125_i48
#ISCELL
  mstr_symbols p3v3_stby *
  page125_i49
#CELL
  mstr_discrete res *
  page125_i50
#ISCELL
  mstr_symbols p3v3_stby *
  page125_i51
#CELL
  mstr_discrete res *
  page125_i52
#ISCELL
  mstr_standard offpage *
  page125_i53
#ISCELL
  mstr_symbols gnd *
  page125_i54
#ISCELL
  mstr_symbols gnd *
  page125_i6
#CELL
  mstr_discrete res *
  page125_i60
#ISCELL
  mstr_symbols p3v3_stby *
  page125_i61
#ISCELL
  mstr_standard offpage *
  page125_i64
#ISCELL
  mstr_standard offpage *
  page125_i65
#ISCELL
  mstr_symbols p3v3_stby *
  page125_i66
#ISCELL
  mstr_symbols gnd *
  page125_i69
#ISCELL
  mstr_standard offpage *
  page125_i7
#CELL
  mstr_discrete res *
  page125_i70
#CELL
  mstr_discrete res *
  page125_i71
#CELL
  mstr_discrete res *
  page125_i72
#ISCELL
  mstr_standard offpage *
  page125_i73
#ISCELL
  mstr_symbols p3v3_stby *
  page125_i74
#ISCELL
  mstr_symbols p3v3_stby *
  page125_i75
#CELL
  mstr_discrete res *
  page125_i76
#ISCELL
  mstr_standard offpage *
  page125_i77
#CELL
  mstr_discrete res *
  page125_i78
#ISCELL
  mstr_symbols p3v3_stby *
  page125_i79
#ISCELL
  mstr_standard offpage *
  page125_i82
#CELL
  mstr_discrete res *
  page125_i83
#ISCELL
  mstr_symbols p3v3_stby *
  page125_i84
#ISCELL
  mstr_misc dns *
  *
#ISCELL
  mstr_symbols design_note *
  *
#ISCELL
  mstr_symbols intel_corp_bpage *
  *
#CELL
  mstr_discrete res *
  page126_i10
#ISCELL
  mstr_standard offpage *
  page126_i11
#CELL
  mstr_discrete res *
  page126_i12
#CELL
  mstr_discrete fet_n *
  page126_i13
#ISCELL
  mstr_symbols gnd *
  page126_i14
#ISCELL
  mstr_symbols p3v3_stby *
  page126_i16
#ISCELL
  mstr_standard offpage *
  page126_i17
#CELL
  mstr_discrete res *
  page126_i20
#ISCELL
  mstr_standard offpage *
  page126_i21
#CELL
  mstr_discrete res *
  page126_i22
#CELL
  mstr_discrete res *
  page126_i23
#ISCELL
  mstr_symbols gnd *
  page126_i24
#ISCELL
  mstr_symbols p3v3_stby *
  page126_i25
#ISCELL
  mstr_standard offpage *
  page126_i26
#ISCELL
  mstr_symbols gnd *
  page126_i5
#CELL
  mstr_discrete res *
  page126_i6
#ISCELL
  mstr_symbols p3v3_stby *
  page126_i7
#ISCELL
  mstr_standard offpage *
  page126_i8
#ISCELL
  mstr_symbols p3v3_stby *
  page126_i9
#ISCELL
  mstr_symbols intel_corp_bpage *
  *
#ISCELL
  mstr_symbols gnd *
  page127_i14
#ISCELL
  mstr_symbols p1v05_pch_stby *
  page127_i16
#CELL
  mstr_discrete ferrite *
  page127_i17
#CELL
  dev_discrete cap_a *
  page127_i18
#ISCELL
  mstr_symbols gnd *
  page127_i23
#ISCELL
  mstr_symbols p1v05_pch_stby *
  page127_i25
#CELL
  mstr_discrete ferrite *
  page127_i26
#CELL
  dev_discrete cap_a *
  page127_i27
#ISCELL
  mstr_symbols gnd *
  page127_i32
#ISCELL
  mstr_symbols gnd *
  page127_i34
#ISCELL
  mstr_symbols gnd *
  page127_i36
#ISCELL
  mstr_symbols p1v05_pch_stby_vcca_xtal *
  page127_i39
#ISCELL
  mstr_symbols p1v05_pch_stby_wm20_pll *
  page127_i40
#CELL
  mstr_discrete cap *
  page127_i43
#CELL
  dev_discrete cap_a *
  page127_i44
#ISCELL
  mstr_symbols p1v05_pch_stby *
  page127_i45
#CELL
  mstr_discrete ferrite *
  page127_i46
#ISCELL
  mstr_symbols p1v05_pch_stby_wm26_pll *
  page127_i47
#CELL
  mstr_discrete cap *
  page127_i49
#CELL
  dev_discrete cap_a *
  page127_i50
#ISCELL
  mstr_symbols gnd *
  page127_i51
#ISCELL
  mstr_symbols p1v05_pch_stby_isclk_pll *
  page127_i52
#ISCELL
  mstr_symbols p1v05_pch_stby *
  page127_i55
#CELL
  mstr_discrete ferrite *
  page127_i56
#CELL
  dev_discrete cap_a *
  page127_i57
#ISCELL
  mstr_symbols gnd *
  page127_i58
#ISCELL
  mstr_symbols gnd *
  page127_i59
#ISCELL
  mstr_symbols gnd *
  page127_i6
#ISCELL
  mstr_symbols gnd *
  page127_i61
#ISCELL
  mstr_symbols p1v05_pch_stby_kr_pll *
  page127_i62
#CELL
  mstr_discrete cap *
  page127_i64
#CELL
  dev_discrete cap_a *
  page127_i65
#ISCELL
  mstr_symbols gnd *
  page127_i66
#ISCELL
  mstr_symbols p1v05_pch_stby *
  page127_i68
#CELL
  mstr_discrete ferrite *
  page127_i69
#ISCELL
  mstr_symbols p1v05_pch_stby *
  page127_i7
#ISCELL
  mstr_symbols p1v05_pch_stby *
  page127_i70
#CELL
  mstr_discrete inductor *
  page127_i71
#ISCELL
  mstr_symbols p1v05_pch_stby_vcca_pll0 *
  page127_i72
#ISCELL
  mstr_symbols p1v05_pch_stby_vcca_pll1 *
  page127_i73
#CELL
  dev_discrete cap_a *
  page127_i74
#ISCELL
  mstr_symbols gnd *
  page127_i75
#CELL
  dev_discrete cap_a *
  page127_i76
#ISCELL
  mstr_symbols gnd *
  page127_i77
#CELL
  dev_discrete cap_a *
  page127_i78
#ISCELL
  mstr_symbols gnd *
  page127_i79
#CELL
  mstr_discrete ferrite *
  page127_i8
#CELL
  dev_discrete cap_a *
  page127_i80
#CELL
  mstr_discrete cap *
  page127_i81
#CELL
  mstr_discrete cap *
  page127_i82
#CELL
  dev_discrete cap_a *
  page127_i83
#CELL
  dev_discrete cap_a *
  page127_i84
#CELL
  mstr_discrete cap *
  page127_i85
#CELL
  mstr_discrete cap *
  page127_i86
#CELL
  dev_discrete cap_a *
  page127_i87
#CELL
  dev_discrete cap_a *
  page127_i9
#ISCELL
  mstr_symbols intel_corp_bpage *
  *
#ISCELL
  mstr_symbols intel_corp_bpage *
  *
#ISCELL
  mstr_standard offpage *
  page129_i1
#ISCELL
  mstr_standard offpage *
  page129_i10
#ISCELL
  mstr_standard tap *
  page129_i11
#ISCELL
  mstr_standard tap *
  page129_i12
#ISCELL
  mstr_standard tap *
  page129_i13
#ISCELL
  mstr_standard tap *
  page129_i14
#ISCELL
  mstr_standard tap *
  page129_i2
#ISCELL
  mstr_standard tap *
  page129_i23
#ISCELL
  mstr_standard tap *
  page129_i24
#ISCELL
  mstr_standard tap *
  page129_i25
#ISCELL
  mstr_standard tap *
  page129_i26
#ISCELL
  mstr_standard offpage *
  page129_i27
#ISCELL
  mstr_standard offpage *
  page129_i28
#ISCELL
  mstr_standard tap *
  page129_i29
#ISCELL
  mstr_standard tap *
  page129_i3
#ISCELL
  mstr_standard tap *
  page129_i30
#ISCELL
  mstr_standard tap *
  page129_i31
#ISCELL
  mstr_standard tap *
  page129_i32
#CELL
  mstr_discrete cap *
  page129_i35
#ISCELL
  mstr_standard tap *
  page129_i37
#ISCELL
  mstr_standard tap *
  page129_i38
#ISCELL
  mstr_standard tap *
  page129_i39
#ISCELL
  mstr_standard tap *
  page129_i4
#ISCELL
  mstr_standard tap *
  page129_i40
#ISCELL
  mstr_standard offpage *
  page129_i42
#ISCELL
  mstr_standard offpage *
  page129_i43
#ISCELL
  mstr_standard tap *
  page129_i45
#ISCELL
  mstr_standard tap *
  page129_i46
#ISCELL
  mstr_standard tap *
  page129_i47
#ISCELL
  mstr_standard tap *
  page129_i48
#ISCELL
  mstr_standard tap *
  page129_i5
#ISCELL
  mstr_standard tap *
  page129_i57
#ISCELL
  mstr_standard tap *
  page129_i58
#ISCELL
  mstr_standard tap *
  page129_i59
#ISCELL
  mstr_standard tap *
  page129_i60
#ISCELL
  mstr_standard offpage *
  page129_i61
#ISCELL
  mstr_standard tap *
  page129_i62
#ISCELL
  mstr_standard tap *
  page129_i63
#ISCELL
  mstr_standard tap *
  page129_i64
#ISCELL
  mstr_standard tap *
  page129_i65
#ISCELL
  mstr_standard offpage *
  page129_i67
#CELL
  mstr_discrete cap *
  page129_i69
#CELL
  mstr_discrete cap *
  page129_i70
#CELL
  mstr_discrete cap *
  page129_i71
#CELL
  mstr_discrete cap *
  page129_i72
#CELL
  mstr_discrete cap *
  page129_i73
#CELL
  mstr_discrete cap *
  page129_i74
#CELL
  mstr_discrete cap *
  page129_i75
#CELL
  mstr_discrete cap *
  page129_i76
#CELL
  mstr_discrete cap *
  page129_i77
#CELL
  mstr_discrete cap *
  page129_i78
#CELL
  mstr_discrete cap *
  page129_i79
#CELL
  mstr_discrete cap *
  page129_i80
#CELL
  mstr_discrete cap *
  page129_i81
#CELL
  mstr_discrete cap *
  page129_i82
#CELL
  mstr_discrete cap *
  page129_i83
#ISCELL
  mstr_symbols cad_note *
  *
#ISCELL
  mstr_symbols design_note *
  *
#ISCELL
  mstr_symbols intel_corp_bpage *
  *
#CELL
  dev_discrete cap_a *
  page130_i12
#ISCELL
  mstr_symbols gnd *
  page130_i13
#ISCELL
  mstr_symbols gnd *
  page130_i14
#CELL
  mstr_discrete cap *
  page130_i15
#CELL
  dev_discrete cap_a *
  page130_i16
#ISCELL
  mstr_symbols gnd *
  page130_i17
#ISCELL
  mstr_standard offpage *
  page130_i18
#CELL
  mstr_discrete cap *
  page130_i19
#CELL
  mstr_discrete cap *
  page130_i2
#CELL
  mstr_discrete cap *
  page130_i20
#CELL
  mstr_discrete cap *
  page130_i21
#CELL
  mstr_discrete cap *
  page130_i22
#CELL
  mstr_discrete cap *
  page130_i24
#CELL
  mstr_discrete cap *
  page130_i25
#ISCELL
  mstr_symbols gnd *
  page130_i27
#CELL
  mstr_discrete cap *
  page130_i28
#CELL
  dev_discrete cap_a *
  page130_i29
#ISCELL
  mstr_symbols gnd *
  page130_i3
#CELL
  dev_discrete cap_a *
  page130_i30
#ISCELL
  mstr_symbols p1v8_pch_stby *
  page130_i31
#CELL
  dev_discrete cap_a *
  page130_i32
#ISCELL
  mstr_symbols gnd *
  page130_i33
#CELL
  dev_discrete cap_a *
  page130_i34
#ISCELL
  mstr_symbols gnd *
  page130_i35
#CELL
  dev_discrete cap_a *
  page130_i37
#CELL
  dev_discrete cap_a *
  page130_i38
#CELL
  dev_discrete cap_a *
  page130_i39
#CELL
  dev_discrete cap_a *
  page130_i4
#ISCELL
  mstr_symbols gnd *
  page130_i40
#CELL
  dev_discrete cap_a *
  page130_i41
#CELL
  dev_discrete cap_a *
  page130_i42
#CELL
  dev_discrete cap_a *
  page130_i43
#ISCELL
  mstr_symbols p1v8_pch_stby *
  page130_i44
#CELL
  dev_discrete cap_a *
  page130_i45
#ISCELL
  mstr_symbols gnd *
  page130_i46
#CELL
  dev_discrete cap_a *
  page130_i47
#ISCELL
  mstr_symbols gnd *
  page130_i48
#CELL
  dev_discrete cap_a *
  page130_i49
#CELL
  dev_discrete cap_a *
  page130_i50
#ISCELL
  mstr_symbols p1v8_pch_stby *
  page130_i51
#CELL
  dev_discrete cap_a *
  page130_i52
#CELL
  dev_discrete cap_a *
  page130_i53
#ISCELL
  mstr_symbols p3v3_stby *
  page130_i54
#ISCELL
  mstr_symbols p3v3_stby *
  page130_i55
#ISCELL
  mstr_symbols p3v3_stby *
  page130_i58
#ISCELL
  mstr_symbols p3v3_stby *
  page130_i59
#ISCELL
  mstr_symbols gnd *
  page130_i6
#ISCELL
  mstr_symbols p3v3_stby *
  page130_i60
#ISCELL
  mstr_symbols p3v3_stby *
  page130_i61
#ISCELL
  mstr_symbols p3v3_stby *
  page130_i62
#CELL
  dev_discrete cap_a *
  page130_i7
#CELL
  mstr_discrete cap *
  page130_i8
#CELL
  mstr_discrete cap *
  page130_i9
#ISCELL
  mstr_symbols cad_note *
  *
#ISCELL
  mstr_symbols design_note *
  *
#ISCELL
  mstr_symbols intel_corp_bpage *
  *
#CELL
  dev_discrete cap_a *
  page131_i1
#CELL
  dev_discrete cap_a *
  page131_i10
#CELL
  dev_discrete cap_a *
  page131_i11
#CELL
  dev_discrete cap_a *
  page131_i12
#ISCELL
  mstr_symbols gnd *
  page131_i13
#CELL
  dev_discrete cap_a *
  page131_i14
#CELL
  dev_discrete cap_a *
  page131_i15
#CELL
  dev_discrete cap_a *
  page131_i16
#ISCELL
  mstr_symbols p1v05_pch_stby *
  page131_i17
#CELL
  dev_discrete cap_a *
  page131_i18
#ISCELL
  mstr_symbols p1v05_pch_stby *
  page131_i19
#CELL
  dev_discrete cap_a *
  page131_i2
#CELL
  dev_discrete cap_a *
  page131_i20
#ISCELL
  mstr_symbols gnd *
  page131_i21
#CELL
  mstr_discrete cap *
  page131_i22
#ISCELL
  mstr_symbols p1v05_pch_stby *
  page131_i23
#CELL
  mstr_discrete cap *
  page131_i24
#ISCELL
  mstr_symbols gnd *
  page131_i25
#ISCELL
  mstr_symbols p1v05_pch_stby *
  page131_i26
#CELL
  dev_discrete cap_a *
  page131_i27
#CELL
  dev_discrete cap_a *
  page131_i28
#CELL
  dev_discrete cap_a *
  page131_i29
#CELL
  dev_discrete cap_a *
  page131_i3
#ISCELL
  mstr_symbols gnd *
  page131_i30
#CELL
  dev_discrete cap_a *
  page131_i31
#CELL
  dev_discrete cap_a *
  page131_i32
#ISCELL
  mstr_symbols gnd *
  page131_i33
#CELL
  mstr_discrete cap *
  page131_i34
#CELL
  mstr_discrete cap *
  page131_i35
#ISCELL
  mstr_symbols p1v05_pch_stby *
  page131_i36
#CELL
  mstr_discrete cap *
  page131_i37
#ISCELL
  mstr_symbols gnd *
  page131_i38
#CELL
  dev_discrete cap_a *
  page131_i39
#CELL
  dev_discrete cap_a *
  page131_i4
#CELL
  dev_discrete cap_a *
  page131_i40
#CELL
  dev_discrete cap_a *
  page131_i41
#CELL
  dev_discrete cap_a *
  page131_i42
#CELL
  dev_discrete cap_a *
  page131_i43
#CELL
  dev_discrete cap_a *
  page131_i44
#CELL
  dev_discrete cap_a *
  page131_i45
#ISCELL
  mstr_symbols p1v05_pch_stby *
  page131_i46
#CELL
  dev_discrete cap_a *
  page131_i47
#CELL
  dev_discrete cap_a *
  page131_i48
#ISCELL
  mstr_symbols p1v05_pch_stby *
  page131_i49
#ISCELL
  mstr_symbols p1v05_pch_stby *
  page131_i5
#CELL
  dev_discrete cap_a *
  page131_i50
#ISCELL
  mstr_symbols gnd *
  page131_i51
#CELL
  dev_discrete cap_a *
  page131_i52
#CELL
  dev_discrete cap_a *
  page131_i6
#CELL
  dev_discrete cap_a *
  page131_i7
#CELL
  dev_discrete cap_a *
  page131_i8
#ISCELL
  mstr_symbols gnd *
  page131_i9
#ISCELL
  mstr_symbols cad_note *
  *
#ISCELL
  mstr_symbols design_note *
  *
#ISCELL
  mstr_symbols intel_corp_bpage *
  *
#CELL
  dev_discrete cap_a *
  page132_i1
#ISCELL
  mstr_symbols gnd *
  page132_i10
#CELL
  dev_discrete cap_a *
  page132_i11
#CELL
  dev_discrete cap_a *
  page132_i12
#CELL
  dev_discrete cap_a *
  page132_i13
#ISCELL
  mstr_symbols pvnn_pch_stby *
  page132_i14
#ISCELL
  mstr_symbols gnd *
  page132_i15
#CELL
  dev_discrete cap_a *
  page132_i16
#CELL
  dev_discrete cap_a *
  page132_i17
#ISCELL
  mstr_symbols pvnn_pch_stby *
  page132_i18
#CELL
  dev_discrete cap_a *
  page132_i19
#CELL
  dev_discrete cap_a *
  page132_i2
#CELL
  dev_discrete cap_a *
  page132_i20
#ISCELL
  mstr_symbols gnd *
  page132_i21
#ISCELL
  mstr_symbols pvnn_pch_stby *
  page132_i22
#CELL
  mstr_discrete cap *
  page132_i23
#CELL
  mstr_discrete cap *
  page132_i24
#ISCELL
  mstr_symbols gnd *
  page132_i25
#CELL
  dev_discrete cap_a *
  page132_i26
#CELL
  dev_discrete cap_a *
  page132_i27
#CELL
  dev_discrete cap_a *
  page132_i28
#CELL
  dev_discrete cap_a *
  page132_i29
#CELL
  dev_discrete cap_a *
  page132_i3
#CELL
  dev_discrete cap_a *
  page132_i30
#CELL
  dev_discrete cap_a *
  page132_i31
#CELL
  dev_discrete cap_a *
  page132_i32
#ISCELL
  mstr_symbols gnd *
  page132_i33
#CELL
  dev_discrete cap_a *
  page132_i34
#CELL
  dev_discrete cap_a *
  page132_i35
#CELL
  dev_discrete cap_a *
  page132_i36
#ISCELL
  mstr_symbols gnd *
  page132_i37
#CELL
  mstr_discrete cap *
  page132_i38
#ISCELL
  mstr_symbols pvnn_pch_stby *
  page132_i39
#CELL
  dev_discrete cap_a *
  page132_i4
#CELL
  mstr_discrete cap *
  page132_i40
#ISCELL
  mstr_symbols gnd *
  page132_i41
#CELL
  dev_discrete cap_a *
  page132_i42
#CELL
  dev_discrete cap_a *
  page132_i43
#CELL
  dev_discrete cap_a *
  page132_i44
#CELL
  dev_discrete cap_a *
  page132_i45
#CELL
  dev_discrete cap_a *
  page132_i46
#ISCELL
  mstr_symbols pvnn_pch_stby *
  page132_i47
#CELL
  dev_discrete cap_a *
  page132_i48
#CELL
  dev_discrete cap_a *
  page132_i49
#ISCELL
  mstr_symbols pvnn_pch_stby *
  page132_i5
#ISCELL
  mstr_symbols pvnn_pch_stby *
  page132_i50
#CELL
  dev_discrete cap_a *
  page132_i51
#CELL
  dev_discrete cap_a *
  page132_i52
#ISCELL
  mstr_symbols pvnn_pch_stby *
  page132_i53
#CELL
  dev_discrete cap_a *
  page132_i54
#ISCELL
  mstr_symbols gnd *
  page132_i55
#CELL
  dev_discrete cap_a *
  page132_i56
#CELL
  dev_discrete cap_a *
  page132_i6
#CELL
  dev_discrete cap_a *
  page132_i7
#CELL
  dev_discrete cap_a *
  page132_i8
#CELL
  dev_discrete cap_a *
  page132_i9
#ISCELL
  mstr_misc dns *
  *
#ISCELL
  mstr_symbols design_note *
  *
#ISCELL
  mstr_symbols intel_corp_bpage *
  *
#ISCELL
  mstr_symbols gnd *
  page133_i110
#ISCELL
  mstr_standard offpage *
  page133_i112
#ISCELL
  mstr_standard offpage *
  page133_i117
#CELL
  mstr_discrete res *
  page133_i120
#CELL
  mstr_discrete res *
  page133_i122
#CELL
  mstr_discrete res *
  page133_i200
#CELL
  mstr_discrete res *
  page133_i202
#ISCELL
  mstr_standard offpage *
  page133_i204
#ISCELL
  mstr_standard offpage *
  page133_i205
#ISCELL
  mstr_standard offpage *
  page133_i206
#ISCELL
  mstr_standard offpage *
  page133_i208
#CELL
  mstr_discrete res *
  page133_i237
#ISCELL
  mstr_standard offpage *
  page133_i238
#ISCELL
  mstr_standard offpage *
  page133_i242
#CELL
  mstr_discrete res *
  page133_i243
#ISCELL
  mstr_standard offpage *
  page133_i244
#CELL
  mstr_discrete res *
  page133_i245
#ISCELL
  mstr_standard offpage *
  page133_i246
#CELL
  mstr_discrete res *
  page133_i247
#ISCELL
  mstr_standard offpage *
  page133_i248
#ISCELL
  mstr_symbols p3v3_stby *
  page133_i251
#ISCELL
  mstr_standard offpage *
  page133_i254
#ISCELL
  mstr_symbols p3v3_stby *
  page133_i256
#ISCELL
  mstr_standard offpage *
  page133_i257
#CELL
  mstr_discrete res *
  page133_i258
#ISCELL
  mstr_standard offpage *
  page133_i259
#ISCELL
  mstr_symbols p3v3_stby *
  page133_i260
#ISCELL
  mstr_standard offpage *
  page133_i264
#CELL
  mstr_discrete res *
  page133_i267
#ISCELL
  mstr_symbols p3v3_stby *
  page133_i268
#ISCELL
  mstr_standard offpage *
  page133_i279
#CELL
  mstr_discrete res *
  page133_i280
#ISCELL
  mstr_standard offpage *
  page133_i281
#CELL
  mstr_discrete res *
  page133_i282
#ISCELL
  mstr_standard offpage *
  page133_i283
#CELL
  mstr_discrete res *
  page133_i284
#ISCELL
  mstr_standard offpage *
  page133_i285
#CELL
  mstr_discrete res *
  page133_i286
#ISCELL
  mstr_standard offpage *
  page133_i287
#ISCELL
  mstr_standard offpage *
  page133_i289
#ISCELL
  mstr_standard offpage *
  page133_i292
#ISCELL
  mstr_standard offpage *
  page133_i293
#ISCELL
  mstr_standard offpage *
  page133_i294
#CELL
  mstr_discrete res *
  page133_i295
#CELL
  mstr_discrete res *
  page133_i296
#CELL
  mstr_discrete res *
  page133_i297
#ISCELL
  mstr_symbols p3v3_stby *
  page133_i298
#ISCELL
  mstr_standard offpage *
  page133_i299
#ISCELL
  mstr_symbols p3v3_stby *
  page133_i300
#CELL
  mstr_discrete res *
  page133_i301
#ISCELL
  mstr_symbols p3v3_stby *
  page133_i302
#CELL
  mstr_discrete res *
  page133_i303
#CELL
  mstr_discrete res *
  page133_i304
#CELL
  mstr_discrete res *
  page133_i306
#CELL
  mstr_discrete res *
  page133_i307
#CELL
  mstr_discrete res *
  page133_i309
#ISCELL
  mstr_standard offpage *
  page133_i311
#ISCELL
  mstr_standard offpage *
  page133_i312
#ISCELL
  mstr_standard offpage *
  page133_i313
#ISCELL
  mstr_standard offpage *
  page133_i314
#CELL
  mstr_discrete res *
  page133_i315
#CELL
  mstr_discrete res *
  page133_i316
#CELL
  mstr_discrete res *
  page133_i317
#CELL
  mstr_discrete res *
  page133_i318
#ISCELL
  mstr_standard offpage *
  page133_i319
#ISCELL
  mstr_standard offpage *
  page133_i320
#CELL
  mstr_discrete res *
  page133_i321
#CELL
  mstr_discrete res *
  page133_i322
#ISCELL
  mstr_standard offpage *
  page133_i325
#CELL
  mstr_discrete res *
  page133_i326
#CELL
  mstr_discrete res *
  page133_i327
#ISCELL
  mstr_standard offpage *
  page133_i328
#CELL
  mstr_discrete res *
  page133_i331
#CELL
  mstr_discrete res *
  page133_i332
#CELL
  mstr_discrete res *
  page133_i333
#ISCELL
  mstr_standard offpage *
  page133_i334
#ISCELL
  mstr_symbols p3v3_stby *
  page133_i335
#ISCELL
  mstr_symbols p1v05_pch_stby *
  page133_i339
#ISCELL
  mstr_standard offpage *
  page133_i340
#CELL
  mstr_discrete res *
  page133_i341
#ISCELL
  mstr_symbols p3v3_stby *
  page133_i342
#CELL
  mstr_discrete res *
  page133_i349
#ISCELL
  mstr_standard offpage *
  page133_i350
#ISCELL
  mstr_standard offpage *
  page133_i351
#CELL
  mstr_discrete res *
  page133_i352
#ISCELL
  mstr_symbols p3v3_stby *
  page133_i353
#ISCELL
  mstr_standard offpage *
  page133_i354
#CELL
  mstr_discrete res *
  page133_i355
#CELL
  mstr_discrete res *
  page133_i356
#CELL
  mstr_discrete res *
  page133_i357
#ISCELL
  mstr_standard offpage *
  page133_i358
#ISCELL
  mstr_standard offpage *
  page133_i359
#CELL
  mstr_discrete res *
  page133_i360
#ISCELL
  mstr_standard offpage *
  page133_i361
#CELL
  mstr_discrete res *
  page133_i362
#ISCELL
  mstr_standard offpage *
  page133_i363
#ISCELL
  mstr_symbols intel_corp_bpage *
  *
#ISCELL
  mstr_standard offpage *
  page134_i1
#CELL
  mstr_discrete fet_n *
  page134_i10
#CELL
  mstr_discrete res *
  page134_i11
#ISCELL
  mstr_symbols gnd *
  page134_i12
#ISCELL
  mstr_standard offpage *
  page134_i13
#ISCELL
  mstr_symbols p3v3_stby *
  page134_i2
#CELL
  mstr_discrete res *
  page134_i3
#CELL
  mstr_discrete fet_n *
  page134_i4
#ISCELL
  mstr_standard offpage *
  page134_i5
#ISCELL
  mstr_standard offpage *
  page134_i6
#ISCELL
  mstr_standard offpage *
  page134_i7
#ISCELL
  mstr_symbols p1v05_pch_stby *
  page134_i8
#CELL
  mstr_discrete res *
  page134_i9
#ISCELL
  mstr_misc dns *
  *
#ISCELL
  mstr_symbols cad_note *
  *
#ISCELL
  mstr_symbols design_note *
  *
#ISCELL
  mstr_symbols intel_corp_bpage *
  *
#ISCELL
  mstr_symbols p3v3_stby *
  page135_i106
#CELL
  mstr_discrete res *
  page135_i107
#ISCELL
  mstr_standard offpage *
  page135_i108
#ISCELL
  mstr_standard offpage *
  page135_i109
#ISCELL
  mstr_standard offpage *
  page135_i110
#ISCELL
  mstr_symbols p3v3_stby *
  page135_i111
#CELL
  mstr_discrete res *
  page135_i112
#CELL
  mstr_discrete res *
  page135_i113
#ISCELL
  mstr_symbols gnd *
  page135_i114
#ISCELL
  mstr_standard offpage *
  page135_i115
#ISCELL
  mstr_symbols p3v3_stby *
  page135_i116
#CELL
  mstr_discrete res *
  page135_i117
#CELL
  mstr_discrete res *
  page135_i118
#ISCELL
  mstr_symbols p3v3_stby *
  page135_i119
#CELL
  mstr_discrete res *
  page135_i120
#CELL
  mstr_discrete res *
  page135_i121
#ISCELL
  mstr_symbols p3v3_stby *
  page135_i122
#ISCELL
  mstr_symbols gnd *
  page135_i123
#CELL
  mstr_conn conn12_c73564003 *
  page135_i124
#ISCELL
  mstr_symbols gnd *
  page135_i125
#ISCELL
  mstr_standard offpage *
  page135_i126
#ISCELL
  mstr_standard offpage *
  page135_i127
#ISCELL
  mstr_symbols p3v3_stby *
  page135_i128
#CELL
  mstr_discrete res *
  page135_i129
#ISCELL
  mstr_symbols gnd *
  page135_i130
#CELL
  mstr_conn conn4_d42317002 *
  page135_i131
#ISCELL
  mstr_symbols bom_note *
  *
#ISCELL
  mstr_symbols cad_note *
  *
#ISCELL
  mstr_symbols design_note *
  *
#ISCELL
  mstr_symbols intel_corp_bpage *
  *
#CELL
  mstr_discrete res *
  page136_i101
#CELL
  mstr_discrete res *
  page136_i102
#ISCELL
  mstr_symbols gnd *
  page136_i103
#ISCELL
  mstr_symbols p3v3_stby *
  page136_i124
#ISCELL
  mstr_standard offpage *
  page136_i125
#CELL
  mstr_discrete res *
  page136_i126
#ISCELL
  mstr_symbols p3v3_stby *
  page136_i127
#CELL
  dev_discrete cap_a *
  page136_i128
#ISCELL
  mstr_symbols gnd *
  page136_i129
#CELL
  mstr_ttl ttl1g126_a *
  page136_i130
#ISCELL
  mstr_symbols p3v3_stby *
  page136_i131
#ISCELL
  mstr_standard offpage *
  page136_i132
#CELL
  mstr_discrete res *
  page136_i133
#CELL
  mstr_discrete fet_n *
  page136_i134
#ISCELL
  mstr_symbols gnd *
  page136_i135
#ISCELL
  mstr_standard offpage *
  page136_i136
#CELL
  mstr_discrete res *
  page136_i139
#CELL
  mstr_discrete res *
  page136_i140
#ISCELL
  mstr_symbols gnd *
  page136_i141
#CELL
  mstr_discrete res *
  page136_i147
#CELL
  mstr_discrete res *
  page136_i148
#ISCELL
  mstr_symbols gnd *
  page136_i152
#ISCELL
  mstr_symbols p3v3_stby *
  page136_i154
#CELL
  mstr_discrete res *
  page136_i155
#CELL
  mstr_discrete res *
  page136_i156
#ISCELL
  mstr_symbols gnd *
  page136_i157
#ISCELL
  mstr_standard offpage *
  page136_i162
#ISCELL
  mstr_standard offpage *
  page136_i165
#ISCELL
  mstr_standard offpage *
  page136_i170
#CELL
  mstr_conn conn12_c73564003 *
  page136_i174
#ISCELL
  mstr_standard offpage *
  page136_i175
#ISCELL
  mstr_misc dns *
  *
#ISCELL
  mstr_symbols bom_note *
  *
#ISCELL
  mstr_symbols cad_note *
  *
#ISCELL
  mstr_symbols design_note *
  *
#ISCELL
  mstr_symbols intel_corp_bpage *
  *
#CELL
  mstr_discrete res *
  page137_i11
#ISCELL
  mstr_standard offpage *
  page137_i123
#ISCELL
  mstr_standard offpage *
  page137_i124
#ISCELL
  mstr_standard offpage *
  page137_i126
#CELL
  mstr_conn conn12_c73564003 *
  page137_i128
#ISCELL
  mstr_standard offpage *
  page137_i129
#CELL
  mstr_discrete res *
  page137_i13
#CELL
  dev_discrete cap_a *
  page137_i14
#CELL
  mstr_discrete res *
  page137_i15
#ISCELL
  mstr_symbols gnd *
  page137_i16
#ISCELL
  mstr_standard offpage *
  page137_i17
#CELL
  mstr_discrete res *
  page137_i19
#CELL
  dev_discrete cap_a *
  page137_i20
#ISCELL
  mstr_symbols gnd *
  page137_i21
#CELL
  mstr_discrete res *
  page137_i67
#ISCELL
  mstr_symbols p3v3_stby *
  page137_i68
#CELL
  mstr_discrete res *
  page137_i69
#ISCELL
  mstr_symbols gnd *
  page137_i70
#ISCELL
  mstr_symbols p3v3_rtc_stby *
  page137_i78
#ISCELL
  mstr_symbols p3v3_rtc_stby *
  page137_i79
#ISCELL
  mstr_misc dns *
  *
#ISCELL
  mstr_symbols cad_note *
  *
#ISCELL
  mstr_symbols design_note *
  *
#ISCELL
  mstr_symbols intel_corp_bpage *
  *
#ISCELL
  mstr_standard offpage *
  page138_i100
#ISCELL
  mstr_standard offpage *
  page138_i103
#ISCELL
  mstr_standard offpage *
  page138_i104
#ISCELL
  mstr_standard offpage *
  page138_i105
#ISCELL
  mstr_standard offpage *
  page138_i108
#ISCELL
  mstr_standard offpage *
  page138_i111
#ISCELL
  mstr_standard offpage *
  page138_i114
#ISCELL
  mstr_standard offpage *
  page138_i115
#ISCELL
  mstr_standard offpage *
  page138_i122
#ISCELL
  mstr_standard offpage *
  page138_i123
#ISCELL
  mstr_standard offpage *
  page138_i126
#ISCELL
  mstr_standard offpage *
  page138_i127
#ISCELL
  mstr_symbols p3v3_stby *
  page138_i138
#ISCELL
  mstr_symbols p3v3_stby *
  page138_i139
#ISCELL
  mstr_symbols p3v3_stby *
  page138_i140
#ISCELL
  mstr_symbols p3v3_stby *
  page138_i141
#ISCELL
  mstr_symbols p3v3_stby *
  page138_i144
#ISCELL
  mstr_symbols p3v3_stby *
  page138_i145
#ISCELL
  mstr_symbols p3v3_stby *
  page138_i146
#ISCELL
  mstr_symbols p3v3_stby *
  page138_i147
#ISCELL
  mstr_symbols p3v3_stby *
  page138_i148
#ISCELL
  mstr_symbols p3v3_stby *
  page138_i149
#ISCELL
  mstr_symbols p3v3_stby *
  page138_i150
#ISCELL
  mstr_symbols p3v3_stby *
  page138_i151
#ISCELL
  mstr_standard offpage *
  page138_i154
#ISCELL
  mstr_standard offpage *
  page138_i155
#ISCELL
  mstr_standard offpage *
  page138_i156
#ISCELL
  mstr_standard offpage *
  page138_i157
#CELL
  mstr_discrete res *
  page138_i158
#CELL
  mstr_discrete res *
  page138_i159
#CELL
  mstr_discrete res *
  page138_i161
#CELL
  mstr_discrete res *
  page138_i162
#CELL
  mstr_discrete res *
  page138_i163
#CELL
  mstr_discrete res *
  page138_i164
#CELL
  mstr_discrete res *
  page138_i165
#CELL
  mstr_discrete res *
  page138_i166
#CELL
  mstr_discrete res *
  page138_i167
#CELL
  mstr_discrete res *
  page138_i168
#CELL
  mstr_discrete res *
  page138_i169
#CELL
  mstr_discrete res *
  page138_i170
#CELL
  mstr_discrete res *
  page138_i171
#CELL
  mstr_discrete res *
  page138_i173
#CELL
  mstr_discrete res *
  page138_i174
#CELL
  mstr_discrete res *
  page138_i175
#ISCELL
  mstr_standard offpage *
  page138_i45
#ISCELL
  mstr_standard offpage *
  page138_i46
#ISCELL
  mstr_standard offpage *
  page138_i47
#ISCELL
  mstr_standard offpage *
  page138_i48
#ISCELL
  mstr_standard offpage *
  page138_i49
#ISCELL
  mstr_standard offpage *
  page138_i50
#ISCELL
  mstr_standard offpage *
  page138_i51
#ISCELL
  mstr_standard offpage *
  page138_i52
#ISCELL
  mstr_standard offpage *
  page138_i53
#ISCELL
  mstr_standard offpage *
  page138_i54
#ISCELL
  mstr_standard offpage *
  page138_i57
#ISCELL
  mstr_standard offpage *
  page138_i58
#ISCELL
  mstr_standard offpage *
  page138_i59
#ISCELL
  mstr_standard offpage *
  page138_i60
#CELL
  mstr_discrete res *
  page138_i83
#CELL
  mstr_discrete res *
  page138_i84
#CELL
  mstr_discrete res *
  page138_i87
#CELL
  mstr_discrete res *
  page138_i88
#CELL
  mstr_discrete res *
  page138_i89
#CELL
  mstr_discrete res *
  page138_i90
#CELL
  mstr_discrete res *
  page138_i91
#CELL
  mstr_discrete res *
  page138_i92
#CELL
  mstr_discrete res *
  page138_i95
#CELL
  mstr_discrete res *
  page138_i96
#CELL
  mstr_discrete res *
  page138_i97
#CELL
  mstr_discrete res *
  page138_i98
#ISCELL
  mstr_misc dns *
  *
#ISCELL
  mstr_symbols cad_note *
  *
#ISCELL
  mstr_symbols design_note *
  *
#ISCELL
  mstr_symbols intel_corp_bpage *
  *
#ISCELL
  mstr_standard offpage *
  page139_i101
#ISCELL
  mstr_standard offpage *
  page139_i102
#ISCELL
  mstr_standard offpage *
  page139_i103
#ISCELL
  mstr_standard offpage *
  page139_i104
#ISCELL
  mstr_standard offpage *
  page139_i105
#ISCELL
  mstr_standard offpage *
  page139_i106
#ISCELL
  mstr_standard offpage *
  page139_i107
#ISCELL
  mstr_standard offpage *
  page139_i108
#CELL
  mstr_discrete crystal *
  page139_i109
#CELL
  mstr_discrete res *
  page139_i110
#CELL
  mstr_discrete cap *
  page139_i111
#CELL
  mstr_discrete cap *
  page139_i112
#ISCELL
  mstr_symbols gnd *
  page139_i113
#ISCELL
  mstr_symbols gnd *
  page139_i114
#ISCELL
  mstr_standard offpage *
  page139_i115
#ISCELL
  mstr_standard offpage *
  page139_i116
#ISCELL
  mstr_standard offpage *
  page139_i117
#ISCELL
  mstr_standard offpage *
  page139_i118
#ISCELL
  mstr_standard offpage *
  page139_i127
#CELL
  mstr_discrete res *
  page139_i128
#CELL
  mstr_discrete res *
  page139_i129
#CELL
  mstr_discrete res *
  page139_i130
#ISCELL
  mstr_standard offpage *
  page139_i131
#ISCELL
  mstr_standard offpage *
  page139_i132
#ISCELL
  mstr_standard offpage *
  page139_i133
#CELL
  mstr_discrete cap *
  page139_i134
#CELL
  mstr_discrete cap *
  page139_i135
#CELL
  mstr_discrete cap *
  page139_i136
#ISCELL
  mstr_symbols gnd *
  page139_i137
#ISCELL
  mstr_symbols gnd *
  page139_i138
#ISCELL
  mstr_symbols gnd *
  page139_i139
#CELL
  mstr_discrete cap *
  page139_i140
#CELL
  mstr_discrete cap *
  page139_i142
#CELL
  dev_discrete cap_a *
  page139_i143
#CELL
  dev_discrete cap_a *
  page139_i144
#CELL
  dev_discrete cap_a *
  page139_i145
#CELL
  dev_discrete cap_a *
  page139_i146
#ISCELL
  mstr_symbols gnd *
  page139_i147
#CELL
  dev_discrete cap_a *
  page139_i149
#CELL
  dev_discrete cap_a *
  page139_i150
#CELL
  dev_discrete cap_a *
  page139_i151
#CELL
  dev_discrete cap_a *
  page139_i152
#CELL
  mstr_discrete cap *
  page139_i153
#ISCELL
  mstr_symbols p1v5_lan *
  page139_i154
#CELL
  mstr_discrete cap *
  page139_i155
#ISCELL
  mstr_symbols gnd *
  page139_i156
#CELL
  dev_discrete cap_a *
  page139_i157
#CELL
  dev_discrete cap_a *
  page139_i158
#CELL
  dev_discrete cap_a *
  page139_i159
#CELL
  dev_discrete cap_a *
  page139_i160
#CELL
  mstr_discrete cap *
  page139_i161
#ISCELL
  mstr_symbols p0v9_lan *
  page139_i162
#CELL
  dev_discrete cap_a *
  page139_i163
#ISCELL
  mstr_symbols gnd *
  page139_i164
#ISCELL
  mstr_standard offpage *
  page139_i165
#ISCELL
  mstr_standard offpage *
  page139_i166
#ISCELL
  mstr_standard offpage *
  page139_i167
#ISCELL
  mstr_standard offpage *
  page139_i172
#CELL
  mstr_discrete res *
  page139_i173
#CELL
  mstr_discrete res *
  page139_i174
#ISCELL
  mstr_standard offpage *
  page139_i175
#ISCELL
  mstr_symbols gnd *
  page139_i176
#CELL
  mstr_discrete res *
  page139_i177
#CELL
  mstr_discrete res *
  page139_i178
#CELL
  mstr_discrete res *
  page139_i179
#ISCELL
  mstr_symbols p3v3_stby *
  page139_i180
#CELL
  mstr_discrete res *
  page139_i181
#ISCELL
  mstr_symbols p3v3_stby *
  page139_i182
#ISCELL
  mstr_standard offpage *
  page139_i183
#ISCELL
  mstr_standard offpage *
  page139_i184
#ISCELL
  mstr_standard offpage *
  page139_i185
#ISCELL
  mstr_symbols p3v3_stby *
  page139_i186
#ISCELL
  mstr_symbols p3v3_stby *
  page139_i188
#ISCELL
  mstr_symbols p3v3_stby *
  page139_i189
#ISCELL
  mstr_standard offpage *
  page139_i191
#ISCELL
  mstr_standard offpage *
  page139_i192
#CELL
  mstr_discrete res *
  page139_i193
#ISCELL
  mstr_symbols p3v3_stby *
  page139_i194
#CELL
  mstr_discrete res *
  page139_i195
#ISCELL
  mstr_standard offpage *
  page139_i197
#ISCELL
  mstr_standard offpage *
  page139_i198
#ISCELL
  mstr_symbols p3v3_stby *
  page139_i199
#CELL
  mstr_discrete res *
  page139_i200
#CELL
  mstr_discrete res *
  page139_i201
#ISCELL
  mstr_standard offpage *
  page139_i202
#ISCELL
  mstr_standard offpage *
  page139_i203
#ISCELL
  mstr_symbols gnd *
  page139_i204
#ISCELL
  mstr_standard offpage *
  page139_i206
#ISCELL
  mstr_symbols gnd *
  page139_i207
#ISCELL
  mstr_standard offpage *
  page139_i209
#ISCELL
  mstr_symbols gnd *
  page139_i211
#CELL
  mstr_discrete res *
  page139_i212
#CELL
  mstr_discrete res *
  page139_i213
#CELL
  mstr_discrete res *
  page139_i214
#ISCELL
  mstr_standard offpage *
  page139_i218
#ISCELL
  mstr_standard offpage *
  page139_i219
#ISCELL
  mstr_standard offpage *
  page139_i220
#ISCELL
  mstr_standard offpage *
  page139_i223
#ISCELL
  mstr_standard offpage *
  page139_i224
#CELL
  mstr_discrete res *
  page139_i225
#ISCELL
  mstr_standard offpage *
  page139_i226
#ISCELL
  mstr_standard offpage *
  page139_i227
#CELL
  mstr_discrete res *
  page139_i228
#CELL
  mstr_discrete res *
  page139_i229
#ISCELL
  mstr_standard offpage *
  page139_i230
#ISCELL
  mstr_standard offpage *
  page139_i231
#ISCELL
  mstr_standard offpage *
  page139_i233
#CELL
  mstr_discrete res *
  page139_i235
#ISCELL
  mstr_standard offpage *
  page139_i236
#CELL
  mstr_discrete res *
  page139_i237
#CELL
  mstr_discrete res *
  page139_i238
#CELL
  mstr_discrete res *
  page139_i239
#CELL
  mstr_discrete res *
  page139_i240
#CELL
  dev_discrete cap_a *
  page139_i241
#CELL
  mstr_intel springville *
  page139_i72
#ISCELL
  mstr_symbols p0v9_lan *
  page139_i73
#ISCELL
  mstr_symbols p1v5_lan *
  page139_i74
#CELL
  mstr_discrete cap *
  page139_i76
#ISCELL
  mstr_symbols gnd *
  page139_i77
#ISCELL
  mstr_standard offpage *
  page139_i84
#ISCELL
  mstr_standard offpage *
  page139_i85
#ISCELL
  mstr_standard offpage *
  page139_i86
#CELL
  dev_discrete cap_a *
  page139_i87
#CELL
  dev_discrete cap_a *
  page139_i88
#CELL
  dev_discrete cap_a *
  page139_i89
#CELL
  dev_discrete cap_a *
  page139_i90
#ISCELL
  mstr_standard offpage *
  page139_i91
#ISCELL
  mstr_standard offpage *
  page139_i92
#ISCELL
  mstr_standard offpage *
  page139_i93
#ISCELL
  mstr_standard offpage *
  page139_i94
#ISCELL
  mstr_misc dns *
  *
#ISCELL
  mstr_symbols intel_corp_bpage *
  *
#CELL
  mstr_memory m25pe16 *
  page140_i1
#CELL
  mstr_discrete res *
  page140_i10
#CELL
  mstr_discrete res *
  page140_i11
#CELL
  mstr_discrete res *
  page140_i12
#ISCELL
  mstr_symbols p3v3_stby *
  page140_i13
#CELL
  mstr_discrete res *
  page140_i14
#ISCELL
  mstr_symbols gnd *
  page140_i16
#CELL
  mstr_discrete res *
  page140_i17
#CELL
  dev_discrete cap_a *
  page140_i3
#ISCELL
  mstr_symbols gnd *
  page140_i4
#ISCELL
  mstr_standard offpage *
  page140_i5
#ISCELL
  mstr_standard offpage *
  page140_i6
#ISCELL
  mstr_standard offpage *
  page140_i7
#ISCELL
  mstr_standard offpage *
  page140_i8
#ISCELL
  mstr_symbols gnd *
  page140_i9
#ISCELL
  mstr_misc dns *
  *
#ISCELL
  mstr_symbols cad_note *
  *
#ISCELL
  mstr_symbols design_note *
  *
#ISCELL
  mstr_symbols intel_corp_bpage *
  *
#CELL
  mstr_discrete cap *
  page141_i100
#CELL
  mstr_discrete cap *
  page141_i101
#CELL
  mstr_discrete cap *
  page141_i102
#ISCELL
  mstr_standard offpage *
  page141_i103
#ISCELL
  mstr_standard offpage *
  page141_i104
#ISCELL
  mstr_standard offpage *
  page141_i105
#ISCELL
  mstr_standard offpage *
  page141_i106
#ISCELL
  mstr_symbols gnd_nic *
  page141_i107
#ISCELL
  mstr_symbols gnd_nic *
  page141_i108
#CELL
  mstr_conn conn17_h71061002 *
  page141_i109
#ISCELL
  mstr_symbols gnd_nic *
  page141_i110
#ISCELL
  mstr_symbols gnd *
  page141_i111
#CELL
  mstr_discrete res *
  page141_i112
#ISCELL
  mstr_symbols gnd_nic *
  page141_i113
#CELL
  mstr_discrete res *
  page141_i114
#ISCELL
  mstr_symbols gnd *
  page141_i115
#ISCELL
  mstr_standard offpage *
  page141_i18
#ISCELL
  mstr_standard offpage *
  page141_i19
#ISCELL
  mstr_standard offpage *
  page141_i20
#ISCELL
  mstr_standard offpage *
  page141_i21
#ISCELL
  mstr_standard offpage *
  page141_i22
#ISCELL
  mstr_standard offpage *
  page141_i23
#ISCELL
  mstr_standard offpage *
  page141_i24
#ISCELL
  mstr_standard offpage *
  page141_i25
#CELL
  mstr_discrete res *
  page141_i28
#ISCELL
  mstr_standard offpage *
  page141_i29
#CELL
  mstr_discrete res *
  page141_i30
#ISCELL
  mstr_standard offpage *
  page141_i31
#CELL
  dev_discrete cap_a *
  page141_i33
#ISCELL
  mstr_symbols gnd *
  page141_i35
#CELL
  mstr_discrete cap *
  page141_i36
#ISCELL
  mstr_symbols gnd *
  page141_i38
#ISCELL
  mstr_standard offpage *
  page141_i42
#ISCELL
  mstr_standard offpage *
  page141_i43
#ISCELL
  mstr_standard offpage *
  page141_i44
#ISCELL
  mstr_standard offpage *
  page141_i45
#CELL
  dev_discrete cap_a *
  page141_i46
#CELL
  dev_discrete cap_a *
  page141_i47
#CELL
  mstr_discrete cap *
  page141_i48
#ISCELL
  mstr_standard offpage *
  page141_i49
#ISCELL
  mstr_symbols gnd *
  page141_i50
#ISCELL
  mstr_standard offpage *
  page141_i53
#CELL
  mstr_discrete res *
  page141_i54
#CELL
  mstr_discrete res *
  page141_i56
#CELL
  mstr_discrete cap *
  page141_i58
#CELL
  mstr_discrete cap *
  page141_i59
#CELL
  mstr_discrete cap *
  page141_i60
#ISCELL
  mstr_symbols gnd *
  page141_i61
#ISCELL
  mstr_symbols gnd *
  page141_i62
#ISCELL
  mstr_symbols gnd *
  page141_i63
#ISCELL
  mstr_symbols p3v3_stby *
  page141_i64
#ISCELL
  mstr_symbols p3v3_stby *
  page141_i65
#CELL
  mstr_discrete res *
  page141_i75
#CELL
  mstr_discrete res *
  page141_i76
#CELL
  mstr_discrete res *
  page141_i77
#CELL
  mstr_discrete res *
  page141_i78
#CELL
  mstr_discrete res *
  page141_i79
#CELL
  mstr_discrete res *
  page141_i80
#CELL
  mstr_discrete res *
  page141_i81
#CELL
  mstr_discrete res *
  page141_i82
#ISCELL
  mstr_standard offpage *
  page141_i83
#ISCELL
  mstr_standard offpage *
  page141_i84
#ISCELL
  mstr_standard offpage *
  page141_i85
#ISCELL
  mstr_standard offpage *
  page141_i86
#ISCELL
  mstr_standard offpage *
  page141_i87
#ISCELL
  mstr_standard offpage *
  page141_i88
#ISCELL
  mstr_standard offpage *
  page141_i89
#ISCELL
  mstr_standard offpage *
  page141_i90
#ISCELL
  mstr_standard offpage *
  page141_i91
#ISCELL
  mstr_standard offpage *
  page141_i92
#ISCELL
  mstr_standard offpage *
  page141_i93
#ISCELL
  mstr_standard offpage *
  page141_i94
#ISCELL
  mstr_standard offpage *
  page141_i95
#ISCELL
  mstr_standard offpage *
  page141_i96
#ISCELL
  mstr_standard offpage *
  page141_i97
#ISCELL
  mstr_standard offpage *
  page141_i98
#CELL
  mstr_discrete cap *
  page141_i99
#ISCELL
  mstr_misc dns *
  *
#ISCELL
  mstr_symbols cad_note *
  *
#ISCELL
  mstr_symbols design_note *
  *
#ISCELL
  mstr_symbols intel_corp_bpage *
  *
#CELL
  mstr_ttl ttl1g126_a *
  page142_i1
#ISCELL
  mstr_standard offpage *
  page142_i11
#ISCELL
  mstr_standard offpage *
  page142_i12
#ISCELL
  mstr_standard offpage *
  page142_i13
#ISCELL
  mstr_standard offpage *
  page142_i17
#CELL
  mstr_discrete res *
  page142_i18
#ISCELL
  mstr_standard offpage *
  page142_i19
#CELL
  mstr_discrete res *
  page142_i2
#CELL
  dev_discrete cap_a *
  page142_i20
#ISCELL
  mstr_symbols p3v3_stby *
  page142_i21
#ISCELL
  mstr_symbols gnd *
  page142_i22
#CELL
  mstr_discrete res *
  page142_i23
#ISCELL
  mstr_symbols p3v3_stby *
  page142_i24
#CELL
  mstr_discrete res *
  page142_i28
#CELL
  mstr_discrete res *
  page142_i3
#CELL
  mstr_discrete res *
  page142_i30
#CELL
  mstr_discrete res *
  page142_i31
#CELL
  mstr_discrete res *
  page142_i32
#CELL
  mstr_discrete res *
  page142_i33
#ISCELL
  mstr_symbols p3v3_stby *
  page142_i4
#ISCELL
  mstr_standard offpage *
  page142_i5
#ISCELL
  mstr_symbols intel_corp_bpage *
  *
#ISCELL
  mstr_standard offpage *
  page143_i10
#ISCELL
  mstr_standard offpage *
  page143_i11
#ISCELL
  mstr_standard offpage *
  page143_i12
#ISCELL
  mstr_standard offpage *
  page143_i13
#ISCELL
  mstr_standard offpage *
  page143_i14
#ISCELL
  mstr_standard offpage *
  page143_i15
#ISCELL
  mstr_standard offpage *
  page143_i16
#ISCELL
  mstr_standard offpage *
  page143_i17
#ISCELL
  mstr_standard offpage *
  page143_i18
#ISCELL
  mstr_standard offpage *
  page143_i19
#ISCELL
  mstr_standard offpage *
  page143_i2
#ISCELL
  mstr_standard offpage *
  page143_i20
#ISCELL
  mstr_standard offpage *
  page143_i21
#ISCELL
  mstr_standard offpage *
  page143_i23
#ISCELL
  mstr_standard offpage *
  page143_i24
#ISCELL
  mstr_standard offpage *
  page143_i25
#ISCELL
  mstr_standard offpage *
  page143_i26
#ISCELL
  mstr_standard offpage *
  page143_i27
#ISCELL
  mstr_standard offpage *
  page143_i28
#ISCELL
  mstr_standard offpage *
  page143_i29
#ISCELL
  mstr_standard offpage *
  page143_i3
#ISCELL
  mstr_standard offpage *
  page143_i30
#ISCELL
  mstr_standard offpage *
  page143_i31
#ISCELL
  mstr_standard offpage *
  page143_i33
#ISCELL
  mstr_standard offpage *
  page143_i34
#ISCELL
  mstr_standard offpage *
  page143_i36
#ISCELL
  mstr_standard offpage *
  page143_i37
#ISCELL
  mstr_standard offpage *
  page143_i38
#ISCELL
  mstr_standard offpage *
  page143_i39
#ISCELL
  mstr_standard offpage *
  page143_i4
#ISCELL
  mstr_standard offpage *
  page143_i40
#ISCELL
  mstr_standard offpage *
  page143_i41
#ISCELL
  mstr_standard offpage *
  page143_i42
#ISCELL
  mstr_standard offpage *
  page143_i43
#ISCELL
  mstr_standard offpage *
  page143_i44
#ISCELL
  mstr_standard offpage *
  page143_i45
#ISCELL
  mstr_standard offpage *
  page143_i46
#ISCELL
  mstr_standard offpage *
  page143_i47
#ISCELL
  mstr_standard offpage *
  page143_i48
#ISCELL
  mstr_standard offpage *
  page143_i49
#ISCELL
  mstr_standard offpage *
  page143_i5
#ISCELL
  mstr_standard offpage *
  page143_i50
#ISCELL
  mstr_standard offpage *
  page143_i51
#ISCELL
  mstr_standard offpage *
  page143_i52
#ISCELL
  mstr_symbols gnd *
  page143_i54
#CELL
  mstr_discrete cap *
  page143_i55
#ISCELL
  mstr_symbols gnd *
  page143_i57
#CELL
  mstr_discrete res *
  page143_i58
#ISCELL
  mstr_standard offpage *
  page143_i59
#ISCELL
  mstr_standard offpage *
  page143_i6
#ISCELL
  mstr_standard offpage *
  page143_i60
#ISCELL
  mstr_standard offpage *
  page143_i61
#ISCELL
  mstr_standard offpage *
  page143_i62
#CELL
  w_hdl ast2520a1-gp-gp *
  page143_i63
#ISCELL
  mstr_standard offpage *
  page143_i7
#ISCELL
  mstr_standard offpage *
  page143_i8
#ISCELL
  mstr_standard offpage *
  page143_i9
#ISCELL
  mstr_misc dns *
  *
#ISCELL
  mstr_symbols intel_corp_bpage *
  *
#ISCELL
  mstr_standard offpage *
  page144_i24
#ISCELL
  mstr_standard offpage *
  page144_i25
#ISCELL
  mstr_standard offpage *
  page144_i26
#ISCELL
  mstr_standard offpage *
  page144_i27
#ISCELL
  mstr_standard offpage *
  page144_i28
#ISCELL
  mstr_standard offpage *
  page144_i29
#ISCELL
  mstr_standard offpage *
  page144_i30
#ISCELL
  mstr_standard offpage *
  page144_i31
#ISCELL
  mstr_standard offpage *
  page144_i32
#ISCELL
  mstr_standard offpage *
  page144_i33
#ISCELL
  mstr_standard offpage *
  page144_i34
#ISCELL
  mstr_standard offpage *
  page144_i35
#ISCELL
  mstr_standard offpage *
  page144_i36
#ISCELL
  mstr_standard offpage *
  page144_i37
#ISCELL
  mstr_standard offpage *
  page144_i4
#ISCELL
  mstr_standard offpage *
  page144_i44
#ISCELL
  mstr_standard offpage *
  page144_i45
#ISCELL
  mstr_standard offpage *
  page144_i47
#ISCELL
  mstr_standard offpage *
  page144_i48
#ISCELL
  mstr_standard offpage *
  page144_i49
#ISCELL
  mstr_standard offpage *
  page144_i5
#ISCELL
  mstr_standard offpage *
  page144_i50
#ISCELL
  mstr_standard offpage *
  page144_i51
#ISCELL
  mstr_standard offpage *
  page144_i52
#ISCELL
  mstr_standard offpage *
  page144_i53
#ISCELL
  mstr_standard offpage *
  page144_i54
#ISCELL
  mstr_standard offpage *
  page144_i55
#ISCELL
  mstr_standard offpage *
  page144_i56
#CELL
  mstr_discrete res *
  page144_i57
#CELL
  mstr_discrete res *
  page144_i58
#CELL
  mstr_discrete res *
  page144_i59
#ISCELL
  mstr_standard offpage *
  page144_i60
#ISCELL
  mstr_standard offpage *
  page144_i66
#ISCELL
  mstr_standard offpage *
  page144_i67
#ISCELL
  mstr_standard offpage *
  page144_i68
#ISCELL
  mstr_standard offpage *
  page144_i69
#ISCELL
  mstr_standard offpage *
  page144_i70
#ISCELL
  mstr_symbols gnd *
  page144_i72
#CELL
  mstr_discrete res *
  page144_i73
#ISCELL
  mstr_standard offpage *
  page144_i74
#ISCELL
  mstr_standard offpage *
  page144_i75
#ISCELL
  mstr_standard offpage *
  page144_i76
#ISCELL
  mstr_standard offpage *
  page144_i77
#ISCELL
  mstr_standard offpage *
  page144_i78
#ISCELL
  mstr_standard offpage *
  page144_i80
#ISCELL
  mstr_standard offpage *
  page144_i81
#CELL
  mstr_discrete res *
  page144_i82
#ISCELL
  mstr_standard offpage *
  page144_i83
#ISCELL
  mstr_standard offpage *
  page144_i85
#CELL
  mstr_discrete res *
  page144_i89
#CELL
  mstr_discrete res *
  page144_i90
#ISCELL
  mstr_standard offpage *
  page144_i91
#ISCELL
  mstr_standard offpage *
  page144_i92
#ISCELL
  mstr_standard offpage *
  page144_i93
#ISCELL
  mstr_standard offpage *
  page144_i94
#CELL
  w_hdl ast2520a1-gp-gp *
  page144_i95
#ISCELL
  mstr_misc dns *
  *
#ISCELL
  mstr_symbols cad_note *
  *
#ISCELL
  mstr_symbols intel_corp_bpage *
  *
#CELL
  mstr_discrete res *
  page145_i10
#CELL
  mstr_discrete res *
  page145_i100
#CELL
  mstr_discrete res *
  page145_i101
#ISCELL
  mstr_symbols gnd *
  page145_i102
#ISCELL
  mstr_standard offpage *
  page145_i103
#ISCELL
  mstr_standard offpage *
  page145_i104
#ISCELL
  mstr_standard offpage *
  page145_i109
#CELL
  mstr_discrete res *
  page145_i11
#ISCELL
  mstr_standard offpage *
  page145_i110
#ISCELL
  mstr_standard offpage *
  page145_i111
#ISCELL
  mstr_standard offpage *
  page145_i112
#ISCELL
  mstr_standard offpage *
  page145_i115
#ISCELL
  mstr_standard offpage *
  page145_i116
#CELL
  w_hdl ast2520a1-gp-gp *
  page145_i117
#ISCELL
  mstr_standard offpage *
  page145_i12
#ISCELL
  mstr_symbols gnd *
  page145_i13
#CELL
  mstr_discrete res *
  page145_i14
#CELL
  dev_discrete cap_a *
  page145_i15
#ISCELL
  mstr_symbols p3v3_stby *
  page145_i16
#ISCELL
  mstr_symbols gnd *
  page145_i17
#ISCELL
  mstr_standard offpage *
  page145_i18
#ISCELL
  mstr_standard offpage *
  page145_i19
#CELL
  mstr_discrete res *
  page145_i20
#ISCELL
  mstr_standard offpage *
  page145_i21
#CELL
  mstr_discrete res *
  page145_i22
#ISCELL
  mstr_symbols gnd *
  page145_i23
#ISCELL
  mstr_standard offpage *
  page145_i24
#ISCELL
  mstr_standard offpage *
  page145_i25
#ISCELL
  mstr_standard offpage *
  page145_i26
#ISCELL
  mstr_standard offpage *
  page145_i27
#ISCELL
  mstr_standard offpage *
  page145_i28
#ISCELL
  mstr_standard offpage *
  page145_i29
#CELL
  mstr_discrete res *
  page145_i30
#CELL
  mstr_discrete res *
  page145_i31
#ISCELL
  mstr_symbols gnd *
  page145_i32
#ISCELL
  mstr_symbols gnd *
  page145_i33
#CELL
  mstr_discrete res *
  page145_i34
#ISCELL
  mstr_symbols gnd *
  page145_i35
#CELL
  mstr_discrete res *
  page145_i36
#ISCELL
  mstr_symbols gnd *
  page145_i37
#CELL
  mstr_discrete res *
  page145_i38
#ISCELL
  mstr_symbols gnd *
  page145_i39
#ISCELL
  mstr_standard offpage *
  page145_i4
#ISCELL
  mstr_standard offpage *
  page145_i41
#ISCELL
  mstr_standard offpage *
  page145_i42
#ISCELL
  mstr_standard offpage *
  page145_i43
#CELL
  dev_discrete cap_a *
  page145_i44
#CELL
  dev_discrete cap_a *
  page145_i45
#CELL
  mstr_discrete res *
  page145_i46
#ISCELL
  mstr_symbols gnd *
  page145_i47
#ISCELL
  mstr_standard offpage *
  page145_i48
#ISCELL
  mstr_standard offpage *
  page145_i49
#ISCELL
  mstr_standard offpage *
  page145_i5
#ISCELL
  mstr_standard offpage *
  page145_i51
#ISCELL
  mstr_standard offpage *
  page145_i52
#ISCELL
  mstr_standard offpage *
  page145_i53
#ISCELL
  mstr_standard offpage *
  page145_i54
#ISCELL
  mstr_standard offpage *
  page145_i55
#ISCELL
  mstr_standard offpage *
  page145_i56
#ISCELL
  mstr_standard offpage *
  page145_i57
#ISCELL
  mstr_standard offpage *
  page145_i58
#ISCELL
  mstr_standard offpage *
  page145_i59
#ISCELL
  mstr_standard offpage *
  page145_i6
#ISCELL
  mstr_standard offpage *
  page145_i68
#ISCELL
  mstr_standard offpage *
  page145_i69
#ISCELL
  mstr_standard offpage *
  page145_i7
#ISCELL
  mstr_standard offpage *
  page145_i70
#ISCELL
  mstr_standard offpage *
  page145_i71
#ISCELL
  mstr_standard offpage *
  page145_i72
#ISCELL
  mstr_standard offpage *
  page145_i73
#ISCELL
  mstr_standard offpage *
  page145_i74
#ISCELL
  mstr_standard offpage *
  page145_i75
#ISCELL
  mstr_standard offpage *
  page145_i76
#ISCELL
  mstr_standard offpage *
  page145_i78
#ISCELL
  mstr_standard offpage *
  page145_i79
#CELL
  mstr_discrete osc_c *
  page145_i8
#ISCELL
  mstr_standard offpage *
  page145_i80
#ISCELL
  mstr_standard offpage *
  page145_i81
#ISCELL
  mstr_standard offpage *
  page145_i82
#ISCELL
  mstr_standard offpage *
  page145_i83
#ISCELL
  mstr_standard offpage *
  page145_i84
#ISCELL
  mstr_standard offpage *
  page145_i85
#ISCELL
  mstr_standard offpage *
  page145_i86
#ISCELL
  mstr_standard offpage *
  page145_i87
#ISCELL
  mstr_standard offpage *
  page145_i88
#ISCELL
  mstr_standard offpage *
  page145_i89
#ISCELL
  mstr_standard offpage *
  page145_i9
#ISCELL
  mstr_standard offpage *
  page145_i90
#ISCELL
  mstr_standard offpage *
  page145_i91
#ISCELL
  mstr_standard offpage *
  page145_i92
#ISCELL
  mstr_standard offpage *
  page145_i93
#ISCELL
  mstr_standard offpage *
  page145_i94
#ISCELL
  mstr_standard offpage *
  page145_i95
#ISCELL
  mstr_standard offpage *
  page145_i96
#ISCELL
  mstr_standard offpage *
  page145_i97
#ISCELL
  mstr_standard offpage *
  page145_i98
#ISCELL
  mstr_standard offpage *
  page145_i99
#ISCELL
  mstr_symbols cad_note *
  *
#ISCELL
  mstr_symbols intel_corp_bpage *
  *
#ISCELL
  mstr_standard offpage *
  page146_i100
#ISCELL
  mstr_standard offpage *
  page146_i102
#ISCELL
  mstr_standard offpage *
  page146_i103
#CELL
  w_hdl ast2520a1-gp-gp *
  page146_i104
#CELL
  w_hdl ast2520a1-gp-gp *
  page146_i105
#ISCELL
  mstr_standard offpage *
  page146_i106
#ISCELL
  mstr_standard offpage *
  page146_i17
#ISCELL
  mstr_standard offpage *
  page146_i18
#ISCELL
  mstr_standard offpage *
  page146_i19
#ISCELL
  mstr_standard offpage *
  page146_i21
#ISCELL
  mstr_standard offpage *
  page146_i23
#ISCELL
  mstr_standard offpage *
  page146_i24
#ISCELL
  mstr_standard offpage *
  page146_i25
#CELL
  mstr_discrete res *
  page146_i26
#CELL
  mstr_discrete res *
  page146_i27
#ISCELL
  mstr_standard offpage *
  page146_i28
#ISCELL
  mstr_standard offpage *
  page146_i29
#ISCELL
  mstr_standard offpage *
  page146_i30
#ISCELL
  mstr_standard offpage *
  page146_i31
#ISCELL
  mstr_standard offpage *
  page146_i32
#ISCELL
  mstr_standard offpage *
  page146_i33
#CELL
  mstr_discrete res *
  page146_i35
#ISCELL
  mstr_symbols gnd *
  page146_i36
#CELL
  mstr_discrete res *
  page146_i37
#ISCELL
  mstr_standard offpage *
  page146_i38
#ISCELL
  mstr_standard offpage *
  page146_i39
#ISCELL
  mstr_standard offpage *
  page146_i4
#ISCELL
  mstr_standard offpage *
  page146_i40
#ISCELL
  mstr_standard offpage *
  page146_i41
#ISCELL
  mstr_standard offpage *
  page146_i42
#ISCELL
  mstr_standard offpage *
  page146_i43
#ISCELL
  mstr_standard offpage *
  page146_i44
#ISCELL
  mstr_standard offpage *
  page146_i45
#ISCELL
  mstr_standard offpage *
  page146_i46
#ISCELL
  mstr_standard offpage *
  page146_i47
#ISCELL
  mstr_standard offpage *
  page146_i48
#ISCELL
  mstr_standard offpage *
  page146_i49
#ISCELL
  mstr_standard offpage *
  page146_i5
#CELL
  mstr_discrete res *
  page146_i51
#ISCELL
  mstr_symbols p3v3_stby *
  page146_i52
#ISCELL
  mstr_standard offpage *
  page146_i54
#ISCELL
  mstr_standard offpage *
  page146_i55
#ISCELL
  mstr_standard offpage *
  page146_i56
#ISCELL
  mstr_standard offpage *
  page146_i57
#ISCELL
  mstr_standard offpage *
  page146_i59
#ISCELL
  mstr_standard offpage *
  page146_i60
#ISCELL
  mstr_standard offpage *
  page146_i61
#ISCELL
  mstr_standard offpage *
  page146_i62
#ISCELL
  mstr_standard offpage *
  page146_i63
#CELL
  mstr_discrete res *
  page146_i64
#CELL
  mstr_discrete res *
  page146_i65
#ISCELL
  mstr_symbols gnd *
  page146_i66
#CELL
  mstr_discrete res *
  page146_i67
#CELL
  mstr_discrete res *
  page146_i68
#CELL
  mstr_discrete res *
  page146_i69
#CELL
  mstr_discrete res *
  page146_i70
#CELL
  mstr_discrete res *
  page146_i71
#CELL
  mstr_discrete res *
  page146_i72
#CELL
  mstr_discrete res *
  page146_i73
#CELL
  mstr_discrete res *
  page146_i74
#CELL
  mstr_discrete res *
  page146_i75
#CELL
  mstr_discrete res *
  page146_i76
#ISCELL
  mstr_symbols gnd *
  page146_i77
#CELL
  mstr_discrete res *
  page146_i78
#ISCELL
  mstr_symbols gnd *
  page146_i79
#ISCELL
  mstr_standard offpage *
  page146_i80
#ISCELL
  mstr_standard offpage *
  page146_i81
#ISCELL
  mstr_standard offpage *
  page146_i82
#ISCELL
  mstr_standard offpage *
  page146_i83
#CELL
  mstr_discrete res *
  page146_i84
#CELL
  mstr_discrete res *
  page146_i85
#ISCELL
  mstr_standard offpage *
  page146_i86
#ISCELL
  mstr_standard offpage *
  page146_i87
#ISCELL
  mstr_standard offpage *
  page146_i88
#ISCELL
  mstr_standard offpage *
  page146_i89
#ISCELL
  mstr_standard tap *
  page146_i90
#ISCELL
  mstr_standard tap *
  page146_i91
#ISCELL
  mstr_standard tap *
  page146_i92
#ISCELL
  mstr_standard tap *
  page146_i93
#ISCELL
  mstr_standard offpage *
  page146_i94
#ISCELL
  mstr_standard offpage *
  page146_i95
#CELL
  mstr_discrete res *
  page146_i96
#ISCELL
  mstr_standard offpage *
  page146_i97
#ISCELL
  mstr_standard offpage *
  page146_i98
#ISCELL
  mstr_standard offpage *
  page146_i99
#ISCELL
  mstr_misc dns *
  *
#ISCELL
  mstr_symbols cad_note *
  *
#ISCELL
  mstr_symbols intel_corp_bpage *
  *
#ISCELL
  mstr_standard offpage *
  page147_i10
#ISCELL
  mstr_standard offpage *
  page147_i100
#ISCELL
  mstr_standard offpage *
  page147_i102
#ISCELL
  mstr_standard offpage *
  page147_i103
#ISCELL
  mstr_standard offpage *
  page147_i104
#ISCELL
  mstr_standard offpage *
  page147_i105
#CELL
  w_hdl ast2520a1-gp-gp *
  page147_i106
#ISCELL
  mstr_standard offpage *
  page147_i11
#ISCELL
  mstr_standard offpage *
  page147_i12
#ISCELL
  mstr_standard offpage *
  page147_i13
#ISCELL
  mstr_standard offpage *
  page147_i14
#ISCELL
  mstr_standard offpage *
  page147_i15
#ISCELL
  mstr_standard offpage *
  page147_i16
#ISCELL
  mstr_standard offpage *
  page147_i17
#ISCELL
  mstr_standard offpage *
  page147_i18
#ISCELL
  mstr_standard offpage *
  page147_i19
#ISCELL
  mstr_standard offpage *
  page147_i2
#ISCELL
  w_power w_vcc_circle *
  page147_i20
#CELL
  mstr_discrete res *
  page147_i21
#CELL
  mstr_discrete res *
  page147_i22
#CELL
  mstr_discrete res *
  page147_i23
#CELL
  mstr_discrete res *
  page147_i24
#CELL
  mstr_discrete res *
  page147_i25
#ISCELL
  mstr_standard offpage *
  page147_i26
#ISCELL
  mstr_standard offpage *
  page147_i27
#ISCELL
  mstr_standard offpage *
  page147_i28
#ISCELL
  mstr_standard offpage *
  page147_i29
#CELL
  mstr_discrete res *
  page147_i3
#ISCELL
  mstr_standard offpage *
  page147_i30
#ISCELL
  mstr_standard offpage *
  page147_i31
#ISCELL
  mstr_standard offpage *
  page147_i32
#ISCELL
  mstr_standard offpage *
  page147_i33
#ISCELL
  mstr_standard offpage *
  page147_i34
#ISCELL
  mstr_standard offpage *
  page147_i35
#CELL
  mstr_discrete cap *
  page147_i36
#ISCELL
  mstr_symbols gnd *
  page147_i37
#CELL
  mstr_discrete cap *
  page147_i38
#CELL
  mstr_discrete cap *
  page147_i39
#CELL
  mstr_discrete res *
  page147_i4
#CELL
  mstr_discrete res *
  page147_i40
#ISCELL
  mstr_symbols gnd *
  page147_i41
#CELL
  mstr_discrete res *
  page147_i42
#CELL
  mstr_discrete res *
  page147_i43
#ISCELL
  mstr_symbols p3v3_stby *
  page147_i44
#ISCELL
  mstr_standard offpage *
  page147_i45
#ISCELL
  mstr_symbols gnd *
  page147_i46
#ISCELL
  mstr_standard offpage *
  page147_i47
#ISCELL
  mstr_standard offpage *
  page147_i48
#ISCELL
  mstr_standard offpage *
  page147_i49
#ISCELL
  mstr_symbols p3v3_stby *
  page147_i5
#ISCELL
  mstr_standard offpage *
  page147_i50
#ISCELL
  mstr_standard offpage *
  page147_i51
#ISCELL
  mstr_standard offpage *
  page147_i52
#ISCELL
  mstr_standard offpage *
  page147_i53
#ISCELL
  mstr_standard offpage *
  page147_i54
#ISCELL
  mstr_standard offpage *
  page147_i55
#ISCELL
  mstr_standard offpage *
  page147_i56
#ISCELL
  mstr_standard offpage *
  page147_i57
#ISCELL
  mstr_standard offpage *
  page147_i58
#ISCELL
  mstr_standard offpage *
  page147_i59
#ISCELL
  mstr_standard offpage *
  page147_i6
#ISCELL
  mstr_standard offpage *
  page147_i60
#CELL
  mstr_discrete res *
  page147_i61
#CELL
  mstr_discrete res *
  page147_i62
#ISCELL
  mstr_symbols gnd *
  page147_i63
#ISCELL
  mstr_symbols gnd *
  page147_i64
#CELL
  mstr_discrete res *
  page147_i65
#CELL
  mstr_discrete res *
  page147_i66
#ISCELL
  mstr_symbols gnd *
  page147_i67
#ISCELL
  mstr_symbols gnd *
  page147_i68
#ISCELL
  mstr_standard offpage *
  page147_i7
#ISCELL
  mstr_standard offpage *
  page147_i72
#ISCELL
  mstr_standard offpage *
  page147_i73
#CELL
  mstr_discrete res *
  page147_i75
#ISCELL
  mstr_symbols gnd *
  page147_i76
#ISCELL
  mstr_standard offpage *
  page147_i77
#ISCELL
  mstr_standard offpage *
  page147_i79
#CELL
  mstr_discrete res *
  page147_i8
#ISCELL
  mstr_standard offpage *
  page147_i81
#ISCELL
  mstr_standard offpage *
  page147_i84
#ISCELL
  mstr_standard offpage *
  page147_i85
#ISCELL
  mstr_standard offpage *
  page147_i86
#ISCELL
  mstr_standard offpage *
  page147_i87
#ISCELL
  mstr_standard offpage *
  page147_i88
#ISCELL
  mstr_standard offpage *
  page147_i89
#ISCELL
  mstr_standard offpage *
  page147_i9
#ISCELL
  mstr_standard offpage *
  page147_i91
#ISCELL
  mstr_standard offpage *
  page147_i92
#ISCELL
  mstr_standard offpage *
  page147_i93
#ISCELL
  mstr_standard offpage *
  page147_i94
#ISCELL
  mstr_standard offpage *
  page147_i95
#ISCELL
  mstr_standard offpage *
  page147_i96
#ISCELL
  mstr_standard offpage *
  page147_i99
#ISCELL
  mstr_symbols intel_corp_bpage *
  *
#ISCELL
  w_power w_vcc_circle *
  page148_i10
#ISCELL
  mstr_standard offpage *
  page148_i12
#ISCELL
  mstr_standard offpage *
  page148_i13
#ISCELL
  w_power w_vcc_circle *
  page148_i14
#ISCELL
  w_power w_vcc_circle *
  page148_i15
#CELL
  mstr_discrete res *
  page148_i16
#ISCELL
  w_power w_vcc_circle *
  page148_i17
#ISCELL
  mstr_symbols p3v3_stby *
  page148_i18
#ISCELL
  w_power w_vcc_circle *
  page148_i19
#ISCELL
  mstr_symbols p3v3_stby *
  page148_i2
#CELL
  dev_discrete cap_a *
  page148_i20
#ISCELL
  mstr_symbols pvccio_cpu0 *
  page148_i21
#ISCELL
  mstr_symbols gnd *
  page148_i22
#CELL
  mstr_discrete res *
  page148_i23
#ISCELL
  mstr_standard offpage *
  page148_i25
#ISCELL
  w_power w_vcc_circle *
  page148_i26
#ISCELL
  w_power w_vcc_circle *
  page148_i27
#CELL
  w_hdl ast2520a1-gp-gp *
  page148_i28
#ISCELL
  mstr_symbols gnd *
  page148_i3
#ISCELL
  mstr_symbols p3v3_stby *
  page148_i4
#ISCELL
  w_power w_vcc_circle *
  page148_i6
#ISCELL
  w_power w_vcc_circle *
  page148_i7
#ISCELL
  w_power w_vcc_circle *
  page148_i8
#ISCELL
  w_power w_vcc_circle *
  page148_i9
#ISCELL
  mstr_misc dns *
  *
#ISCELL
  mstr_symbols cad_note *
  *
#ISCELL
  mstr_symbols intel_corp_bpage *
  *
#CELL
  w_hdl h5an4g6nafr-tfc-gp *
  page149_i1
#ISCELL
  mstr_standard offpage *
  page149_i10
#ISCELL
  mstr_symbols p3v3_stby *
  page149_i108
#CELL
  mstr_discrete fet_n_dual *
  page149_i109
#ISCELL
  mstr_standard offpage *
  page149_i11
#ISCELL
  mstr_symbols gnd *
  page149_i110
#CELL
  mstr_discrete res *
  page149_i111
#ISCELL
  mstr_symbols gnd *
  page149_i112
#CELL
  mstr_discrete fet_n_dual *
  page149_i113
#ISCELL
  mstr_standard offpage *
  page149_i114
#ISCELL
  mstr_standard offpage *
  page149_i115
#ISCELL
  mstr_standard offpage *
  page149_i116
#ISCELL
  mstr_standard offpage *
  page149_i117
#ISCELL
  w_power w_vcc_circle *
  page149_i119
#ISCELL
  mstr_standard offpage *
  page149_i12
#CELL
  mstr_discrete res *
  page149_i120
#ISCELL
  mstr_symbols gnd *
  page149_i121
#CELL
  mstr_discrete res *
  page149_i122
#ISCELL
  w_power w_vcc_circle *
  page149_i123
#CELL
  mstr_discrete res *
  page149_i124
#CELL
  mstr_discrete res *
  page149_i125
#CELL
  mstr_discrete cap *
  page149_i126
#ISCELL
  mstr_symbols gnd *
  page149_i127
#ISCELL
  mstr_standard offpage *
  page149_i13
#CELL
  mstr_discrete res *
  page149_i14
#ISCELL
  w_power w_vcc_circle *
  page149_i15
#ISCELL
  mstr_symbols gnd *
  page149_i154
#ISCELL
  mstr_symbols p3v3_stby *
  page149_i155
#CELL
  mstr_discrete res *
  page149_i156
#ISCELL
  mstr_standard offpage *
  page149_i157
#CELL
  mstr_discrete cap *
  page149_i158
#CELL
  mstr_discrete cap *
  page149_i159
#CELL
  mstr_discrete res *
  page149_i16
#CELL
  w_hdl 120r2f-gp *
  page149_i160
#CELL
  w_hdl 120r2f-gp *
  page149_i161
#CELL
  w_hdl 120r2f-gp *
  page149_i162
#CELL
  w_hdl 120r2f-gp *
  page149_i163
#CELL
  w_hdl 120r2f-gp *
  page149_i164
#CELL
  w_hdl 120r2f-gp *
  page149_i165
#CELL
  w_hdl 120r2f-gp *
  page149_i166
#CELL
  w_hdl 120r2f-gp *
  page149_i167
#CELL
  w_hdl 120r2f-gp *
  page149_i168
#CELL
  w_hdl 120r2f-gp *
  page149_i169
#ISCELL
  mstr_standard offpage *
  page149_i17
#CELL
  w_hdl 120r2f-gp *
  page149_i170
#CELL
  w_hdl 120r2f-gp *
  page149_i171
#CELL
  w_hdl 120r2f-gp *
  page149_i172
#CELL
  w_hdl 120r2f-gp *
  page149_i173
#CELL
  w_hdl 120r2f-gp *
  page149_i174
#CELL
  w_hdl 120r2f-gp *
  page149_i175
#CELL
  w_hdl 120r2f-gp *
  page149_i176
#CELL
  w_hdl 120r2f-gp *
  page149_i177
#CELL
  w_hdl 120r2f-gp *
  page149_i178
#CELL
  w_hdl 120r2f-gp *
  page149_i179
#ISCELL
  mstr_standard offpage *
  page149_i18
#CELL
  w_hdl 120r2f-gp *
  page149_i180
#CELL
  w_hdl 120r2f-gp *
  page149_i181
#CELL
  w_hdl 120r2f-gp *
  page149_i182
#CELL
  w_hdl 120r2f-gp *
  page149_i183
#CELL
  w_hdl 120r2f-gp *
  page149_i184
#CELL
  w_hdl 120r2f-gp *
  page149_i185
#CELL
  w_hdl 120r2f-gp *
  page149_i186
#CELL
  w_hdl 120r2f-gp *
  page149_i187
#CELL
  w_hdl 120r2f-gp *
  page149_i188
#CELL
  w_hdl 120r2f-gp *
  page149_i189
#ISCELL
  mstr_standard offpage *
  page149_i19
#CELL
  w_hdl 120r2f-gp *
  page149_i190
#CELL
  w_hdl 120r2f-gp *
  page149_i191
#CELL
  w_hdl 120r2f-gp *
  page149_i192
#CELL
  w_hdl 120r2f-gp *
  page149_i193
#CELL
  w_hdl 120r2f-gp *
  page149_i194
#CELL
  w_hdl 120r2f-gp *
  page149_i195
#CELL
  w_hdl 120r2f-gp *
  page149_i196
#CELL
  w_hdl 120r2f-gp *
  page149_i197
#CELL
  w_hdl 120r2f-gp *
  page149_i198
#CELL
  w_hdl 120r2f-gp *
  page149_i199
#ISCELL
  mstr_standard offpage *
  page149_i2
#ISCELL
  mstr_standard offpage *
  page149_i20
#CELL
  w_hdl 120r2f-gp *
  page149_i200
#CELL
  w_hdl 120r2f-gp *
  page149_i201
#CELL
  w_hdl 120r2f-gp *
  page149_i202
#CELL
  w_hdl 120r2f-gp *
  page149_i203
#CELL
  w_hdl 120r2f-gp *
  page149_i204
#CELL
  w_hdl 120r2f-gp *
  page149_i205
#CELL
  w_hdl 120r2f-gp *
  page149_i206
#CELL
  w_hdl 120r2f-gp *
  page149_i207
#CELL
  w_hdl 120r2f-gp *
  page149_i208
#CELL
  w_hdl 120r2f-gp *
  page149_i209
#ISCELL
  mstr_standard offpage *
  page149_i21
#CELL
  w_hdl 120r2f-gp *
  page149_i210
#CELL
  w_hdl 120r2f-gp *
  page149_i211
#CELL
  w_hdl 120r2f-gp *
  page149_i212
#ISCELL
  mstr_standard offpage *
  page149_i22
#ISCELL
  mstr_standard offpage *
  page149_i23
#ISCELL
  mstr_standard offpage *
  page149_i24
#ISCELL
  mstr_standard offpage *
  page149_i25
#ISCELL
  mstr_standard offpage *
  page149_i26
#ISCELL
  mstr_standard offpage *
  page149_i27
#ISCELL
  mstr_standard offpage *
  page149_i28
#ISCELL
  mstr_standard offpage *
  page149_i29
#ISCELL
  mstr_standard offpage *
  page149_i3
#ISCELL
  mstr_standard offpage *
  page149_i30
#ISCELL
  mstr_standard offpage *
  page149_i31
#ISCELL
  mstr_standard offpage *
  page149_i32
#ISCELL
  mstr_symbols gnd *
  page149_i33
#CELL
  mstr_ttl ttl1g07_a *
  page149_i34
#ISCELL
  w_power w_vcc_circle *
  page149_i35
#ISCELL
  mstr_standard offpage *
  page149_i36
#CELL
  mstr_discrete cap *
  page149_i37
#CELL
  w_hdl sc1u16v3kx-2gp *
  page149_i38
#CELL
  w_hdl scd1u16v2kx-3gp *
  page149_i39
#ISCELL
  mstr_standard offpage *
  page149_i4
#ISCELL
  w_power w_vcc_circle *
  page149_i40
#ISCELL
  mstr_standard offpage *
  page149_i41
#ISCELL
  mstr_standard offpage *
  page149_i42
#ISCELL
  mstr_standard offpage *
  page149_i43
#CELL
  w_hdl scd1u16v2kx-3gp *
  page149_i44
#ISCELL
  mstr_symbols gnd *
  page149_i45
#ISCELL
  mstr_standard offpage *
  page149_i46
#ISCELL
  mstr_standard offpage *
  page149_i47
#ISCELL
  mstr_standard offpage *
  page149_i48
#ISCELL
  mstr_standard offpage *
  page149_i49
#ISCELL
  mstr_standard offpage *
  page149_i5
#ISCELL
  mstr_standard offpage *
  page149_i50
#ISCELL
  mstr_standard offpage *
  page149_i51
#ISCELL
  mstr_standard offpage *
  page149_i52
#ISCELL
  mstr_standard offpage *
  page149_i53
#ISCELL
  mstr_standard offpage *
  page149_i54
#CELL
  mstr_discrete res *
  page149_i55
#ISCELL
  mstr_symbols gnd *
  page149_i56
#ISCELL
  mstr_standard offpage *
  page149_i57
#ISCELL
  mstr_standard offpage *
  page149_i58
#ISCELL
  mstr_standard offpage *
  page149_i59
#ISCELL
  mstr_standard offpage *
  page149_i6
#ISCELL
  mstr_standard offpage *
  page149_i60
#ISCELL
  mstr_standard offpage *
  page149_i61
#ISCELL
  mstr_standard offpage *
  page149_i62
#ISCELL
  mstr_standard offpage *
  page149_i63
#ISCELL
  mstr_standard offpage *
  page149_i64
#CELL
  mstr_discrete cap *
  page149_i65
#ISCELL
  mstr_symbols gnd *
  page149_i66
#ISCELL
  w_power w_vcc_circle *
  page149_i67
#CELL
  w_hdl sc1u16v3kx-2gp *
  page149_i68
#CELL
  w_hdl sc4d7u10v3kx-gp *
  page149_i69
#ISCELL
  mstr_standard offpage *
  page149_i7
#ISCELL
  mstr_symbols gnd *
  page149_i70
#CELL
  mstr_discrete cap *
  page149_i71
#CELL
  mstr_discrete cap *
  page149_i72
#CELL
  mstr_discrete cap *
  page149_i73
#CELL
  mstr_discrete cap *
  page149_i74
#ISCELL
  w_power w_vcc_circle *
  page149_i75
#ISCELL
  mstr_standard offpage *
  page149_i8
#ISCELL
  mstr_standard offpage *
  page149_i9
#ISCELL
  mstr_symbols p3v3_stby *
  page149_i93
#CELL
  mstr_discrete res *
  page149_i94
#ISCELL
  mstr_symbols gnd *
  page149_i95
#CELL
  mstr_discrete cap *
  page149_i96
#CELL
  mstr_discrete cap *
  page149_i97
#CELL
  mstr_discrete led *
  page149_i98
#ISCELL
  mstr_symbols intel_corp_bpage *
  *
#CELL
  mstr_discrete cap *
  page150_i1
#CELL
  w_hdl scd1u16v2kx-3gp *
  page150_i10
#ISCELL
  mstr_symbols gnd *
  page150_i11
#CELL
  mstr_discrete cap *
  page150_i12
#CELL
  mstr_discrete cap *
  page150_i13
#CELL
  mstr_discrete cap *
  page150_i14
#ISCELL
  w_power w_vcc_circle *
  page150_i15
#ISCELL
  mstr_symbols gnd *
  page150_i16
#CELL
  w_hdl sc4d7u10v3kx-gp *
  page150_i17
#CELL
  w_hdl scd1u16v2kx-3gp *
  page150_i18
#CELL
  mstr_discrete cap *
  page150_i19
#CELL
  w_hdl sc4d7u10v3kx-gp *
  page150_i2
#ISCELL
  w_power w_vcc_circle *
  page150_i20
#CELL
  w_hdl sc4d7u10v3kx-gp *
  page150_i21
#ISCELL
  mstr_symbols gnd *
  page150_i22
#ISCELL
  mstr_symbols gnd *
  page150_i23
#CELL
  w_hdl scd1u16v2kx-3gp *
  page150_i24
#CELL
  mstr_discrete cap *
  page150_i25
#CELL
  w_hdl hcb1608kf-800t30-gp *
  page150_i26
#ISCELL
  w_power w_vcc_circle *
  page150_i27
#CELL
  w_hdl sc4d7u10v3kx-gp *
  page150_i28
#ISCELL
  mstr_symbols gnd *
  page150_i29
#ISCELL
  w_power w_vcc_circle *
  page150_i3
#CELL
  w_hdl scd1u16v2kx-3gp *
  page150_i30
#CELL
  mstr_discrete cap *
  page150_i31
#CELL
  w_hdl hcb1608kf-800t30-gp *
  page150_i32
#CELL
  mstr_discrete cap *
  page150_i33
#ISCELL
  w_power w_vcc_circle *
  page150_i34
#CELL
  mstr_discrete cap *
  page150_i35
#CELL
  w_hdl scd1u16v2kx-3gp *
  page150_i36
#ISCELL
  mstr_symbols p3v3_stby *
  page150_i37
#CELL
  mstr_discrete cap *
  page150_i38
#CELL
  w_hdl hcb1608kf-800t30-gp *
  page150_i39
#CELL
  mstr_discrete cap *
  page150_i4
#ISCELL
  mstr_symbols p3v3_stby *
  page150_i40
#ISCELL
  mstr_symbols p3v3_stby *
  page150_i41
#ISCELL
  w_power w_vcc_circle *
  page150_i42
#CELL
  w_hdl sc4d7u10v3kx-gp *
  page150_i43
#ISCELL
  mstr_symbols gnd *
  page150_i44
#CELL
  mstr_discrete cap *
  page150_i45
#CELL
  mstr_discrete cap *
  page150_i46
#ISCELL
  mstr_symbols p3v3_stby *
  page150_i47
#CELL
  mstr_discrete cap *
  page150_i48
#ISCELL
  w_power w_vcc_circle *
  page150_i49
#ISCELL
  mstr_symbols gnd *
  page150_i5
#CELL
  w_hdl sc4d7u10v3kx-gp *
  page150_i50
#CELL
  mstr_discrete cap *
  page150_i51
#ISCELL
  mstr_symbols gnd *
  page150_i52
#CELL
  w_hdl scd1u16v2kx-3gp *
  page150_i53
#CELL
  w_hdl sc4d7u10v3kx-gp *
  page150_i54
#CELL
  mstr_discrete cap *
  page150_i55
#ISCELL
  mstr_symbols gnd *
  page150_i56
#CELL
  w_hdl 0r3j-0-u-gp *
  page150_i57
#ISCELL
  w_power w_vcc_circle *
  page150_i58
#CELL
  mstr_discrete cap *
  page150_i59
#CELL
  w_hdl sc4d7u10v3kx-gp *
  page150_i6
#ISCELL
  mstr_symbols gnd *
  page150_i60
#CELL
  w_hdl scd1u16v2kx-3gp *
  page150_i61
#CELL
  mstr_discrete cap *
  page150_i62
#CELL
  mstr_discrete cap *
  page150_i63
#ISCELL
  w_power w_vcc_circle *
  page150_i64
#CELL
  w_hdl sc4d7u10v3kx-gp *
  page150_i65
#ISCELL
  mstr_symbols gnd *
  page150_i66
#CELL
  w_hdl scd1u16v2kx-3gp *
  page150_i67
#ISCELL
  mstr_symbols p3v3_stby *
  page150_i68
#CELL
  w_hdl sc4d7u10v3kx-gp *
  page150_i69
#CELL
  w_hdl 0r3j-0-u-gp *
  page150_i7
#ISCELL
  mstr_symbols gnd *
  page150_i70
#CELL
  mstr_discrete cap *
  page150_i71
#CELL
  mstr_discrete cap *
  page150_i72
#CELL
  mstr_discrete cap *
  page150_i73
#ISCELL
  w_power w_vcc_circle *
  page150_i74
#CELL
  mstr_discrete cap *
  page150_i75
#CELL
  w_hdl hcb1608kf-800t30-gp *
  page150_i76
#ISCELL
  mstr_symbols p3v3_stby *
  page150_i77
#CELL
  mstr_discrete cap *
  page150_i78
#CELL
  w_hdl scd1u16v2kx-3gp *
  page150_i79
#ISCELL
  mstr_symbols p3v3_stby *
  page150_i8
#CELL
  mstr_discrete cap *
  page150_i80
#CELL
  mstr_discrete cap *
  page150_i81
#CELL
  mstr_discrete cap *
  page150_i82
#ISCELL
  mstr_symbols p3v3_stby *
  page150_i83
#CELL
  w_hdl hcb1608kf-800t30-gp *
  page150_i84
#CELL
  w_hdl scd1u16v2kx-3gp *
  page150_i85
#CELL
  mstr_discrete cap *
  page150_i86
#CELL
  mstr_discrete cap *
  page150_i87
#ISCELL
  mstr_symbols p3v3_stby *
  page150_i88
#CELL
  w_hdl hcb1608kf-800t30-gp *
  page150_i89
#ISCELL
  w_power w_vcc_circle *
  page150_i9
#ISCELL
  mstr_misc dns *
  *
#ISCELL
  mstr_symbols intel_corp_bpage *
  *
#ISCELL
  mstr_symbols gnd *
  page151_i1
#CELL
  mstr_discrete res *
  page151_i10
#CELL
  mstr_discrete res *
  page151_i11
#CELL
  mstr_discrete res *
  page151_i12
#CELL
  mstr_discrete res *
  page151_i13
#CELL
  mstr_discrete res *
  page151_i14
#ISCELL
  mstr_symbols p3v3_stby *
  page151_i15
#ISCELL
  mstr_standard offpage *
  page151_i16
#ISCELL
  mstr_standard offpage *
  page151_i17
#ISCELL
  mstr_standard offpage *
  page151_i18
#ISCELL
  mstr_standard offpage *
  page151_i19
#CELL
  mstr_discrete res *
  page151_i2
#ISCELL
  mstr_standard offpage *
  page151_i20
#ISCELL
  mstr_standard offpage *
  page151_i21
#ISCELL
  mstr_standard offpage *
  page151_i22
#ISCELL
  mstr_standard offpage *
  page151_i23
#ISCELL
  mstr_standard offpage *
  page151_i24
#ISCELL
  mstr_standard offpage *
  page151_i25
#ISCELL
  mstr_standard offpage *
  page151_i26
#CELL
  mstr_discrete res *
  page151_i27
#CELL
  mstr_discrete res *
  page151_i28
#CELL
  mstr_discrete res *
  page151_i29
#ISCELL
  mstr_standard offpage *
  page151_i3
#CELL
  mstr_discrete res *
  page151_i30
#CELL
  mstr_discrete res *
  page151_i31
#CELL
  mstr_discrete res *
  page151_i32
#CELL
  mstr_discrete res *
  page151_i33
#CELL
  mstr_discrete res *
  page151_i34
#CELL
  mstr_discrete res *
  page151_i35
#CELL
  mstr_discrete res *
  page151_i36
#ISCELL
  mstr_standard offpage *
  page151_i37
#ISCELL
  mstr_standard offpage *
  page151_i38
#ISCELL
  mstr_standard offpage *
  page151_i39
#ISCELL
  mstr_standard offpage *
  page151_i4
#ISCELL
  mstr_standard offpage *
  page151_i40
#ISCELL
  mstr_standard offpage *
  page151_i41
#ISCELL
  mstr_standard offpage *
  page151_i42
#CELL
  mstr_discrete res *
  page151_i43
#CELL
  mstr_discrete res *
  page151_i44
#CELL
  mstr_discrete res *
  page151_i45
#CELL
  mstr_discrete res *
  page151_i46
#CELL
  mstr_discrete res *
  page151_i47
#CELL
  mstr_discrete res *
  page151_i48
#ISCELL
  mstr_standard offpage *
  page151_i5
#ISCELL
  mstr_standard offpage *
  page151_i6
#ISCELL
  mstr_standard offpage *
  page151_i7
#ISCELL
  mstr_standard offpage *
  page151_i8
#CELL
  mstr_discrete res *
  page151_i9
#ISCELL
  mstr_misc dns *
  *
#ISCELL
  mstr_symbols cad_note *
  *
#ISCELL
  mstr_symbols design_note *
  *
#ISCELL
  mstr_symbols intel_corp_bpage *
  *
#CELL
  mstr_digital gtl2014 *
  page152_i1
#ISCELL
  mstr_standard offpage *
  page152_i10
#CELL
  mstr_discrete res *
  page152_i100
#ISCELL
  mstr_standard offpage *
  page152_i101
#CELL
  mstr_discrete res *
  page152_i102
#ISCELL
  mstr_standard offpage *
  page152_i11
#ISCELL
  mstr_standard offpage *
  page152_i12
#ISCELL
  mstr_standard offpage *
  page152_i13
#CELL
  mstr_discrete res *
  page152_i14
#CELL
  mstr_discrete res *
  page152_i15
#CELL
  mstr_discrete res *
  page152_i16
#ISCELL
  mstr_symbols gnd *
  page152_i17
#CELL
  mstr_discrete cap *
  page152_i18
#CELL
  mstr_discrete res *
  page152_i2
#ISCELL
  mstr_symbols gnd *
  page152_i20
#ISCELL
  mstr_standard offpage *
  page152_i21
#ISCELL
  mstr_standard offpage *
  page152_i22
#ISCELL
  mstr_standard offpage *
  page152_i23
#ISCELL
  mstr_standard offpage *
  page152_i24
#CELL
  mstr_discrete res *
  page152_i25
#CELL
  mstr_discrete res *
  page152_i26
#CELL
  dev_discrete cap_a *
  page152_i27
#ISCELL
  mstr_symbols pvccio_cpu0 *
  page152_i28
#ISCELL
  mstr_symbols gnd *
  page152_i29
#ISCELL
  mstr_symbols gnd *
  page152_i3
#ISCELL
  mstr_standard offpage *
  page152_i30
#ISCELL
  mstr_standard offpage *
  page152_i4
#CELL
  mstr_discrete res *
  page152_i45
#CELL
  mstr_discrete res *
  page152_i47
#CELL
  mstr_discrete res *
  page152_i49
#ISCELL
  mstr_symbols p3v3 *
  page152_i5
#CELL
  mstr_discrete res *
  page152_i50
#CELL
  mstr_discrete res *
  page152_i51
#ISCELL
  mstr_symbols pvccio_cpu0 *
  page152_i52
#CELL
  mstr_discrete res *
  page152_i53
#CELL
  mstr_discrete res *
  page152_i54
#ISCELL
  mstr_symbols pvccio_cpu1 *
  page152_i55
#CELL
  mstr_discrete res *
  page152_i56
#CELL
  mstr_discrete res *
  page152_i57
#CELL
  mstr_discrete res *
  page152_i58
#CELL
  mstr_discrete res *
  page152_i59
#CELL
  mstr_discrete res *
  page152_i6
#ISCELL
  mstr_symbols pvccio_cpu0 *
  page152_i60
#CELL
  mstr_discrete res *
  page152_i61
#CELL
  mstr_discrete res *
  page152_i62
#ISCELL
  mstr_symbols pvccio_cpu1 *
  page152_i63
#CELL
  mstr_discrete res *
  page152_i64
#CELL
  mstr_discrete res *
  page152_i65
#CELL
  mstr_discrete res *
  page152_i66
#CELL
  mstr_discrete res *
  page152_i67
#CELL
  mstr_discrete res *
  page152_i68
#CELL
  mstr_discrete res *
  page152_i69
#CELL
  mstr_discrete res *
  page152_i70
#CELL
  mstr_discrete res *
  page152_i71
#CELL
  mstr_discrete res *
  page152_i72
#CELL
  mstr_discrete res *
  page152_i73
#CELL
  mstr_discrete res *
  page152_i74
#ISCELL
  mstr_standard offpage *
  page152_i75
#ISCELL
  mstr_standard offpage *
  page152_i76
#ISCELL
  mstr_standard offpage *
  page152_i77
#ISCELL
  mstr_standard offpage *
  page152_i78
#CELL
  mstr_discrete res *
  page152_i79
#ISCELL
  mstr_standard offpage *
  page152_i85
#ISCELL
  mstr_standard offpage *
  page152_i87
#ISCELL
  mstr_standard offpage *
  page152_i89
#ISCELL
  mstr_standard offpage *
  page152_i91
#CELL
  mstr_discrete res *
  page152_i92
#CELL
  mstr_discrete res *
  page152_i93
#CELL
  mstr_discrete res *
  page152_i94
#CELL
  mstr_discrete res *
  page152_i95
#ISCELL
  mstr_standard offpage *
  page152_i96
#ISCELL
  mstr_standard offpage *
  page152_i97
#CELL
  mstr_discrete res *
  page152_i98
#ISCELL
  mstr_standard offpage *
  page152_i99
#ISCELL
  mstr_misc dns *
  *
#ISCELL
  mstr_symbols bom_note *
  *
#ISCELL
  mstr_symbols cad_note *
  *
#ISCELL
  mstr_symbols design_note *
  *
#ISCELL
  mstr_symbols intel_corp_bpage *
  *
#ISCELL
  mstr_standard offpage *
  page153_i101
#ISCELL
  mstr_standard offpage *
  page153_i102
#ISCELL
  mstr_standard offpage *
  page153_i103
#ISCELL
  mstr_standard offpage *
  page153_i105
#ISCELL
  mstr_standard offpage *
  page153_i107
#CELL
  mstr_discrete res *
  page153_i108
#CELL
  mstr_discrete res *
  page153_i109
#ISCELL
  mstr_standard offpage *
  page153_i110
#ISCELL
  mstr_standard offpage *
  page153_i111
#CELL
  dev_discrete cap_a *
  page153_i130
#CELL
  dev_discrete cap_a *
  page153_i131
#ISCELL
  mstr_symbols gnd *
  page153_i133
#CELL
  dev_discrete cap_a *
  page153_i136
#CELL
  dev_discrete cap_a *
  page153_i138
#ISCELL
  mstr_symbols gnd *
  page153_i139
#CELL
  mstr_discrete res *
  page153_i140
#ISCELL
  mstr_symbols p3v3_stby *
  page153_i141
#ISCELL
  mstr_standard offpage *
  page153_i144
#CELL
  mstr_memory w25q256 *
  page153_i146
#CELL
  mstr_discrete res *
  page153_i150
#ISCELL
  mstr_symbols p3v3_stby *
  page153_i151
#CELL
  mstr_discrete res *
  page153_i152
#ISCELL
  mstr_standard offpage *
  page153_i153
#ISCELL
  mstr_symbols gnd *
  page153_i154
#CELL
  mstr_discrete res *
  page153_i155
#CELL
  mstr_discrete res *
  page153_i156
#CELL
  mstr_discrete res *
  page153_i157
#ISCELL
  mstr_standard offpage *
  page153_i158
#ISCELL
  mstr_standard offpage *
  page153_i159
#ISCELL
  mstr_standard offpage *
  page153_i161
#ISCELL
  mstr_standard offpage *
  page153_i162
#ISCELL
  mstr_standard offpage *
  page153_i163
#ISCELL
  mstr_standard offpage *
  page153_i164
#CELL
  mstr_memory w25q256 *
  page153_i165
#CELL
  mstr_discrete res *
  page153_i166
#CELL
  mstr_discrete res *
  page153_i167
#CELL
  mstr_discrete res *
  page153_i168
#ISCELL
  mstr_symbols p3v3_stby *
  page153_i169
#CELL
  mstr_discrete res *
  page153_i170
#ISCELL
  mstr_standard offpage *
  page153_i171
#ISCELL
  mstr_symbols gnd *
  page153_i172
#ISCELL
  mstr_standard offpage *
  page153_i173
#CELL
  mstr_discrete res *
  page153_i174
#ISCELL
  mstr_symbols p3v3_stby *
  page153_i175
#ISCELL
  mstr_symbols p3v3_stby *
  page153_i176
#ISCELL
  mstr_standard offpage *
  page153_i177
#CELL
  mstr_discrete res *
  page153_i178
#CELL
  mstr_discrete res *
  page153_i179
#ISCELL
  mstr_symbols gnd *
  page153_i180
#CELL
  mstr_discrete res *
  page153_i181
#ISCELL
  mstr_standard offpage *
  page153_i182
#ISCELL
  mstr_standard offpage *
  page153_i183
#CELL
  mstr_discrete res *
  page153_i184
#CELL
  mstr_discrete res *
  page153_i90
#ISCELL
  mstr_symbols gnd *
  page153_i91
#CELL
  mstr_discrete res *
  page153_i94
#ISCELL
  mstr_symbols p3v3_stby *
  page153_i95
#CELL
  mstr_discrete res *
  page153_i98
#ISCELL
  mstr_symbols cad_note *
  *
#ISCELL
  mstr_symbols design_note *
  *
#ISCELL
  mstr_symbols intel_corp_bpage *
  *
#CELL
  mstr_ttl ttl1g32_a *
  page154_i100
#CELL
  mstr_discrete res *
  page154_i101
#ISCELL
  mstr_standard offpage *
  page154_i102
#ISCELL
  mstr_standard offpage *
  page154_i103
#CELL
  mstr_discrete res *
  page154_i105
#CELL
  mstr_discrete res *
  page154_i106
#ISCELL
  mstr_standard offpage *
  page154_i107
#ISCELL
  mstr_symbols gnd *
  page154_i109
#ISCELL
  mstr_symbols p3v3_stby *
  page154_i110
#ISCELL
  mstr_symbols p3v3_stby *
  page154_i111
#CELL
  mstr_discrete res *
  page154_i119
#ISCELL
  mstr_symbols p3v3_stby *
  page154_i12
#ISCELL
  mstr_standard offpage *
  page154_i123
#CELL
  mstr_discrete fet_n *
  page154_i126
#CELL
  mstr_discrete res *
  page154_i127
#CELL
  mstr_discrete res *
  page154_i128
#ISCELL
  mstr_symbols gnd *
  page154_i129
#ISCELL
  mstr_symbols gnd *
  page154_i13
#ISCELL
  mstr_standard offpage *
  page154_i130
#ISCELL
  mstr_symbols p3v3_stby *
  page154_i131
#CELL
  dev_discrete cap_a *
  page154_i132
#ISCELL
  mstr_symbols gnd *
  page154_i133
#ISCELL
  mstr_symbols p3v3_stby *
  page154_i134
#CELL
  dev_discrete cap_a *
  page154_i135
#ISCELL
  mstr_symbols gnd *
  page154_i136
#ISCELL
  mstr_symbols p3v3_stby *
  page154_i137
#ISCELL
  mstr_standard offpage *
  page154_i138
#CELL
  dev_discrete cap_a *
  page154_i14
#CELL
  mstr_discrete res *
  page154_i62
#ISCELL
  mstr_standard offpage *
  page154_i70
#ISCELL
  mstr_standard offpage *
  page154_i71
#ISCELL
  mstr_standard offpage *
  page154_i72
#ISCELL
  mstr_standard offpage *
  page154_i73
#CELL
  mstr_digital pi3b3257a *
  page154_i74
#CELL
  mstr_digital pi3b3257a *
  page154_i75
#ISCELL
  mstr_standard offpage *
  page154_i76
#ISCELL
  mstr_standard offpage *
  page154_i77
#ISCELL
  mstr_standard offpage *
  page154_i78
#ISCELL
  mstr_standard offpage *
  page154_i79
#ISCELL
  mstr_standard offpage *
  page154_i81
#ISCELL
  mstr_standard offpage *
  page154_i82
#ISCELL
  mstr_standard offpage *
  page154_i83
#ISCELL
  mstr_standard offpage *
  page154_i84
#ISCELL
  mstr_symbols gnd *
  page154_i85
#ISCELL
  mstr_symbols gnd *
  page154_i86
#ISCELL
  mstr_standard offpage *
  page154_i87
#ISCELL
  mstr_standard offpage *
  page154_i88
#ISCELL
  mstr_standard offpage *
  page154_i89
#ISCELL
  mstr_standard offpage *
  page154_i90
#ISCELL
  mstr_standard offpage *
  page154_i91
#CELL
  mstr_discrete res *
  page154_i92
#CELL
  mstr_discrete res *
  page154_i93
#CELL
  dev_discrete cap_a *
  page154_i94
#ISCELL
  mstr_symbols gnd *
  page154_i95
#ISCELL
  mstr_symbols p3v3_stby *
  page154_i96
#ISCELL
  mstr_symbols gnd *
  page154_i97
#ISCELL
  mstr_symbols gnd *
  page154_i98
#CELL
  mstr_ttl ttl1g32_a *
  page154_i99
#ISCELL
  mstr_misc dns *
  *
#ISCELL
  mstr_symbols cad_note *
  *
#ISCELL
  mstr_symbols intel_corp_bpage *
  *
#CELL
  dev_discrete cap_a *
  page155_i127
#ISCELL
  mstr_symbols gnd *
  page155_i128
#CELL
  mstr_discrete fuse *
  page155_i129
#CELL
  mstr_discrete res *
  page155_i130
#CELL
  mstr_conn conn14_h54902001 *
  page155_i171
#CELL
  mstr_ttl ttl1g07_a *
  page155_i178
#ISCELL
  mstr_symbols gnd *
  page155_i180
#ISCELL
  mstr_standard offpage *
  page155_i182
#ISCELL
  mstr_symbols p3v3_stby *
  page155_i183
#CELL
  dev_discrete cap_a *
  page155_i184
#ISCELL
  mstr_symbols gnd *
  page155_i185
#CELL
  mstr_discrete res *
  page155_i186
#CELL
  mstr_discrete fet_n_dual *
  page155_i187
#CELL
  mstr_discrete fet_n_dual *
  page155_i188
#CELL
  mstr_discrete res *
  page155_i191
#ISCELL
  mstr_symbols p5v_stby *
  page155_i192
#ISCELL
  mstr_symbols p12v_stby *
  page155_i193
#ISCELL
  mstr_symbols p5v_stby *
  page155_i194
#CELL
  mstr_discrete res *
  page155_i195
#CELL
  mstr_discrete res *
  page155_i196
#CELL
  mstr_conn conn3_c95678002 *
  page155_i198
#ISCELL
  mstr_symbols p5v_stby *
  page155_i199
#ISCELL
  mstr_symbols p5v *
  page155_i200
#ISCELL
  mstr_standard offpage *
  page155_i31
#ISCELL
  mstr_standard offpage *
  page155_i32
#ISCELL
  mstr_standard offpage *
  page155_i33
#ISCELL
  mstr_standard offpage *
  page155_i34
#ISCELL
  mstr_standard offpage *
  page155_i37
#ISCELL
  mstr_standard offpage *
  page155_i38
#ISCELL
  mstr_standard offpage *
  page155_i39
#ISCELL
  mstr_standard offpage *
  page155_i40
#ISCELL
  mstr_symbols gnd *
  page155_i41
#ISCELL
  mstr_standard offpage *
  page155_i42
#ISCELL
  mstr_standard offpage *
  page155_i43
#ISCELL
  mstr_standard offpage *
  page155_i52
#CELL
  mstr_discrete res *
  page155_i53
#ISCELL
  mstr_standard offpage *
  page155_i55
#ISCELL
  mstr_standard offpage *
  page155_i56
#ISCELL
  mstr_standard offpage *
  page155_i57
#ISCELL
  mstr_standard offpage *
  page155_i58
#ISCELL
  mstr_standard offpage *
  page155_i59
#ISCELL
  mstr_standard offpage *
  page155_i60
#ISCELL
  mstr_standard offpage *
  page155_i61
#ISCELL
  mstr_standard offpage *
  page155_i62
#ISCELL
  mstr_standard offpage *
  page155_i63
#ISCELL
  mstr_standard offpage *
  page155_i64
#CELL
  mstr_discrete res *
  page155_i65
#CELL
  mstr_discrete res *
  page155_i66
#CELL
  mstr_discrete res *
  page155_i67
#CELL
  mstr_discrete res *
  page155_i68
#ISCELL
  mstr_standard offpage *
  page155_i69
#ISCELL
  mstr_standard offpage *
  page155_i70
#ISCELL
  mstr_standard offpage *
  page155_i71
#ISCELL
  mstr_standard offpage *
  page155_i72
#CELL
  mstr_discrete res *
  page155_i73
#CELL
  mstr_discrete res *
  page155_i74
#CELL
  mstr_discrete res *
  page155_i75
#CELL
  mstr_discrete res *
  page155_i76
#ISCELL
  mstr_standard offpage *
  page155_i77
#ISCELL
  mstr_standard offpage *
  page155_i78
#ISCELL
  mstr_standard offpage *
  page155_i79
#CELL
  mstr_discrete res *
  page155_i80
#ISCELL
  mstr_symbols p3v3_stby *
  page155_i81
#ISCELL
  mstr_misc dns *
  *
#ISCELL
  mstr_symbols cad_note *
  *
#ISCELL
  mstr_symbols intel_corp_bpage *
  *
#CELL
  mstr_ttl ttl2g07 *
  page156_i201
#ISCELL
  mstr_standard offpage *
  page156_i202
#ISCELL
  mstr_standard offpage *
  page156_i203
#ISCELL
  mstr_standard offpage *
  page156_i204
#ISCELL
  mstr_standard offpage *
  page156_i205
#CELL
  mstr_discrete res *
  page156_i206
#CELL
  mstr_discrete res *
  page156_i207
#ISCELL
  mstr_symbols p3v3_stby *
  page156_i208
#ISCELL
  mstr_symbols p3v3_stby *
  page156_i209
#CELL
  mstr_discrete res *
  page156_i210
#CELL
  mstr_discrete res *
  page156_i211
#ISCELL
  mstr_standard offpage *
  page156_i212
#ISCELL
  mstr_standard offpage *
  page156_i213
#CELL
  mstr_discrete res *
  page156_i214
#CELL
  mstr_discrete res *
  page156_i215
#ISCELL
  mstr_symbols p3v3_stby *
  page156_i216
#ISCELL
  mstr_symbols gnd *
  page156_i257
#CELL
  mstr_discrete res *
  page156_i265
#ISCELL
  mstr_symbols p3v3_stby *
  page156_i266
#CELL
  mstr_discrete res *
  page156_i267
#CELL
  mstr_ttl ttl2g07 *
  page156_i269
#ISCELL
  mstr_standard offpage *
  page156_i270
#ISCELL
  mstr_standard offpage *
  page156_i271
#ISCELL
  mstr_symbols p3v3_stby *
  page156_i272
#CELL
  dev_discrete cap_a *
  page156_i273
#ISCELL
  mstr_symbols gnd *
  page156_i274
#CELL
  dev_discrete cap_a *
  page156_i275
#ISCELL
  mstr_symbols gnd *
  page156_i276
#ISCELL
  mstr_symbols p3v3_stby *
  page156_i277
#ISCELL
  mstr_standard offpage *
  page156_i278
#CELL
  mstr_discrete res *
  page156_i279
#ISCELL
  mstr_standard offpage *
  page156_i280
#CELL
  mstr_conn conn3_c95678002 *
  page156_i281
#ISCELL
  mstr_symbols gnd *
  page156_i282
#ISCELL
  mstr_standard offpage *
  page156_i283
#ISCELL
  mstr_standard offpage *
  page156_i284
#CELL
  mstr_conn conn3_c95678002 *
  page156_i285
#ISCELL
  mstr_standard offpage *
  page156_i286
#ISCELL
  mstr_standard offpage *
  page156_i287
#CELL
  mstr_discrete res *
  page156_i288
#CELL
  mstr_discrete res *
  page156_i289
#ISCELL
  mstr_standard offpage *
  page156_i296
#ISCELL
  mstr_standard offpage *
  page156_i297
#ISCELL
  mstr_standard offpage *
  page156_i298
#CELL
  mstr_discrete res *
  page156_i299
#CELL
  mstr_discrete res *
  page156_i300
#CELL
  mstr_discrete res *
  page156_i302
#CELL
  mstr_discrete res *
  page156_i303
#CELL
  mstr_discrete res *
  page156_i304
#ISCELL
  mstr_standard offpage *
  page156_i305
#ISCELL
  mstr_symbols gnd *
  page156_i306
#ISCELL
  mstr_standard offpage *
  page156_i308
#ISCELL
  mstr_standard offpage *
  page156_i309
#ISCELL
  mstr_standard offpage *
  page156_i310
#ISCELL
  mstr_symbols gnd *
  page156_i311
#CELL
  mstr_discrete res *
  page156_i312
#CELL
  mstr_discrete res *
  page156_i313
#ISCELL
  mstr_standard offpage *
  page156_i314
#ISCELL
  mstr_standard offpage *
  page156_i315
#ISCELL
  mstr_standard offpage *
  page156_i316
#ISCELL
  mstr_symbols p3v3_stby *
  page156_i318
#CELL
  mstr_discrete res *
  page156_i320
#CELL
  mstr_discrete res *
  page156_i321
#CELL
  mstr_discrete res *
  page156_i322
#CELL
  mstr_discrete res *
  page156_i323
#CELL
  mstr_discrete res *
  page156_i324
#ISCELL
  mstr_standard offpage *
  page156_i325
#ISCELL
  mstr_standard offpage *
  page156_i326
#ISCELL
  mstr_standard offpage *
  page156_i327
#ISCELL
  mstr_standard offpage *
  page156_i328
#ISCELL
  mstr_standard offpage *
  page156_i329
#ISCELL
  mstr_standard offpage *
  page156_i330
#CELL
  mstr_discrete res *
  page156_i331
#ISCELL
  mstr_symbols p3v3_stby *
  page156_i332
#CELL
  mstr_discrete res *
  page156_i333
#ISCELL
  mstr_symbols gnd *
  page156_i334
#ISCELL
  mstr_standard offpage *
  page156_i335
#CELL
  mstr_discrete res *
  page156_i336
#CELL
  mstr_discrete res *
  page156_i337
#ISCELL
  mstr_symbols gnd *
  page156_i338
#ISCELL
  mstr_symbols p3v3_stby *
  page156_i339
#ISCELL
  mstr_misc dns *
  *
#ISCELL
  mstr_symbols cad_note *
  *
#ISCELL
  mstr_symbols intel_corp_bpage *
  *
#ISCELL
  mstr_standard offpage *
  page157_i293
#CELL
  mstr_discrete res *
  page157_i296
#ISCELL
  mstr_symbols p3v3_stby *
  page157_i297
#CELL
  mstr_discrete res *
  page157_i298
#ISCELL
  mstr_standard offpage *
  page157_i299
#ISCELL
  mstr_standard offpage *
  page157_i300
#ISCELL
  mstr_standard offpage *
  page157_i301
#CELL
  mstr_discrete res *
  page157_i302
#ISCELL
  mstr_symbols p3v3 *
  page157_i303
#CELL
  mstr_discrete res *
  page157_i316
#ISCELL
  mstr_standard offpage *
  page157_i317
#ISCELL
  mstr_symbols gnd *
  page157_i322
#ISCELL
  mstr_standard offpage *
  page157_i324
#ISCELL
  mstr_standard offpage *
  page157_i325
#CELL
  mstr_discrete res *
  page157_i326
#CELL
  mstr_discrete res *
  page157_i327
#ISCELL
  mstr_symbols p3v3_stby *
  page157_i328
#ISCELL
  mstr_symbols p3v3_stby *
  page157_i329
#CELL
  mstr_discrete npn *
  page157_i330
#ISCELL
  mstr_symbols gnd *
  page157_i333
#CELL
  mstr_discrete res *
  page157_i335
#ISCELL
  mstr_symbols p3v3_stby *
  page157_i339
#CELL
  mstr_discrete fet_n *
  page157_i340
#CELL
  mstr_discrete res *
  page157_i342
#ISCELL
  mstr_standard offpage *
  page157_i343
#CELL
  mstr_discrete res *
  page157_i344
#ISCELL
  mstr_standard offpage *
  page157_i345
#CELL
  mstr_discrete res *
  page157_i346
#ISCELL
  mstr_standard offpage *
  page157_i347
#CELL
  mstr_discrete res *
  page157_i348
#ISCELL
  mstr_standard offpage *
  page157_i349
#CELL
  mstr_misc switch_d90553001 *
  page157_i351
#CELL
  mstr_discrete res *
  page157_i352
#CELL
  dev_discrete cap_a *
  page157_i353
#ISCELL
  mstr_symbols gnd *
  page157_i354
#ISCELL
  mstr_symbols gnd *
  page157_i355
#CELL
  mstr_ttl ttl2g14 *
  page157_i356
#CELL
  mstr_ttl ttl2g14 *
  page157_i357
#CELL
  mstr_discrete res *
  page157_i358
#ISCELL
  mstr_standard offpage *
  page157_i359
#ISCELL
  mstr_standard offpage *
  page157_i360
#CELL
  mstr_discrete res *
  page157_i361
#ISCELL
  mstr_symbols p3v3_stby *
  page157_i362
#ISCELL
  mstr_standard offpage *
  page157_i366
#CELL
  mstr_discrete res *
  page157_i367
#CELL
  mstr_discrete res *
  page157_i368
#ISCELL
  mstr_symbols p3v3_stby *
  page157_i369
#CELL
  dev_discrete cap_a *
  page157_i370
#ISCELL
  mstr_symbols gnd *
  page157_i371
#ISCELL
  mstr_standard offpage *
  page157_i373
#CELL
  mstr_ttl ttl1g07_a *
  page157_i374
#ISCELL
  mstr_standard offpage *
  page157_i375
#CELL
  dev_discrete cap_a *
  page157_i376
#ISCELL
  mstr_symbols gnd *
  page157_i377
#ISCELL
  mstr_symbols p3v3_stby *
  page157_i378
#CELL
  mstr_discrete res *
  page157_i379
#ISCELL
  mstr_standard offpage *
  page157_i380
#ISCELL
  mstr_standard offpage *
  page157_i381
#CELL
  mstr_discrete res *
  page157_i382
#ISCELL
  mstr_symbols p3v3_stby *
  page157_i384
#CELL
  mstr_discrete res *
  page157_i385
#CELL
  mstr_discrete res *
  page157_i386
#CELL
  mstr_discrete res *
  page157_i388
#ISCELL
  mstr_standard offpage *
  page157_i389
#CELL
  mstr_discrete res *
  page157_i97
#ISCELL
  mstr_misc dns *
  *
#ISCELL
  mstr_symbols cad_note *
  *
#ISCELL
  mstr_symbols design_note *
  *
#ISCELL
  mstr_symbols intel_corp_bpage *
  *
#CELL
  mstr_discrete res *
  page158_i100
#ISCELL
  mstr_standard offpage *
  page158_i124
#ISCELL
  mstr_standard offpage *
  page158_i125
#ISCELL
  mstr_standard offpage *
  page158_i126
#ISCELL
  mstr_standard offpage *
  page158_i127
#ISCELL
  mstr_standard offpage *
  page158_i128
#ISCELL
  mstr_standard offpage *
  page158_i129
#CELL
  mstr_discrete led *
  page158_i130
#CELL
  mstr_discrete res *
  page158_i131
#ISCELL
  mstr_standard offpage *
  page158_i132
#CELL
  mstr_discrete led *
  page158_i134
#ISCELL
  mstr_symbols p3v3_stby *
  page158_i135
#CELL
  mstr_discrete res *
  page158_i136
#ISCELL
  mstr_standard offpage *
  page158_i137
#ISCELL
  mstr_standard offpage *
  page158_i144
#ISCELL
  mstr_standard offpage *
  page158_i147
#CELL
  mstr_discrete res *
  page158_i148
#CELL
  mstr_discrete res *
  page158_i149
#CELL
  mstr_discrete res *
  page158_i150
#CELL
  mstr_discrete res *
  page158_i152
#CELL
  dev_discrete cap_a *
  page158_i70
#ISCELL
  mstr_symbols gnd *
  page158_i72
#CELL
  mstr_analog fsa3357 *
  page158_i74
#CELL
  mstr_analog fsa3357 *
  page158_i75
#ISCELL
  mstr_symbols gnd *
  page158_i76
#ISCELL
  mstr_symbols gnd *
  page158_i77
#ISCELL
  mstr_symbols p3v3_stby *
  page158_i78
#ISCELL
  mstr_symbols p3v3_stby *
  page158_i79
#ISCELL
  mstr_standard offpage *
  page158_i85
#CELL
  mstr_discrete res *
  page158_i86
#ISCELL
  mstr_standard offpage *
  page158_i87
#CELL
  mstr_discrete res *
  page158_i91
#ISCELL
  mstr_standard offpage *
  page158_i92
#ISCELL
  mstr_standard offpage *
  page158_i93
#ISCELL
  mstr_standard offpage *
  page158_i94
#ISCELL
  mstr_standard offpage *
  page158_i95
#CELL
  dev_discrete cap_a *
  page158_i97
#ISCELL
  mstr_symbols gnd *
  page158_i98
#CELL
  mstr_discrete res *
  page158_i99
#ISCELL
  mstr_misc dns *
  *
#ISCELL
  mstr_symbols cad_note *
  *
#ISCELL
  mstr_symbols intel_corp_bpage *
  *
#ISCELL
  mstr_standard offpage *
  page159_i111
#ISCELL
  mstr_standard offpage *
  page159_i112
#ISCELL
  mstr_standard offpage *
  page159_i113
#ISCELL
  mstr_standard offpage *
  page159_i114
#ISCELL
  mstr_standard offpage *
  page159_i117
#ISCELL
  mstr_standard offpage *
  page159_i118
#ISCELL
  mstr_standard offpage *
  page159_i161
#ISCELL
  mstr_standard offpage *
  page159_i162
#ISCELL
  mstr_standard offpage *
  page159_i168
#ISCELL
  mstr_standard offpage *
  page159_i169
#ISCELL
  mstr_standard offpage *
  page159_i170
#ISCELL
  mstr_standard offpage *
  page159_i171
#ISCELL
  mstr_standard offpage *
  page159_i185
#ISCELL
  mstr_standard offpage *
  page159_i186
#ISCELL
  mstr_standard offpage *
  page159_i187
#ISCELL
  mstr_standard offpage *
  page159_i188
#ISCELL
  mstr_standard offpage *
  page159_i189
#ISCELL
  mstr_standard offpage *
  page159_i190
#ISCELL
  mstr_standard offpage *
  page159_i195
#ISCELL
  mstr_standard offpage *
  page159_i196
#ISCELL
  mstr_standard offpage *
  page159_i197
#ISCELL
  mstr_standard offpage *
  page159_i198
#ISCELL
  mstr_standard offpage *
  page159_i199
#ISCELL
  mstr_standard offpage *
  page159_i200
#ISCELL
  mstr_symbols p3v3_stby *
  page159_i209
#CELL
  mstr_discrete res *
  page159_i210
#ISCELL
  mstr_symbols p3v3_stby *
  page159_i211
#CELL
  mstr_discrete res *
  page159_i212
#ISCELL
  mstr_symbols p3v3_stby *
  page159_i213
#CELL
  mstr_discrete res *
  page159_i214
#ISCELL
  mstr_symbols p3v3_stby *
  page159_i215
#CELL
  mstr_discrete res *
  page159_i216
#CELL
  mstr_discrete res *
  page159_i218
#CELL
  mstr_discrete res *
  page159_i219
#CELL
  mstr_discrete res *
  page159_i220
#CELL
  mstr_discrete res *
  page159_i221
#CELL
  mstr_discrete res *
  page159_i222
#CELL
  mstr_discrete res *
  page159_i223
#CELL
  mstr_discrete res *
  page159_i224
#CELL
  mstr_discrete res *
  page159_i225
#CELL
  mstr_discrete res *
  page159_i226
#CELL
  mstr_discrete res *
  page159_i227
#CELL
  mstr_discrete res *
  page159_i228
#CELL
  mstr_discrete res *
  page159_i229
#CELL
  mstr_discrete res *
  page159_i230
#CELL
  mstr_discrete res *
  page159_i231
#CELL
  mstr_discrete res *
  page159_i232
#CELL
  mstr_discrete res *
  page159_i233
#ISCELL
  mstr_standard offpage *
  page159_i75
#ISCELL
  mstr_standard offpage *
  page159_i76
#ISCELL
  mstr_standard offpage *
  page159_i77
#ISCELL
  mstr_standard offpage *
  page159_i78
#ISCELL
  mstr_standard offpage *
  page159_i79
#ISCELL
  mstr_standard offpage *
  page159_i83
#ISCELL
  mstr_symbols cad_note *
  *
#ISCELL
  mstr_symbols design_note *
  *
#ISCELL
  mstr_symbols intel_corp_bpage *
  *
#ISCELL
  mstr_standard offpage *
  page160_i1
#ISCELL
  mstr_standard offpage *
  page160_i10
#ISCELL
  mstr_standard offpage *
  page160_i17
#ISCELL
  mstr_standard offpage *
  page160_i18
#ISCELL
  mstr_standard offpage *
  page160_i19
#ISCELL
  mstr_standard offpage *
  page160_i2
#ISCELL
  mstr_standard offpage *
  page160_i20
#CELL
  mstr_discrete res *
  page160_i4
#CELL
  mstr_discrete res *
  page160_i46
#ISCELL
  mstr_symbols p3v3_stby *
  page160_i47
#ISCELL
  mstr_symbols p3v3_stby *
  page160_i48
#CELL
  mstr_discrete res *
  page160_i49
#CELL
  mstr_discrete res *
  page160_i50
#CELL
  mstr_discrete res *
  page160_i51
#CELL
  mstr_discrete res *
  page160_i52
#ISCELL
  mstr_standard offpage *
  page160_i9
#ISCELL
  mstr_misc dns *
  *
#ISCELL
  mstr_symbols cad_note *
  *
#ISCELL
  mstr_symbols intel_corp_bpage *
  *
#CELL
  mstr_conn conn6_c74770005 *
  page161_i1
#ISCELL
  mstr_standard offpage *
  page161_i100
#CELL
  mstr_discrete res *
  page161_i102
#ISCELL
  mstr_standard offpage *
  page161_i103
#ISCELL
  mstr_symbols gnd *
  page161_i104
#ISCELL
  mstr_symbols p3v3_stby *
  page161_i105
#ISCELL
  mstr_symbols p12v_fan *
  page161_i108
#ISCELL
  mstr_symbols p12v_fan *
  page161_i110
#ISCELL
  mstr_symbols gnd *
  page161_i111
#CELL
  dev_discrete cap_a *
  page161_i113
#ISCELL
  mstr_standard offpage *
  page161_i114
#ISCELL
  mstr_standard offpage *
  page161_i115
#ISCELL
  mstr_standard offpage *
  page161_i116
#ISCELL
  mstr_symbols p3v3_stby *
  page161_i117
#ISCELL
  mstr_symbols gnd *
  page161_i118
#ISCELL
  mstr_symbols p3v3_stby *
  page161_i119
#CELL
  mstr_discrete res *
  page161_i120
#CELL
  mstr_ttl ttl1g08 *
  page161_i121
#ISCELL
  mstr_symbols gnd *
  page161_i122
#CELL
  mstr_discrete diode *
  page161_i123
#CELL
  mstr_discrete res *
  page161_i124
#CELL
  mstr_discrete res *
  page161_i126
#CELL
  dev_discrete cap_a *
  page161_i128
#ISCELL
  mstr_symbols gnd *
  page161_i129
#ISCELL
  mstr_symbols gnd *
  page161_i13
#ISCELL
  mstr_symbols p3v3_stby *
  page161_i130
#ISCELL
  mstr_standard offpage *
  page161_i131
#ISCELL
  mstr_symbols gnd *
  page161_i132
#CELL
  mstr_discrete diode *
  page161_i133
#CELL
  mstr_discrete res *
  page161_i134
#CELL
  mstr_discrete res *
  page161_i135
#ISCELL
  mstr_symbols p3v3_stby *
  page161_i136
#CELL
  dev_discrete cap_a *
  page161_i137
#ISCELL
  mstr_standard offpage *
  page161_i138
#CELL
  dev_discrete cap_a *
  page161_i26
#CELL
  mstr_discrete cap *
  page161_i27
#CELL
  mstr_discrete cap *
  page161_i3
#ISCELL
  mstr_symbols gnd *
  page161_i30
#CELL
  mstr_conn conn6_c74770005 *
  page161_i32
#CELL
  dev_discrete cap_a *
  page161_i4
#CELL
  mstr_discrete diode *
  page161_i42
#CELL
  mstr_discrete res *
  page161_i43
#CELL
  mstr_discrete res *
  page161_i45
#CELL
  dev_discrete cap_a *
  page161_i46
#ISCELL
  mstr_symbols gnd *
  page161_i47
#ISCELL
  mstr_symbols p3v3_stby *
  page161_i48
#ISCELL
  mstr_standard offpage *
  page161_i49
#CELL
  mstr_discrete diode *
  page161_i50
#CELL
  mstr_discrete res *
  page161_i51
#ISCELL
  mstr_symbols p5v_stby *
  page161_i52
#ISCELL
  mstr_standard offpage *
  page161_i53
#ISCELL
  mstr_symbols p3v3_stby *
  page161_i61
#CELL
  mstr_discrete diode *
  page161_i62
#ISCELL
  mstr_symbols p5v_stby *
  page161_i63
#CELL
  mstr_discrete diode *
  page161_i64
#CELL
  mstr_discrete res *
  page161_i65
#CELL
  mstr_discrete res *
  page161_i67
#CELL
  dev_discrete cap_a *
  page161_i68
#ISCELL
  mstr_symbols gnd *
  page161_i69
#CELL
  mstr_discrete res *
  page161_i70
#ISCELL
  mstr_standard offpage *
  page161_i75
#ISCELL
  mstr_standard offpage *
  page161_i76
#CELL
  mstr_ttl ttl1g07_a *
  page161_i88
#CELL
  dev_discrete cap_a *
  page161_i90
#CELL
  mstr_ttl ttl1g07_a *
  page161_i92
#CELL
  dev_discrete cap_a *
  page161_i93
#ISCELL
  mstr_standard offpage *
  page161_i94
#ISCELL
  mstr_symbols p3v3_stby *
  page161_i96
#ISCELL
  mstr_symbols gnd *
  page161_i97
#ISCELL
  mstr_standard offpage *
  page161_i98
#CELL
  mstr_discrete res *
  page161_i99
#ISCELL
  mstr_misc dns *
  *
#ISCELL
  mstr_symbols bom_note *
  *
#ISCELL
  mstr_symbols cad_note *
  *
#ISCELL
  mstr_symbols intel_corp_bpage *
  *
#ISCELL
  mstr_symbols p3v3_stby *
  page162_i10
#CELL
  mstr_discrete res *
  page162_i13
#ISCELL
  mstr_standard offpage *
  page162_i16
#ISCELL
  mstr_standard offpage *
  page162_i17
#ISCELL
  mstr_standard offpage *
  page162_i19
#ISCELL
  mstr_standard offpage *
  page162_i21
#CELL
  mstr_discrete res *
  page162_i22
#CELL
  mstr_discrete res *
  page162_i23
#CELL
  mstr_discrete res *
  page162_i24
#CELL
  dev_discrete cap_a *
  page162_i28
#CELL
  dev_discrete cap_a *
  page162_i30
#ISCELL
  mstr_symbols gnd *
  page162_i31
#CELL
  mstr_memory w25q128 *
  page162_i32
#ISCELL
  mstr_symbols gnd *
  page162_i33
#ISCELL
  mstr_symbols gnd *
  page162_i6
#CELL
  mstr_discrete res *
  page162_i8
#CELL
  mstr_discrete res *
  page162_i9
#ISCELL
  mstr_symbols cad_note *
  *
#ISCELL
  mstr_symbols design_note *
  *
#ISCELL
  mstr_symbols intel_corp_bpage *
  *
#CELL
  mstr_digital pca9517 *
  page163_i1
#CELL
  dev_discrete cap_a *
  page163_i10
#ISCELL
  mstr_symbols gnd *
  page163_i11
#CELL
  dev_discrete cap_a *
  page163_i12
#ISCELL
  mstr_symbols gnd *
  page163_i13
#CELL
  mstr_discrete res *
  page163_i15
#CELL
  mstr_discrete res *
  page163_i16
#ISCELL
  mstr_standard offpage *
  page163_i18
#ISCELL
  mstr_standard offpage *
  page163_i19
#CELL
  mstr_discrete res *
  page163_i2
#CELL
  mstr_discrete res *
  page163_i20
#CELL
  mstr_discrete res *
  page163_i21
#ISCELL
  mstr_standard offpage *
  page163_i22
#ISCELL
  mstr_standard offpage *
  page163_i23
#CELL
  mstr_discrete res *
  page163_i24
#CELL
  mstr_discrete res *
  page163_i25
#ISCELL
  mstr_symbols p3v3_stby *
  page163_i26
#ISCELL
  mstr_symbols p3v3_stby *
  page163_i27
#CELL
  mstr_discrete res *
  page163_i3
#ISCELL
  mstr_standard offpage *
  page163_i4
#ISCELL
  mstr_standard offpage *
  page163_i5
#CELL
  mstr_discrete res *
  page163_i6
#CELL
  mstr_discrete res *
  page163_i7
#ISCELL
  mstr_symbols pvccio_cpu1 *
  page163_i8
#ISCELL
  mstr_symbols pvccio_cpu1 *
  page163_i9
#ISCELL
  mstr_misc dns *
  *
#ISCELL
  mstr_symbols intel_corp_bpage *
  *
#CELL
  mstr_discrete res *
  page164_i11
#ISCELL
  mstr_symbols p3v3_stby *
  page164_i12
#CELL
  mstr_discrete res *
  page164_i13
#CELL
  mstr_discrete res *
  page164_i14
#ISCELL
  mstr_standard offpage *
  page164_i15
#ISCELL
  mstr_standard offpage *
  page164_i16
#ISCELL
  mstr_standard offpage *
  page164_i17
#ISCELL
  mstr_standard offpage *
  page164_i18
#CELL
  mstr_discrete res *
  page164_i19
#ISCELL
  mstr_standard offpage *
  page164_i2
#CELL
  mstr_discrete res *
  page164_i20
#CELL
  mstr_discrete res *
  page164_i21
#CELL
  mstr_discrete res *
  page164_i22
#CELL
  mstr_discrete res *
  page164_i24
#CELL
  mstr_discrete res *
  page164_i25
#ISCELL
  mstr_symbols p3v3_stby *
  page164_i26
#CELL
  mstr_discrete res *
  page164_i27
#CELL
  mstr_discrete res *
  page164_i28
#CELL
  mstr_discrete res *
  page164_i29
#ISCELL
  mstr_standard offpage *
  page164_i3
#ISCELL
  mstr_standard offpage *
  page164_i30
#ISCELL
  mstr_symbols gnd *
  page164_i31
#CELL
  mstr_discrete res *
  page164_i32
#ISCELL
  mstr_standard offpage *
  page164_i4
#CELL
  mstr_discrete res *
  page164_i5
#CELL
  mstr_discrete res *
  page164_i6
#CELL
  mstr_discrete res *
  page164_i7
#ISCELL
  mstr_symbols gnd *
  page164_i9
#ISCELL
  mstr_misc dns *
  *
#ISCELL
  mstr_symbols cad_note *
  *
#ISCELL
  mstr_symbols design_note *
  *
#ISCELL
  mstr_symbols intel_corp_bpage *
  *
#CELL
  mstr_digital adc128d818 *
  page165_i52
#ISCELL
  mstr_standard offpage *
  page165_i53
#ISCELL
  mstr_standard offpage *
  page165_i54
#CELL
  mstr_discrete res *
  page165_i55
#CELL
  mstr_discrete res *
  page165_i56
#CELL
  mstr_discrete res *
  page165_i57
#CELL
  mstr_discrete res *
  page165_i58
#ISCELL
  mstr_symbols gnd *
  page165_i59
#ISCELL
  mstr_symbols gnd *
  page165_i60
#CELL
  dev_discrete cap_a *
  page165_i61
#ISCELL
  mstr_symbols gnd *
  page165_i62
#ISCELL
  mstr_symbols p3v3_stby *
  page165_i63
#ISCELL
  mstr_symbols p3v3_stby *
  page165_i64
#ISCELL
  mstr_symbols p3v3_stby *
  page165_i65
#ISCELL
  mstr_symbols gnd *
  page165_i66
#CELL
  mstr_discrete cap *
  page165_i67
#ISCELL
  mstr_symbols gnd *
  page165_i68
#CELL
  mstr_discrete res *
  page165_i69
#ISCELL
  mstr_symbols p3v3_stby *
  page165_i70
#ISCELL
  mstr_standard offpage *
  page165_i71
#ISCELL
  mstr_standard offpage *
  page165_i72
#ISCELL
  mstr_standard offpage *
  page165_i73
#ISCELL
  mstr_standard offpage *
  page165_i74
#ISCELL
  mstr_standard offpage *
  page165_i75
#ISCELL
  mstr_standard offpage *
  page165_i76
#ISCELL
  mstr_standard offpage *
  page165_i77
#ISCELL
  mstr_standard offpage *
  page165_i78
#CELL
  mstr_discrete ferrite *
  page165_i79
#ISCELL
  mstr_standard offpage *
  page165_i80
#CELL
  mstr_discrete res *
  page165_i81
#ISCELL
  mstr_misc dns *
  *
#ISCELL
  mstr_symbols cad_note *
  *
#ISCELL
  mstr_symbols design_note *
  *
#ISCELL
  mstr_symbols intel_corp_bpage *
  *
#CELL
  mstr_discrete res *
  page166_i11
#CELL
  mstr_discrete res *
  page166_i14
#CELL
  mstr_discrete res *
  page166_i15
#ISCELL
  mstr_standard offpage *
  page166_i16
#ISCELL
  mstr_standard offpage *
  page166_i17
#ISCELL
  mstr_standard offpage *
  page166_i2
#CELL
  mstr_discrete res *
  page166_i28
#ISCELL
  mstr_symbols pvccio_cpu0 *
  page166_i31
#CELL
  mstr_discrete res *
  page166_i32
#ISCELL
  mstr_symbols gnd *
  page166_i33
#ISCELL
  mstr_misc dns *
  *
#ISCELL
  mstr_symbols cad_note *
  *
#ISCELL
  mstr_symbols design_note *
  *
#ISCELL
  mstr_symbols intel_corp_bpage *
  *
#CELL
  mstr_analog tmp421 *
  page167_i1
#CELL
  mstr_discrete res *
  page167_i10
#ISCELL
  mstr_symbols gnd *
  page167_i12
#ISCELL
  mstr_symbols p3v3_stby *
  page167_i14
#ISCELL
  mstr_symbols gnd *
  page167_i15
#ISCELL
  mstr_standard offpage *
  page167_i16
#ISCELL
  mstr_standard offpage *
  page167_i17
#ISCELL
  mstr_symbols gnd *
  page167_i22
#ISCELL
  mstr_symbols p3v3_stby *
  page167_i23
#CELL
  mstr_discrete cap *
  page167_i24
#CELL
  mstr_discrete res *
  page167_i25
#CELL
  mstr_discrete res *
  page167_i26
#CELL
  mstr_discrete pnp *
  page167_i27
#ISCELL
  mstr_symbols p3v3_stby *
  page167_i29
#CELL
  mstr_discrete pnp *
  page167_i3
#CELL
  mstr_analog tmp421 *
  page167_i30
#CELL
  mstr_discrete res *
  page167_i34
#CELL
  mstr_discrete res *
  page167_i35
#CELL
  mstr_discrete res *
  page167_i38
#CELL
  dev_discrete cap_a *
  page167_i39
#CELL
  dev_discrete cap_a *
  page167_i41
#CELL
  dev_discrete cap_a *
  page167_i42
#ISCELL
  mstr_symbols gnd *
  page167_i45
#ISCELL
  mstr_symbols gnd *
  page167_i46
#ISCELL
  mstr_symbols gnd *
  page167_i47
#CELL
  mstr_memory at24c64 *
  page167_i49
#CELL
  mstr_discrete res *
  page167_i5
#CELL
  mstr_discrete res *
  page167_i50
#ISCELL
  mstr_symbols gnd *
  page167_i52
#ISCELL
  mstr_symbols gnd *
  page167_i55
#ISCELL
  mstr_symbols p3v3_stby *
  page167_i56
#ISCELL
  mstr_symbols p3v3_stby *
  page167_i57
#CELL
  mstr_discrete res *
  page167_i58
#CELL
  mstr_discrete res *
  page167_i6
#ISCELL
  mstr_standard offpage *
  page167_i60
#ISCELL
  mstr_standard offpage *
  page167_i61
#ISCELL
  mstr_standard offpage *
  page167_i62
#ISCELL
  mstr_standard offpage *
  page167_i63
#ISCELL
  mstr_standard offpage *
  page167_i64
#ISCELL
  mstr_standard offpage *
  page167_i65
#ISCELL
  mstr_standard offpage *
  page167_i67
#ISCELL
  mstr_standard offpage *
  page167_i69
#CELL
  mstr_discrete cap *
  page167_i7
#CELL
  mstr_discrete res *
  page167_i70
#ISCELL
  mstr_symbols p3v3_stby *
  page167_i71
#ISCELL
  mstr_symbols p3v3_stby *
  page167_i72
#ISCELL
  mstr_symbols p3v3_stby *
  page167_i73
#CELL
  mstr_discrete res *
  page167_i74
#CELL
  mstr_discrete res *
  page167_i75
#CELL
  mstr_discrete res *
  page167_i76
#CELL
  mstr_discrete res *
  page167_i77
#CELL
  mstr_discrete res *
  page167_i78
#CELL
  mstr_discrete res *
  page167_i79
#CELL
  mstr_discrete res *
  page167_i8
#CELL
  mstr_discrete res *
  page167_i80
#ISCELL
  mstr_symbols p3v3_stby *
  page167_i81
#ISCELL
  mstr_symbols p3v3_stby *
  page167_i82
#CELL
  mstr_discrete res *
  page167_i83
#CELL
  mstr_discrete res *
  page167_i84
#CELL
  mstr_discrete res *
  page167_i85
#ISCELL
  mstr_standard offpage *
  page167_i86
#ISCELL
  mstr_standard offpage *
  page167_i87
#ISCELL
  mstr_symbols intel_corp_bpage *
  *
#ISCELL
  mstr_standard offpage *
  page168_i1
#CELL
  mstr_discrete res *
  page168_i11
#ISCELL
  mstr_symbols gnd *
  page168_i14
#CELL
  mstr_discrete fet_n_dual *
  page168_i18
#CELL
  mstr_discrete fet_n_dual *
  page168_i19
#CELL
  mstr_discrete diode *
  page168_i2
#CELL
  mstr_discrete res *
  page168_i22
#ISCELL
  mstr_symbols p3v3_stby *
  page168_i24
#ISCELL
  mstr_symbols gnd *
  page168_i26
#ISCELL
  mstr_standard offpage *
  page168_i28
#ISCELL
  mstr_symbols p3v3_stby *
  page168_i29
#CELL
  mstr_discrete diode *
  page168_i3
#ISCELL
  mstr_standard offpage *
  page168_i31
#ISCELL
  mstr_symbols gnd *
  page168_i32
#CELL
  mstr_discrete res *
  page168_i33
#CELL
  mstr_discrete res *
  page168_i34
#ISCELL
  mstr_symbols p5v_stby *
  page168_i35
#ISCELL
  mstr_symbols gnd *
  page168_i36
#CELL
  mstr_discrete npn *
  page168_i37
#ISCELL
  mstr_symbols p3v3_stby *
  page168_i38
#CELL
  mstr_discrete res *
  page168_i39
#CELL
  mstr_discrete diode *
  page168_i4
#CELL
  mstr_discrete res *
  page168_i40
#CELL
  mstr_discrete fet_n *
  page168_i41
#CELL
  mstr_discrete diode *
  page168_i5
#CELL
  mstr_discrete res *
  page168_i6
#CELL
  mstr_discrete npn *
  page168_i8
#ISCELL
  mstr_symbols cad_note *
  *
#ISCELL
  mstr_symbols design_note *
  *
#ISCELL
  mstr_symbols intel_corp_bpage *
  *
#ISCELL
  mstr_standard offpage *
  page169_i103
#ISCELL
  mstr_standard offpage *
  page169_i105
#CELL
  mstr_discrete res *
  page169_i106
#ISCELL
  mstr_symbols gnd *
  page169_i107
#CELL
  mstr_discrete cap *
  page169_i108
#ISCELL
  mstr_symbols gnd *
  page169_i109
#CELL
  mstr_discrete res *
  page169_i114
#CELL
  mstr_discrete res *
  page169_i115
#CELL
  mstr_discrete res *
  page169_i116
#ISCELL
  mstr_symbols p5v_stby *
  page169_i119
#ISCELL
  mstr_symbols p1v05_pch_stby *
  page169_i121
#CELL
  mstr_discrete res *
  page169_i126
#ISCELL
  mstr_symbols p3v3_stby *
  page169_i131
#ISCELL
  mstr_symbols p12v_stby *
  page169_i132
#ISCELL
  mstr_standard offpage *
  page169_i138
#CELL
  mstr_discrete cap *
  page169_i139
#CELL
  mstr_discrete res *
  page169_i141
#CELL
  mstr_discrete res *
  page169_i142
#ISCELL
  mstr_symbols gnd *
  page169_i143
#ISCELL
  mstr_symbols p5v *
  page169_i144
#ISCELL
  mstr_standard offpage *
  page169_i145
#CELL
  mstr_discrete cap *
  page169_i146
#CELL
  mstr_discrete res *
  page169_i148
#CELL
  mstr_discrete res *
  page169_i149
#ISCELL
  mstr_symbols gnd *
  page169_i150
#ISCELL
  mstr_symbols p3v3 *
  page169_i151
#ISCELL
  mstr_standard offpage *
  page169_i152
#CELL
  mstr_discrete cap *
  page169_i153
#ISCELL
  mstr_symbols pvnn_pch_stby *
  page169_i154
#CELL
  mstr_discrete ferrite *
  page169_i155
#ISCELL
  mstr_symbols gnd *
  page169_i156
#CELL
  mstr_discrete fet_n_dual *
  page169_i157
#ISCELL
  mstr_symbols gnd *
  page169_i160
#ISCELL
  mstr_standard offpage *
  page169_i161
#CELL
  mstr_discrete fet_n_dual *
  page169_i162
#CELL
  mstr_discrete res *
  page169_i163
#CELL
  mstr_discrete res *
  page169_i164
#ISCELL
  mstr_symbols p3v3_stby *
  page169_i165
#ISCELL
  mstr_symbols p3v3_stby *
  page169_i166
#ISCELL
  mstr_standard offpage *
  page169_i55
#CELL
  mstr_discrete cap *
  page169_i56
#CELL
  mstr_discrete ferrite *
  page169_i57
#ISCELL
  mstr_symbols gnd *
  page169_i58
#ISCELL
  mstr_standard offpage *
  page169_i67
#CELL
  mstr_discrete cap *
  page169_i68
#ISCELL
  mstr_symbols gnd *
  page169_i71
#ISCELL
  mstr_standard offpage *
  page169_i79
#CELL
  mstr_discrete cap *
  page169_i80
#CELL
  mstr_discrete res *
  page169_i82
#CELL
  mstr_discrete res *
  page169_i83
#ISCELL
  mstr_symbols gnd *
  page169_i84
#ISCELL
  mstr_standard offpage *
  page169_i85
#CELL
  mstr_discrete cap *
  page169_i86
#CELL
  mstr_discrete res *
  page169_i88
#ISCELL
  mstr_symbols gnd *
  page169_i90
#ISCELL
  mstr_misc dns *
  *
#ISCELL
  mstr_symbols cad_note *
  *
#ISCELL
  mstr_symbols design_note *
  *
#ISCELL
  mstr_symbols intel_corp_bpage *
  *
#CELL
  mstr_ttl ttl08 *
  page170_i10
#CELL
  mstr_ttl ttl08 *
  page170_i11
#CELL
  mstr_ttl ttl08 *
  page170_i12
#ISCELL
  mstr_standard offpage *
  page170_i15
#ISCELL
  mstr_standard offpage *
  page170_i16
#ISCELL
  mstr_standard offpage *
  page170_i17
#ISCELL
  mstr_standard offpage *
  page170_i18
#ISCELL
  mstr_standard offpage *
  page170_i19
#CELL
  mstr_discrete res *
  page170_i2
#CELL
  mstr_ttl ttl1g126_a *
  page170_i20
#ISCELL
  mstr_symbols p3v3_stby *
  page170_i3
#CELL
  dev_discrete cap_a *
  page170_i30
#ISCELL
  mstr_symbols gnd *
  page170_i31
#ISCELL
  mstr_symbols p3v3_stby *
  page170_i32
#CELL
  dev_discrete cap_a *
  page170_i33
#ISCELL
  mstr_symbols gnd *
  page170_i34
#ISCELL
  mstr_symbols p3v3_stby *
  page170_i35
#CELL
  mstr_ttl ttl1g126_a *
  page170_i38
#ISCELL
  mstr_symbols p3v3_stby *
  page170_i39
#CELL
  mstr_ttl ttl1g07_a *
  page170_i4
#CELL
  dev_discrete cap_a *
  page170_i40
#ISCELL
  mstr_symbols gnd *
  page170_i41
#CELL
  mstr_discrete cap *
  page170_i42
#ISCELL
  mstr_symbols gnd *
  page170_i43
#ISCELL
  mstr_standard offpage *
  page170_i44
#CELL
  mstr_ttl ttl1g07_a *
  page170_i46
#ISCELL
  mstr_standard offpage *
  page170_i47
#ISCELL
  mstr_symbols p3v3_stby *
  page170_i48
#CELL
  dev_discrete cap_a *
  page170_i49
#ISCELL
  mstr_standard offpage *
  page170_i5
#ISCELL
  mstr_symbols gnd *
  page170_i50
#CELL
  mstr_discrete res *
  page170_i51
#CELL
  mstr_discrete res *
  page170_i52
#ISCELL
  mstr_symbols p3v3_stby *
  page170_i53
#CELL
  mstr_discrete res *
  page170_i54
#ISCELL
  mstr_symbols p3v3_stby *
  page170_i55
#CELL
  mstr_discrete res *
  page170_i56
#CELL
  mstr_discrete fet_n *
  page170_i58
#ISCELL
  mstr_standard offpage *
  page170_i59
#ISCELL
  mstr_symbols p3v3_stby *
  page170_i6
#ISCELL
  mstr_symbols gnd *
  page170_i60
#CELL
  mstr_discrete res *
  page170_i61
#ISCELL
  mstr_symbols p3v3_stby *
  page170_i62
#CELL
  mstr_discrete res *
  page170_i63
#ISCELL
  mstr_symbols gnd *
  page170_i64
#CELL
  mstr_discrete res *
  page170_i65
#ISCELL
  mstr_symbols p3v3_stby *
  page170_i66
#CELL
  mstr_discrete fet_n *
  page170_i67
#ISCELL
  mstr_symbols gnd *
  page170_i68
#ISCELL
  mstr_standard offpage *
  page170_i69
#ISCELL
  mstr_symbols gnd *
  page170_i7
#ISCELL
  mstr_symbols p3v3_stby *
  page170_i70
#CELL
  mstr_discrete res *
  page170_i71
#ISCELL
  mstr_symbols p3v3_stby *
  page170_i72
#CELL
  mstr_discrete res *
  page170_i73
#CELL
  mstr_discrete res *
  page170_i74
#CELL
  dev_discrete cap_a *
  page170_i8
#ISCELL
  mstr_symbols intel_corp_bpage *
  *
#ISCELL
  mstr_misc dns *
  *
#ISCELL
  mstr_symbols design_note *
  *
#ISCELL
  mstr_symbols intel_corp_bpage *
  *
#ISCELL
  mstr_standard offpage *
  page172_i10
#ISCELL
  mstr_standard offpage *
  page172_i11
#ISCELL
  mstr_standard offpage *
  page172_i12
#CELL
  mstr_conn conn7_e82125014 *
  page172_i17
#ISCELL
  mstr_symbols gnd *
  page172_i2
#CELL
  mstr_conn conn4_h73295001 *
  page172_i25
#ISCELL
  mstr_symbols gnd *
  page172_i26
#ISCELL
  mstr_symbols gnd *
  page172_i35
#CELL
  mstr_discrete cap *
  page172_i36
#ISCELL
  mstr_symbols p12v *
  page172_i37
#CELL
  mstr_discrete fuse *
  page172_i38
#CELL
  mstr_discrete cap *
  page172_i39
#ISCELL
  mstr_symbols gnd *
  page172_i40
#CELL
  mstr_discrete fuse *
  page172_i41
#ISCELL
  mstr_symbols p5v *
  page172_i42
#CELL
  dev_discrete cap_a *
  page172_i5
#ISCELL
  mstr_symbols gnd *
  page172_i51
#CELL
  mstr_conn conn7_e82125014 *
  page172_i52
#CELL
  mstr_conn conn4_h73295001 *
  page172_i53
#ISCELL
  mstr_symbols gnd *
  page172_i54
#CELL
  dev_discrete cap_a *
  page172_i6
#CELL
  dev_discrete cap_a *
  page172_i7
#CELL
  dev_discrete cap_a *
  page172_i8
#ISCELL
  mstr_standard offpage *
  page172_i9
#ISCELL
  mstr_symbols cad_note *
  *
#ISCELL
  mstr_symbols design_note *
  *
#ISCELL
  mstr_symbols intel_corp_bpage *
  *
#ISCELL
  mstr_symbols gnd *
  page173_i103
#ISCELL
  mstr_symbols gnd *
  page173_i162
#CELL
  mstr_conn conn72_g97614002_a *
  page173_i163
#CELL
  dev_discrete cap_a *
  page173_i165
#CELL
  dev_discrete cap_a *
  page173_i166
#ISCELL
  mstr_standard offpage *
  page173_i170
#ISCELL
  mstr_standard offpage *
  page173_i171
#CELL
  dev_discrete cap_a *
  page173_i172
#CELL
  dev_discrete cap_a *
  page173_i173
#CELL
  dev_discrete cap_a *
  page173_i174
#ISCELL
  mstr_standard tap *
  page173_i175
#ISCELL
  mstr_standard tap *
  page173_i176
#ISCELL
  mstr_standard tap *
  page173_i177
#CELL
  dev_discrete cap_a *
  page173_i191
#CELL
  dev_discrete cap_a *
  page173_i192
#CELL
  dev_discrete cap_a *
  page173_i194
#CELL
  dev_discrete cap_a *
  page173_i195
#CELL
  dev_discrete cap_a *
  page173_i196
#CELL
  dev_discrete cap_a *
  page173_i197
#ISCELL
  mstr_standard tap *
  page173_i198
#ISCELL
  mstr_standard tap *
  page173_i199
#ISCELL
  mstr_standard tap *
  page173_i200
#ISCELL
  mstr_standard tap *
  page173_i201
#ISCELL
  mstr_standard tap *
  page173_i202
#ISCELL
  mstr_standard tap *
  page173_i203
#ISCELL
  mstr_standard tap *
  page173_i204
#CELL
  dev_discrete cap_a *
  page173_i205
#CELL
  dev_discrete cap_a *
  page173_i206
#CELL
  dev_discrete cap_a *
  page173_i207
#CELL
  dev_discrete cap_a *
  page173_i208
#CELL
  dev_discrete cap_a *
  page173_i209
#ISCELL
  mstr_standard tap *
  page173_i210
#ISCELL
  mstr_standard tap *
  page173_i211
#ISCELL
  mstr_standard tap *
  page173_i212
#ISCELL
  mstr_standard tap *
  page173_i213
#ISCELL
  mstr_standard tap *
  page173_i214
#ISCELL
  mstr_standard tap *
  page173_i215
#ISCELL
  mstr_standard tap *
  page173_i216
#ISCELL
  mstr_standard tap *
  page173_i217
#ISCELL
  mstr_standard tap *
  page173_i218
#ISCELL
  mstr_standard tap *
  page173_i219
#CELL
  dev_discrete cap_a *
  page173_i220
#CELL
  dev_discrete cap_a *
  page173_i221
#CELL
  dev_discrete cap_a *
  page173_i222
#ISCELL
  mstr_standard offpage *
  page173_i223
#ISCELL
  mstr_standard offpage *
  page173_i224
#CELL
  dev_discrete cap_a *
  page173_i228
#ISCELL
  mstr_standard tap *
  page173_i229
#ISCELL
  mstr_standard tap *
  page173_i230
#ISCELL
  mstr_standard tap *
  page173_i231
#ISCELL
  mstr_standard tap *
  page173_i232
#CELL
  dev_discrete cap_a *
  page173_i233
#CELL
  dev_discrete cap_a *
  page173_i234
#ISCELL
  mstr_standard tap *
  page173_i235
#ISCELL
  mstr_standard tap *
  page173_i236
#ISCELL
  mstr_standard tap *
  page173_i237
#CELL
  dev_discrete cap_a *
  page173_i238
#CELL
  dev_discrete cap_a *
  page173_i239
#CELL
  dev_discrete cap_a *
  page173_i240
#CELL
  dev_discrete cap_a *
  page173_i241
#CELL
  dev_discrete cap_a *
  page173_i242
#ISCELL
  mstr_standard tap *
  page173_i251
#ISCELL
  mstr_standard tap *
  page173_i252
#ISCELL
  mstr_standard tap *
  page173_i253
#ISCELL
  mstr_standard tap *
  page173_i254
#CELL
  dev_discrete cap_a *
  page173_i255
#CELL
  dev_discrete cap_a *
  page173_i256
#CELL
  dev_discrete cap_a *
  page173_i257
#CELL
  dev_discrete cap_a *
  page173_i258
#CELL
  dev_discrete cap_a *
  page173_i259
#ISCELL
  mstr_symbols p3v3 *
  page173_i260
#CELL
  mstr_discrete res *
  page173_i261
#ISCELL
  mstr_symbols p3v3 *
  page173_i262
#CELL
  mstr_discrete res *
  page173_i263
#CELL
  mstr_discrete res *
  page173_i264
#ISCELL
  mstr_symbols gnd *
  page173_i265
#CELL
  mstr_discrete res *
  page173_i266
#ISCELL
  mstr_symbols gnd *
  page173_i267
#ISCELL
  mstr_standard offpage *
  page173_i268
#ISCELL
  mstr_standard offpage *
  page173_i269
#ISCELL
  mstr_standard offpage *
  page173_i270
#ISCELL
  mstr_standard tap *
  page173_i271
#ISCELL
  mstr_symbols cad_note *
  *
#ISCELL
  mstr_symbols design_note *
  *
#ISCELL
  mstr_symbols intel_corp_bpage *
  *
#ISCELL
  mstr_standard offpage *
  page174_i1
#ISCELL
  mstr_standard tap *
  page174_i10
#ISCELL
  mstr_standard tap *
  page174_i11
#CELL
  dev_discrete cap_a *
  page174_i12
#CELL
  dev_discrete cap_a *
  page174_i13
#CELL
  dev_discrete cap_a *
  page174_i14
#ISCELL
  mstr_symbols gnd *
  page174_i15
#ISCELL
  mstr_standard tap *
  page174_i16
#ISCELL
  mstr_standard tap *
  page174_i17
#CELL
  dev_discrete cap_a *
  page174_i18
#CELL
  dev_discrete cap_a *
  page174_i19
#ISCELL
  mstr_standard offpage *
  page174_i2
#CELL
  dev_discrete cap_a *
  page174_i20
#ISCELL
  mstr_symbols gnd *
  page174_i21
#ISCELL
  mstr_standard offpage *
  page174_i22
#ISCELL
  mstr_standard offpage *
  page174_i23
#ISCELL
  mstr_symbols p3v3 *
  page174_i24
#CELL
  mstr_discrete res *
  page174_i25
#CELL
  mstr_conn conn36_g97614001 *
  page174_i26
#ISCELL
  mstr_symbols gnd *
  page174_i27
#CELL
  dev_discrete cap_a *
  page174_i28
#CELL
  dev_discrete cap_a *
  page174_i29
#ISCELL
  mstr_standard tap *
  page174_i3
#CELL
  dev_discrete cap_a *
  page174_i30
#CELL
  dev_discrete cap_a *
  page174_i31
#CELL
  dev_discrete cap_a *
  page174_i32
#ISCELL
  mstr_standard tap *
  page174_i33
#ISCELL
  mstr_standard tap *
  page174_i34
#ISCELL
  mstr_standard tap *
  page174_i35
#ISCELL
  mstr_standard tap *
  page174_i36
#ISCELL
  mstr_standard tap *
  page174_i37
#ISCELL
  mstr_standard tap *
  page174_i38
#CELL
  dev_discrete cap_a *
  page174_i39
#ISCELL
  mstr_standard tap *
  page174_i4
#CELL
  dev_discrete cap_a *
  page174_i40
#CELL
  dev_discrete cap_a *
  page174_i41
#ISCELL
  mstr_standard tap *
  page174_i42
#ISCELL
  mstr_standard tap *
  page174_i43
#ISCELL
  mstr_standard offpage *
  page174_i44
#ISCELL
  mstr_standard offpage *
  page174_i45
#ISCELL
  mstr_standard offpage *
  page174_i46
#CELL
  mstr_discrete res *
  page174_i5
#ISCELL
  mstr_standard tap *
  page174_i6
#ISCELL
  mstr_standard tap *
  page174_i7
#CELL
  dev_discrete cap_a *
  page174_i8
#CELL
  dev_discrete cap_a *
  page174_i9
#ISCELL
  mstr_misc dns *
  *
#ISCELL
  mstr_symbols cad_note *
  *
#ISCELL
  mstr_symbols intel_corp_bpage *
  *
#CELL
  mstr_ttl ttl2g14 *
  page175_i10
#CELL
  dev_discrete cap_a *
  page175_i11
#ISCELL
  mstr_symbols gnd *
  page175_i12
#CELL
  mstr_discrete res *
  page175_i13
#ISCELL
  mstr_standard offpage *
  page175_i14
#CELL
  mstr_ttl ttl2g14 *
  page175_i15
#CELL
  mstr_ttl ttl2g14 *
  page175_i18
#CELL
  dev_discrete cap_a *
  page175_i19
#ISCELL
  mstr_symbols gnd *
  page175_i20
#ISCELL
  mstr_symbols p3v3_stby *
  page175_i21
#CELL
  mstr_discrete res *
  page175_i22
#CELL
  mstr_discrete res *
  page175_i24
#ISCELL
  mstr_symbols gnd *
  page175_i27
#ISCELL
  mstr_standard offpage *
  page175_i28
#ISCELL
  mstr_symbols gnd *
  page175_i3
#CELL
  mstr_discrete res *
  page175_i35
#ISCELL
  mstr_standard offpage *
  page175_i36
#CELL
  dev_discrete cap_a *
  page175_i37
#CELL
  dev_discrete cap_a *
  page175_i38
#CELL
  mstr_discrete res *
  page175_i4
#CELL
  dev_discrete cap_a *
  page175_i40
#ISCELL
  mstr_symbols gnd *
  page175_i41
#ISCELL
  mstr_symbols gnd *
  page175_i42
#ISCELL
  mstr_symbols p3v3_stby *
  page175_i43
#ISCELL
  mstr_symbols p3v3_stby *
  page175_i44
#CELL
  mstr_discrete res *
  page175_i45
#CELL
  mstr_discrete fet_n *
  page175_i49
#CELL
  mstr_discrete res *
  page175_i5
#CELL
  mstr_discrete led *
  page175_i50
#ISCELL
  mstr_standard offpage *
  page175_i52
#ISCELL
  mstr_symbols gnd *
  page175_i54
#CELL
  mstr_ttl ttl1g86 *
  page175_i57
#CELL
  mstr_discrete res *
  page175_i58
#ISCELL
  mstr_symbols p5v_stby *
  page175_i59
#ISCELL
  mstr_symbols p3v3_stby *
  page175_i6
#ISCELL
  mstr_standard offpage *
  page175_i61
#ISCELL
  mstr_standard offpage *
  page175_i62
#CELL
  mstr_discrete res *
  page175_i63
#CELL
  dev_discrete cap_a *
  page175_i64
#ISCELL
  mstr_symbols gnd *
  page175_i66
#CELL
  mstr_discrete led *
  page175_i67
#ISCELL
  mstr_symbols p3v3_stby *
  page175_i70
#ISCELL
  mstr_symbols gnd *
  page175_i71
#CELL
  mstr_misc switch_d37771002 *
  page175_i78
#CELL
  mstr_misc sw_h67881001 *
  page175_i84
#ISCELL
  mstr_symbols p3v3_stby *
  page175_i85
#ISCELL
  mstr_symbols p5v_stby *
  page175_i86
#ISCELL
  mstr_standard offpage *
  page175_i87
#ISCELL
  mstr_standard offpage *
  page175_i88
#CELL
  w_hdl 0r2j-l-gp *
  page175_i89
#CELL
  mstr_ttl ttl2g14 *
  page175_i9
#ISCELL
  mstr_misc dns *
  *
#ISCELL
  mstr_symbols cad_note *
  *
#ISCELL
  mstr_symbols design_note *
  *
#ISCELL
  mstr_symbols intel_corp_bpage *
  *
#CELL
  mstr_vreg tps2061 *
  page176_i100
#ISCELL
  mstr_symbols p5v *
  page176_i101
#ISCELL
  mstr_symbols gnd *
  page176_i102
#ISCELL
  mstr_standard offpage *
  page176_i103
#ISCELL
  mstr_standard offpage *
  page176_i104
#CELL
  mstr_discrete res *
  page176_i105
#ISCELL
  mstr_standard offpage *
  page176_i107
#CELL
  dev_discrete cap_a *
  page176_i108
#ISCELL
  mstr_symbols gnd *
  page176_i109
#ISCELL
  mstr_symbols p3v3_stby *
  page176_i110
#CELL
  mstr_discrete res *
  page176_i111
#ISCELL
  mstr_symbols gnd *
  page176_i112
#CELL
  mstr_discrete capp *
  page176_i113
#ISCELL
  mstr_symbols gnd *
  page176_i114
#ISCELL
  mstr_standard offpage *
  page176_i119
#ISCELL
  mstr_standard offpage *
  page176_i120
#ISCELL
  mstr_standard offpage *
  page176_i121
#CELL
  mstr_ttl ttl1g08 *
  page176_i122
#ISCELL
  mstr_standard offpage *
  page176_i123
#CELL
  mstr_discrete cap *
  page176_i124
#ISCELL
  mstr_symbols gnd *
  page176_i125
#ISCELL
  mstr_symbols p3v3_stby *
  page176_i126
#ISCELL
  mstr_standard offpage *
  page176_i127
#ISCELL
  mstr_standard offpage *
  page176_i128
#ISCELL
  mstr_standard offpage *
  page176_i129
#CELL
  mstr_discrete res *
  page176_i16
#CELL
  mstr_discrete choke_4pin *
  page176_i30
#CELL
  mstr_discrete res *
  page176_i31
#ISCELL
  mstr_standard offpage *
  page176_i46
#ISCELL
  mstr_standard offpage *
  page176_i47
#CELL
  mstr_conn conn9_h51826001 *
  page176_i69
#ISCELL
  mstr_symbols gnd *
  page176_i70
#ISCELL
  mstr_symbols gnd *
  page176_i71
#ISCELL
  mstr_standard offpage *
  page176_i75
#CELL
  mstr_discrete diodeac_dual_array *
  page176_i98
#ISCELL
  mstr_symbols gnd *
  page176_i99
#ISCELL
  mstr_symbols cad_note *
  *
#ISCELL
  mstr_symbols intel_corp_bpage *
  *
#ISCELL
  mstr_standard offpage *
  page177_i1
#ISCELL
  mstr_symbols p3v3 *
  page177_i10
#CELL
  dev_discrete cap_a *
  page177_i20
#CELL
  mstr_discrete res *
  page177_i3
#ISCELL
  mstr_symbols gnd *
  page177_i30
#CELL
  mstr_discrete led *
  page177_i31
#CELL
  mstr_discrete res *
  page177_i33
#ISCELL
  mstr_symbols p5v_stby *
  page177_i36
#ISCELL
  mstr_standard offpage *
  page177_i4
#CELL
  mstr_discrete led *
  page177_i42
#CELL
  mstr_discrete res *
  page177_i43
#ISCELL
  mstr_symbols p3v3 *
  page177_i45
#ISCELL
  mstr_symbols gnd *
  page177_i46
#CELL
  mstr_discrete res *
  page177_i6
#CELL
  mstr_ttl ttl1g08 *
  page177_i70
#CELL
  mstr_discrete led *
  page177_i71
#CELL
  mstr_discrete res *
  page177_i72
#ISCELL
  mstr_symbols gnd *
  page177_i74
#CELL
  mstr_discrete res *
  page177_i76
#ISCELL
  mstr_symbols p3v3_stby *
  page177_i77
#ISCELL
  mstr_symbols p3v3_stby *
  page177_i78
#CELL
  mstr_discrete fet_n_dual *
  page177_i79
#CELL
  mstr_discrete res *
  page177_i8
#CELL
  mstr_discrete fet_n_dual *
  page177_i80
#ISCELL
  mstr_symbols p3v3_stby *
  page177_i81
#CELL
  mstr_discrete res *
  page177_i82
#ISCELL
  mstr_symbols gnd *
  page177_i83
#ISCELL
  mstr_standard offpage *
  page177_i84
#ISCELL
  mstr_symbols p3v3 *
  page177_i85
#CELL
  mstr_discrete res *
  page177_i9
#ISCELL
  mstr_symbols design_note *
  *
#ISCELL
  mstr_symbols intel_corp_bpage *
  *
#CELL
  mstr_discrete res *
  page178_i1
#ISCELL
  mstr_standard offpage *
  page178_i10
#CELL
  mstr_discrete res *
  page178_i11
#CELL
  mstr_discrete res *
  page178_i12
#CELL
  mstr_discrete res *
  page178_i13
#ISCELL
  mstr_standard offpage *
  page178_i14
#ISCELL
  mstr_standard offpage *
  page178_i15
#ISCELL
  mstr_standard offpage *
  page178_i16
#CELL
  mstr_discrete res *
  page178_i17
#CELL
  mstr_discrete res *
  page178_i18
#ISCELL
  mstr_symbols p3v3_stby *
  page178_i19
#CELL
  mstr_discrete res *
  page178_i2
#CELL
  mstr_discrete res *
  page178_i20
#CELL
  mstr_discrete res *
  page178_i21
#CELL
  mstr_discrete res *
  page178_i22
#CELL
  mstr_discrete res *
  page178_i23
#ISCELL
  mstr_standard offpage *
  page178_i24
#ISCELL
  mstr_standard offpage *
  page178_i25
#ISCELL
  mstr_standard offpage *
  page178_i26
#ISCELL
  mstr_standard offpage *
  page178_i3
#ISCELL
  mstr_standard offpage *
  page178_i4
#ISCELL
  mstr_symbols p3v3_stby *
  page178_i5
#ISCELL
  mstr_standard offpage *
  page178_i6
#ISCELL
  mstr_standard offpage *
  page178_i7
#CELL
  mstr_discrete res *
  page178_i8
#ISCELL
  mstr_standard offpage *
  page178_i9
#ISCELL
  mstr_symbols intel_corp_bpage *
  *
#ISCELL
  mstr_symbols intel_corp_bpage *
  *
#ISCELL
  mstr_misc dns *
  *
#ISCELL
  mstr_symbols cad_note *
  *
#ISCELL
  mstr_symbols design_note *
  *
#ISCELL
  mstr_symbols intel_corp_bpage *
  *
#CELL
  mstr_conn conn76_h22707001 *
  page181_i111
#ISCELL
  mstr_symbols gnd *
  page181_i112
#ISCELL
  mstr_standard tap *
  page181_i113
#ISCELL
  mstr_standard tap *
  page181_i114
#ISCELL
  mstr_standard tap *
  page181_i115
#ISCELL
  mstr_standard tap *
  page181_i116
#ISCELL
  mstr_standard tap *
  page181_i117
#ISCELL
  mstr_standard tap *
  page181_i118
#ISCELL
  mstr_standard tap *
  page181_i119
#ISCELL
  mstr_standard tap *
  page181_i120
#ISCELL
  mstr_standard tap *
  page181_i121
#ISCELL
  mstr_standard tap *
  page181_i122
#ISCELL
  mstr_standard tap *
  page181_i123
#ISCELL
  mstr_standard tap *
  page181_i124
#ISCELL
  mstr_standard tap *
  page181_i125
#ISCELL
  mstr_standard tap *
  page181_i126
#ISCELL
  mstr_standard tap *
  page181_i127
#ISCELL
  mstr_standard tap *
  page181_i128
#ISCELL
  mstr_standard tap *
  page181_i129
#ISCELL
  mstr_standard tap *
  page181_i130
#ISCELL
  mstr_standard tap *
  page181_i131
#ISCELL
  mstr_standard tap *
  page181_i132
#ISCELL
  mstr_standard offpage *
  page181_i133
#ISCELL
  mstr_standard offpage *
  page181_i134
#ISCELL
  mstr_standard offpage *
  page181_i138
#ISCELL
  mstr_standard offpage *
  page181_i139
#ISCELL
  mstr_standard offpage *
  page181_i140
#ISCELL
  mstr_standard offpage *
  page181_i141
#ISCELL
  mstr_standard offpage *
  page181_i142
#ISCELL
  mstr_standard offpage *
  page181_i143
#ISCELL
  mstr_standard offpage *
  page181_i144
#ISCELL
  mstr_standard offpage *
  page181_i145
#ISCELL
  mstr_standard offpage *
  page181_i146
#ISCELL
  mstr_standard offpage *
  page181_i152
#ISCELL
  mstr_standard offpage *
  page181_i157
#ISCELL
  mstr_standard offpage *
  page181_i158
#ISCELL
  mstr_standard offpage *
  page181_i159
#CELL
  mstr_discrete cap *
  page181_i160
#CELL
  mstr_discrete cap *
  page181_i161
#CELL
  mstr_discrete cap *
  page181_i162
#CELL
  mstr_discrete cap *
  page181_i163
#CELL
  mstr_discrete cap *
  page181_i164
#CELL
  mstr_discrete cap *
  page181_i165
#CELL
  mstr_discrete cap *
  page181_i166
#CELL
  mstr_discrete cap *
  page181_i167
#CELL
  mstr_discrete cap *
  page181_i168
#CELL
  mstr_discrete cap *
  page181_i169
#CELL
  mstr_discrete cap *
  page181_i170
#CELL
  mstr_discrete cap *
  page181_i171
#CELL
  mstr_discrete cap *
  page181_i172
#CELL
  mstr_discrete cap *
  page181_i173
#CELL
  mstr_discrete cap *
  page181_i174
#CELL
  mstr_discrete cap *
  page181_i175
#ISCELL
  mstr_symbols p12v_psu *
  page181_i176
#CELL
  mstr_discrete res *
  page181_i177
#CELL
  mstr_discrete diode *
  page181_i178
#ISCELL
  mstr_standard offpage *
  page181_i179
#CELL
  mstr_discrete diode *
  page181_i180
#CELL
  mstr_discrete npn *
  page181_i181
#ISCELL
  mstr_symbols gnd *
  page181_i182
#CELL
  mstr_discrete res *
  page181_i183
#ISCELL
  mstr_symbols p12v_psu *
  page181_i184
#CELL
  mstr_discrete res *
  page181_i185
#ISCELL
  mstr_symbols gnd *
  page181_i186
#ISCELL
  mstr_standard offpage *
  page181_i187
#CELL
  mstr_conn conn8_h62179001 *
  page181_i189
#ISCELL
  mstr_symbols gnd *
  page181_i191
#ISCELL
  mstr_standard offpage *
  page181_i192
#ISCELL
  mstr_standard offpage *
  page181_i193
#ISCELL
  mstr_standard offpage *
  page181_i194
#ISCELL
  mstr_standard offpage *
  page181_i195
#ISCELL
  mstr_symbols p3v3_stby *
  page181_i198
#CELL
  mstr_discrete res *
  page181_i199
#CELL
  mstr_discrete res *
  page181_i200
#CELL
  mstr_discrete res *
  page181_i201
#ISCELL
  mstr_standard offpage *
  page181_i202
#ISCELL
  mstr_standard offpage *
  page181_i203
#ISCELL
  mstr_standard offpage *
  page181_i204
#CELL
  mstr_discrete res *
  page181_i218
#ISCELL
  mstr_standard offpage *
  page181_i221
#ISCELL
  mstr_standard offpage *
  page181_i222
#ISCELL
  mstr_standard offpage *
  page181_i223
#CELL
  mstr_discrete cap *
  page181_i224
#ISCELL
  mstr_symbols gnd *
  page181_i225
#ISCELL
  mstr_symbols p3v3_stby *
  page181_i227
#ISCELL
  mstr_standard offpage *
  page181_i239
#ISCELL
  mstr_standard offpage *
  page181_i241
#CELL
  mstr_ttl ttl08 *
  page181_i243
#ISCELL
  mstr_standard offpage *
  page181_i244
#ISCELL
  mstr_standard offpage *
  page181_i245
#ISCELL
  mstr_standard offpage *
  page181_i246
#ISCELL
  mstr_symbols gnd *
  page181_i248
#ISCELL
  mstr_standard offpage *
  page181_i250
#ISCELL
  mstr_symbols p3v3_stby *
  page181_i251
#ISCELL
  mstr_symbols gnd *
  page181_i252
#CELL
  dev_discrete cap_a *
  page181_i253
#CELL
  mstr_discrete res *
  page181_i254
#CELL
  mstr_discrete res *
  page181_i255
#CELL
  mstr_discrete res *
  page181_i256
#ISCELL
  mstr_standard offpage *
  page181_i257
#ISCELL
  mstr_standard offpage *
  page181_i258
#ISCELL
  mstr_standard offpage *
  page181_i259
#CELL
  mstr_discrete res *
  page181_i261
#ISCELL
  mstr_standard offpage *
  page181_i262
#ISCELL
  mstr_standard offpage *
  page181_i263
#ISCELL
  mstr_standard offpage *
  page181_i264
#ISCELL
  mstr_standard offpage *
  page181_i265
#ISCELL
  mstr_standard offpage *
  page181_i266
#ISCELL
  mstr_standard offpage *
  page181_i267
#CELL
  mstr_discrete res *
  page181_i268
#ISCELL
  mstr_standard offpage *
  page181_i269
#ISCELL
  mstr_standard offpage *
  page181_i272
#ISCELL
  mstr_standard offpage *
  page181_i273
#ISCELL
  mstr_standard offpage *
  page181_i274
#ISCELL
  mstr_standard offpage *
  page181_i275
#CELL
  mstr_discrete res *
  page181_i278
#CELL
  mstr_discrete res *
  page181_i279
#CELL
  mstr_discrete res *
  page181_i280
#CELL
  mstr_discrete res *
  page181_i281
#CELL
  mstr_discrete res *
  page181_i282
#ISCELL
  mstr_symbols gnd *
  page181_i45
#ISCELL
  mstr_standard tap *
  page181_i47
#ISCELL
  mstr_standard tap *
  page181_i48
#ISCELL
  mstr_standard tap *
  page181_i49
#ISCELL
  mstr_standard tap *
  page181_i50
#ISCELL
  mstr_standard tap *
  page181_i53
#ISCELL
  mstr_standard tap *
  page181_i54
#ISCELL
  mstr_standard tap *
  page181_i57
#ISCELL
  mstr_standard tap *
  page181_i58
#ISCELL
  mstr_standard tap *
  page181_i67
#ISCELL
  mstr_standard tap *
  page181_i68
#ISCELL
  mstr_standard tap *
  page181_i69
#ISCELL
  mstr_standard tap *
  page181_i70
#ISCELL
  mstr_misc dns *
  *
#ISCELL
  mstr_symbols design_note *
  *
#ISCELL
  mstr_symbols intel_corp_bpage *
  *
#ISCELL
  mstr_standard offpage *
  page182_i100
#CELL
  mstr_discrete res *
  page182_i101
#ISCELL
  mstr_standard offpage *
  page182_i102
#ISCELL
  mstr_standard offpage *
  page182_i103
#CELL
  mstr_discrete res *
  page182_i104
#ISCELL
  mstr_standard offpage *
  page182_i105
#ISCELL
  mstr_standard offpage *
  page182_i106
#CELL
  mstr_discrete res *
  page182_i107
#ISCELL
  mstr_standard offpage *
  page182_i108
#ISCELL
  mstr_standard offpage *
  page182_i109
#CELL
  mstr_discrete res *
  page182_i110
#ISCELL
  mstr_standard offpage *
  page182_i111
#CELL
  mstr_discrete cap *
  page182_i12
#CELL
  mstr_discrete cap *
  page182_i13
#CELL
  mstr_discrete cap *
  page182_i14
#CELL
  mstr_discrete cap *
  page182_i15
#CELL
  mstr_discrete cap *
  page182_i16
#ISCELL
  mstr_symbols gnd *
  page182_i17
#CELL
  mstr_conn conn76_h22707001 *
  page182_i18
#ISCELL
  mstr_symbols gnd *
  page182_i19
#ISCELL
  mstr_standard tap *
  page182_i2
#ISCELL
  mstr_standard offpage *
  page182_i29
#ISCELL
  mstr_standard offpage *
  page182_i30
#ISCELL
  mstr_standard tap *
  page182_i4
#ISCELL
  mstr_standard tap *
  page182_i41
#ISCELL
  mstr_standard tap *
  page182_i42
#ISCELL
  mstr_standard tap *
  page182_i43
#ISCELL
  mstr_standard tap *
  page182_i44
#ISCELL
  mstr_standard tap *
  page182_i45
#ISCELL
  mstr_standard tap *
  page182_i46
#ISCELL
  mstr_standard tap *
  page182_i47
#ISCELL
  mstr_standard tap *
  page182_i48
#CELL
  mstr_discrete cap *
  page182_i49
#ISCELL
  mstr_standard tap *
  page182_i5
#CELL
  mstr_discrete cap *
  page182_i50
#CELL
  mstr_discrete cap *
  page182_i51
#CELL
  mstr_discrete cap *
  page182_i52
#CELL
  mstr_discrete cap *
  page182_i53
#CELL
  mstr_discrete cap *
  page182_i54
#CELL
  mstr_discrete cap *
  page182_i55
#CELL
  mstr_discrete cap *
  page182_i56
#ISCELL
  mstr_standard tap *
  page182_i57
#ISCELL
  mstr_standard tap *
  page182_i58
#ISCELL
  mstr_standard tap *
  page182_i59
#ISCELL
  mstr_standard tap *
  page182_i6
#ISCELL
  mstr_standard tap *
  page182_i60
#ISCELL
  mstr_standard tap *
  page182_i61
#ISCELL
  mstr_standard tap *
  page182_i62
#ISCELL
  mstr_standard tap *
  page182_i63
#ISCELL
  mstr_standard tap *
  page182_i64
#ISCELL
  mstr_standard offpage *
  page182_i65
#ISCELL
  mstr_standard offpage *
  page182_i66
#ISCELL
  mstr_standard tap *
  page182_i67
#ISCELL
  mstr_standard tap *
  page182_i68
#ISCELL
  mstr_standard tap *
  page182_i69
#ISCELL
  mstr_standard tap *
  page182_i7
#ISCELL
  mstr_standard tap *
  page182_i70
#ISCELL
  mstr_standard tap *
  page182_i71
#ISCELL
  mstr_standard tap *
  page182_i72
#ISCELL
  mstr_standard tap *
  page182_i73
#ISCELL
  mstr_standard tap *
  page182_i74
#ISCELL
  mstr_standard tap *
  page182_i8
#CELL
  mstr_discrete cap *
  page182_i81
#ISCELL
  mstr_standard tap *
  page182_i82
#CELL
  mstr_discrete cap *
  page182_i83
#ISCELL
  mstr_standard tap *
  page182_i84
#ISCELL
  mstr_standard offpage *
  page182_i85
#ISCELL
  mstr_standard offpage *
  page182_i86
#ISCELL
  mstr_standard offpage *
  page182_i87
#CELL
  mstr_discrete cap *
  page182_i9
#ISCELL
  mstr_standard offpage *
  page182_i91
#ISCELL
  mstr_standard offpage *
  page182_i92
#ISCELL
  mstr_standard offpage *
  page182_i94
#ISCELL
  mstr_standard offpage *
  page182_i95
#ISCELL
  mstr_standard offpage *
  page182_i96
#CELL
  mstr_discrete res *
  page182_i97
#ISCELL
  mstr_standard offpage *
  page182_i98
#ISCELL
  mstr_standard offpage *
  page182_i99
#ISCELL
  mstr_misc dns *
  *
#ISCELL
  mstr_symbols design_note *
  *
#ISCELL
  mstr_symbols intel_corp_bpage *
  *
#CELL
  mstr_controller pi7c9x1172 *
  page183_i1
#ISCELL
  mstr_symbols gnd *
  page183_i10
#CELL
  mstr_discrete res *
  page183_i11
#CELL
  mstr_discrete res *
  page183_i12
#CELL
  mstr_discrete res *
  page183_i13
#CELL
  mstr_discrete res *
  page183_i14
#ISCELL
  mstr_symbols p3v3_stby *
  page183_i15
#ISCELL
  mstr_symbols p3v3_stby *
  page183_i16
#ISCELL
  mstr_symbols gnd *
  page183_i17
#ISCELL
  mstr_symbols gnd *
  page183_i18
#CELL
  mstr_discrete crystal *
  page183_i19
#ISCELL
  mstr_standard offpage *
  page183_i2
#CELL
  mstr_discrete cap *
  page183_i20
#CELL
  mstr_discrete cap *
  page183_i21
#ISCELL
  mstr_symbols gnd *
  page183_i22
#ISCELL
  mstr_symbols gnd *
  page183_i23
#CELL
  mstr_discrete res *
  page183_i24
#CELL
  mstr_discrete res *
  page183_i25
#ISCELL
  mstr_standard offpage *
  page183_i3
#CELL
  mstr_discrete res *
  page183_i30
#ISCELL
  mstr_symbols p3v3_stby *
  page183_i31
#ISCELL
  mstr_symbols gnd *
  page183_i32
#CELL
  mstr_discrete res *
  page183_i4
#CELL
  mstr_discrete res *
  page183_i48
#CELL
  mstr_discrete res *
  page183_i49
#ISCELL
  mstr_symbols p3v3_stby *
  page183_i5
#ISCELL
  mstr_standard offpage *
  page183_i50
#ISCELL
  mstr_standard offpage *
  page183_i51
#CELL
  mstr_discrete res *
  page183_i52
#CELL
  mstr_discrete res *
  page183_i53
#ISCELL
  mstr_standard offpage *
  page183_i54
#ISCELL
  mstr_standard offpage *
  page183_i55
#ISCELL
  mstr_standard offpage *
  page183_i56
#ISCELL
  mstr_standard offpage *
  page183_i57
#ISCELL
  mstr_symbols p3v3_stby *
  page183_i6
#CELL
  dev_discrete cap_a *
  page183_i7
#ISCELL
  mstr_symbols gnd *
  page183_i8
#ISCELL
  mstr_symbols cad_note *
  *
#ISCELL
  mstr_symbols intel_corp_bpage *
  *
#ISCELL
  mstr_standard offpage *
  page184_i100
#ISCELL
  mstr_symbols gnd *
  page184_i101
#ISCELL
  mstr_standard offpage *
  page184_i102
#ISCELL
  mstr_standard offpage *
  page184_i103
#CELL
  mstr_misc standoff *
  page184_i104
#ISCELL
  mstr_symbols gnd *
  page184_i105
#CELL
  mstr_sconn sconn11_h67026001 *
  page184_i87
#CELL
  mstr_discrete res *
  page184_i88
#ISCELL
  mstr_standard offpage *
  page184_i89
#ISCELL
  mstr_standard offpage *
  page184_i90
#ISCELL
  mstr_standard offpage *
  page184_i91
#CELL
  mstr_discrete res *
  page184_i92
#CELL
  mstr_discrete res *
  page184_i93
#ISCELL
  mstr_standard offpage *
  page184_i94
#CELL
  mstr_discrete res *
  page184_i95
#ISCELL
  mstr_standard offpage *
  page184_i96
#ISCELL
  mstr_symbols p3v3_stby *
  page184_i97
#ISCELL
  mstr_standard offpage *
  page184_i98
#CELL
  mstr_discrete res *
  page184_i99
#ISCELL
  mstr_misc dns *
  *
#ISCELL
  mstr_symbols cad_note *
  *
#ISCELL
  mstr_symbols design_note *
  *
#ISCELL
  mstr_symbols intel_corp_bpage *
  *
#ISCELL
  mstr_standard offpage *
  page185_i100
#ISCELL
  mstr_standard offpage *
  page185_i101
#ISCELL
  mstr_standard offpage *
  page185_i102
#ISCELL
  mstr_standard offpage *
  page185_i103
#ISCELL
  mstr_standard offpage *
  page185_i104
#CELL
  mstr_discrete res *
  page185_i105
#CELL
  mstr_discrete res *
  page185_i106
#ISCELL
  mstr_standard offpage *
  page185_i107
#ISCELL
  mstr_standard offpage *
  page185_i108
#ISCELL
  mstr_standard offpage *
  page185_i109
#CELL
  mstr_ttl ttl1g07_a *
  page185_i110
#CELL
  mstr_discrete res *
  page185_i111
#ISCELL
  mstr_symbols p3v3 *
  page185_i112
#CELL
  mstr_discrete res *
  page185_i113
#ISCELL
  mstr_symbols p3v3_stby *
  page185_i114
#CELL
  mstr_discrete res *
  page185_i115
#ISCELL
  mstr_standard offpage *
  page185_i116
#CELL
  dev_discrete cap_a *
  page185_i117
#ISCELL
  mstr_symbols p3v3_stby *
  page185_i118
#ISCELL
  mstr_symbols gnd *
  page185_i119
#CELL
  dev_discrete cap_a *
  page185_i120
#ISCELL
  mstr_symbols gnd *
  page185_i122
#CELL
  dev_discrete cap_a *
  page185_i123
#CELL
  dev_discrete cap_a *
  page185_i124
#ISCELL
  mstr_symbols p3v3 *
  page185_i125
#CELL
  dev_discrete cap_a *
  page185_i126
#CELL
  dev_discrete cap_a *
  page185_i127
#ISCELL
  mstr_symbols p3v3 *
  page185_i128
#CELL
  dev_discrete cap_a *
  page185_i129
#ISCELL
  mstr_symbols gnd *
  page185_i130
#CELL
  dev_discrete cap_a *
  page185_i131
#CELL
  dev_discrete cap_a *
  page185_i132
#ISCELL
  mstr_symbols p3v3 *
  page185_i133
#ISCELL
  mstr_symbols gnd *
  page185_i134
#CELL
  dev_discrete cap_a *
  page185_i135
#CELL
  mstr_discrete res *
  page185_i136
#ISCELL
  mstr_symbols p3v3 *
  page185_i137
#CELL
  mstr_sconn sconn75k_h17033002 *
  page185_i53
#ISCELL
  mstr_symbols gnd *
  page185_i54
#ISCELL
  mstr_symbols p3v3 *
  page185_i55
#CELL
  mstr_discrete cap *
  page185_i62
#CELL
  mstr_discrete cap *
  page185_i63
#CELL
  mstr_discrete cap *
  page185_i64
#CELL
  mstr_discrete cap *
  page185_i65
#CELL
  mstr_discrete cap *
  page185_i66
#CELL
  mstr_discrete cap *
  page185_i67
#ISCELL
  mstr_standard offpage *
  page185_i68
#ISCELL
  mstr_standard offpage *
  page185_i69
#ISCELL
  mstr_standard offpage *
  page185_i70
#ISCELL
  mstr_standard offpage *
  page185_i71
#ISCELL
  mstr_standard offpage *
  page185_i72
#ISCELL
  mstr_standard offpage *
  page185_i73
#ISCELL
  mstr_standard offpage *
  page185_i74
#ISCELL
  mstr_standard offpage *
  page185_i75
#ISCELL
  mstr_standard offpage *
  page185_i76
#ISCELL
  mstr_standard offpage *
  page185_i77
#ISCELL
  mstr_standard offpage *
  page185_i78
#ISCELL
  mstr_standard offpage *
  page185_i79
#ISCELL
  mstr_standard offpage *
  page185_i80
#ISCELL
  mstr_standard offpage *
  page185_i81
#ISCELL
  mstr_standard offpage *
  page185_i82
#ISCELL
  mstr_standard offpage *
  page185_i83
#ISCELL
  mstr_standard offpage *
  page185_i85
#ISCELL
  mstr_standard offpage *
  page185_i86
#ISCELL
  mstr_standard offpage *
  page185_i87
#ISCELL
  mstr_standard offpage *
  page185_i89
#CELL
  dev_discrete cap_a *
  page185_i90
#ISCELL
  mstr_standard offpage *
  page185_i91
#ISCELL
  mstr_standard offpage *
  page185_i92
#ISCELL
  mstr_standard offpage *
  page185_i93
#ISCELL
  mstr_standard offpage *
  page185_i94
#CELL
  dev_discrete cap_a *
  page185_i95
#CELL
  mstr_discrete cap *
  page185_i96
#CELL
  dev_discrete cap_a *
  page185_i97
#CELL
  mstr_discrete cap *
  page185_i98
#CELL
  dev_discrete cap_a *
  page185_i99
#ISCELL
  mstr_symbols cad_note *
  *
#ISCELL
  mstr_symbols design_note *
  *
#ISCELL
  mstr_symbols intel_corp_bpage *
  *
#CELL
  dev_discrete cap_a *
  page186_i10
#ISCELL
  mstr_symbols gnd *
  page186_i14
#ISCELL
  mstr_symbols gnd *
  page186_i192
#ISCELL
  mstr_symbols gnd *
  page186_i193
#ISCELL
  mstr_symbols p3v3 *
  page186_i195
#ISCELL
  mstr_standard offpage *
  page186_i217
#CELL
  mstr_discrete res *
  page186_i220
#ISCELL
  mstr_standard offpage *
  page186_i221
#CELL
  mstr_discrete res *
  page186_i222
#ISCELL
  mstr_symbols gnd *
  page186_i223
#ISCELL
  mstr_standard offpage *
  page186_i227
#ISCELL
  mstr_standard offpage *
  page186_i228
#ISCELL
  mstr_standard offpage *
  page186_i229
#ISCELL
  mstr_standard offpage *
  page186_i233
#ISCELL
  mstr_standard offpage *
  page186_i234
#ISCELL
  mstr_symbols p3v3 *
  page186_i247
#ISCELL
  mstr_standard offpage *
  page186_i249
#ISCELL
  mstr_standard offpage *
  page186_i250
#ISCELL
  mstr_standard offpage *
  page186_i251
#ISCELL
  mstr_standard offpage *
  page186_i252
#ISCELL
  mstr_standard offpage *
  page186_i254
#ISCELL
  mstr_standard offpage *
  page186_i255
#ISCELL
  mstr_standard offpage *
  page186_i256
#ISCELL
  mstr_standard offpage *
  page186_i257
#ISCELL
  mstr_standard offpage *
  page186_i267
#ISCELL
  mstr_symbols p3v3 *
  page186_i268
#ISCELL
  mstr_symbols gnd *
  page186_i269
#CELL
  dev_discrete cap_a *
  page186_i270
#ISCELL
  mstr_symbols p3v3_stby *
  page186_i274
#ISCELL
  mstr_symbols p3v3_stby *
  page186_i275
#ISCELL
  mstr_symbols p5v_stby *
  page186_i276
#ISCELL
  mstr_symbols p12v_stby *
  page186_i278
#ISCELL
  mstr_symbols p12v_stby *
  page186_i279
#ISCELL
  mstr_symbols p3v3_stby *
  page186_i296
#ISCELL
  mstr_standard tap *
  page186_i297
#ISCELL
  mstr_standard tap *
  page186_i298
#ISCELL
  mstr_standard tap *
  page186_i299
#CELL
  mstr_discrete cap *
  page186_i3
#ISCELL
  mstr_standard tap *
  page186_i300
#ISCELL
  mstr_standard tap *
  page186_i301
#ISCELL
  mstr_standard tap *
  page186_i302
#ISCELL
  mstr_standard tap *
  page186_i303
#ISCELL
  mstr_standard tap *
  page186_i304
#ISCELL
  mstr_standard tap *
  page186_i305
#ISCELL
  mstr_standard tap *
  page186_i306
#ISCELL
  mstr_standard tap *
  page186_i307
#ISCELL
  mstr_standard tap *
  page186_i308
#ISCELL
  mstr_standard tap *
  page186_i309
#ISCELL
  mstr_standard tap *
  page186_i310
#ISCELL
  mstr_standard tap *
  page186_i311
#ISCELL
  mstr_standard tap *
  page186_i312
#ISCELL
  mstr_standard offpage *
  page186_i313
#ISCELL
  mstr_standard offpage *
  page186_i314
#ISCELL
  mstr_standard tap *
  page186_i315
#ISCELL
  mstr_standard tap *
  page186_i316
#ISCELL
  mstr_standard tap *
  page186_i317
#ISCELL
  mstr_standard tap *
  page186_i318
#ISCELL
  mstr_standard offpage *
  page186_i320
#ISCELL
  mstr_standard tap *
  page186_i321
#ISCELL
  mstr_standard tap *
  page186_i322
#ISCELL
  mstr_standard tap *
  page186_i323
#ISCELL
  mstr_standard tap *
  page186_i324
#ISCELL
  mstr_standard tap *
  page186_i325
#ISCELL
  mstr_standard tap *
  page186_i326
#ISCELL
  mstr_standard tap *
  page186_i327
#ISCELL
  mstr_standard tap *
  page186_i328
#ISCELL
  mstr_standard tap *
  page186_i329
#ISCELL
  mstr_standard tap *
  page186_i330
#ISCELL
  mstr_standard tap *
  page186_i331
#ISCELL
  mstr_standard tap *
  page186_i332
#ISCELL
  mstr_standard offpage *
  page186_i333
#CELL
  dev_discrete cap_a *
  page186_i334
#CELL
  dev_discrete cap_a *
  page186_i335
#CELL
  mstr_sconn sconn120_a28699018 *
  page186_i336
#CELL
  mstr_discrete res *
  page186_i337
#CELL
  mstr_discrete res *
  page186_i338
#CELL
  mstr_discrete res *
  page186_i339
#CELL
  mstr_discrete res *
  page186_i340
#ISCELL
  mstr_standard offpage *
  page186_i341
#ISCELL
  mstr_standard offpage *
  page186_i342
#ISCELL
  mstr_standard offpage *
  page186_i343
#ISCELL
  mstr_standard offpage *
  page186_i344
#CELL
  dev_discrete cap_a *
  page186_i345
#ISCELL
  mstr_symbols gnd *
  page186_i346
#CELL
  dev_discrete cap_a *
  page186_i347
#ISCELL
  mstr_symbols p5v_stby *
  page186_i348
#CELL
  mstr_discrete cap *
  page186_i6
#CELL
  dev_discrete cap_a *
  page186_i7
#CELL
  dev_discrete cap_a *
  page186_i8
#ISCELL
  mstr_symbols gnd *
  page186_i9
#ISCELL
  mstr_symbols design_note *
  *
#ISCELL
  mstr_symbols intel_corp_bpage *
  *
#ISCELL
  mstr_standard offpage *
  page187_i100
#ISCELL
  mstr_standard tap *
  page187_i111
#ISCELL
  mstr_standard tap *
  page187_i112
#ISCELL
  mstr_standard tap *
  page187_i113
#ISCELL
  mstr_standard tap *
  page187_i114
#ISCELL
  mstr_standard tap *
  page187_i115
#ISCELL
  mstr_standard tap *
  page187_i116
#CELL
  mstr_sconn sconn80_e67482007 *
  page187_i119
#ISCELL
  mstr_standard tap *
  page187_i140
#ISCELL
  mstr_standard tap *
  page187_i141
#ISCELL
  mstr_standard tap *
  page187_i142
#ISCELL
  mstr_standard offpage *
  page187_i143
#ISCELL
  mstr_standard offpage *
  page187_i144
#CELL
  mstr_discrete res *
  page187_i145
#ISCELL
  mstr_standard offpage *
  page187_i146
#ISCELL
  mstr_standard tap *
  page187_i147
#ISCELL
  mstr_standard tap *
  page187_i148
#ISCELL
  mstr_standard tap *
  page187_i149
#CELL
  mstr_discrete res *
  page187_i150
#ISCELL
  mstr_standard offpage *
  page187_i151
#ISCELL
  mstr_standard offpage *
  page187_i152
#CELL
  mstr_discrete res *
  page187_i153
#ISCELL
  mstr_symbols gnd *
  page187_i154
#ISCELL
  mstr_standard tap *
  page187_i155
#ISCELL
  mstr_standard tap *
  page187_i156
#ISCELL
  mstr_standard tap *
  page187_i157
#ISCELL
  mstr_standard tap *
  page187_i158
#ISCELL
  mstr_standard offpage *
  page187_i159
#ISCELL
  mstr_standard offpage *
  page187_i160
#ISCELL
  mstr_symbols gnd *
  page187_i162
#ISCELL
  mstr_standard tap *
  page187_i164
#ISCELL
  mstr_standard tap *
  page187_i165
#ISCELL
  mstr_standard tap *
  page187_i166
#ISCELL
  mstr_standard tap *
  page187_i167
#ISCELL
  mstr_standard offpage *
  page187_i168
#CELL
  mstr_discrete res *
  page187_i18
#ISCELL
  mstr_symbols gnd *
  page187_i19
#ISCELL
  mstr_standard offpage *
  page187_i44
#ISCELL
  mstr_standard offpage *
  page187_i45
#ISCELL
  mstr_standard tap *
  page187_i46
#ISCELL
  mstr_standard tap *
  page187_i47
#ISCELL
  mstr_standard tap *
  page187_i50
#ISCELL
  mstr_standard tap *
  page187_i51
#ISCELL
  mstr_symbols p12v_stby *
  page187_i70
#ISCELL
  mstr_standard tap *
  page187_i87
#ISCELL
  mstr_standard tap *
  page187_i88
#ISCELL
  mstr_standard tap *
  page187_i89
#ISCELL
  mstr_standard tap *
  page187_i90
#ISCELL
  mstr_standard tap *
  page187_i95
#ISCELL
  mstr_standard tap *
  page187_i96
#ISCELL
  mstr_standard tap *
  page187_i97
#ISCELL
  mstr_standard tap *
  page187_i98
#ISCELL
  mstr_standard offpage *
  page187_i99
#ISCELL
  mstr_symbols cad_note *
  *
#ISCELL
  mstr_symbols intel_corp_bpage *
  *
#ISCELL
  mstr_standard offpage *
  page188_i10
#ISCELL
  mstr_standard offpage *
  page188_i100
#ISCELL
  mstr_standard offpage *
  page188_i101
#ISCELL
  mstr_standard offpage *
  page188_i102
#ISCELL
  mstr_standard offpage *
  page188_i103
#ISCELL
  mstr_standard offpage *
  page188_i104
#ISCELL
  mstr_standard offpage *
  page188_i105
#ISCELL
  mstr_standard offpage *
  page188_i106
#ISCELL
  mstr_standard offpage *
  page188_i107
#ISCELL
  mstr_standard offpage *
  page188_i108
#ISCELL
  mstr_standard offpage *
  page188_i109
#ISCELL
  mstr_standard offpage *
  page188_i11
#ISCELL
  mstr_standard offpage *
  page188_i110
#ISCELL
  mstr_standard offpage *
  page188_i111
#ISCELL
  mstr_standard offpage *
  page188_i112
#ISCELL
  mstr_standard offpage *
  page188_i113
#ISCELL
  mstr_standard offpage *
  page188_i114
#ISCELL
  mstr_standard offpage *
  page188_i115
#ISCELL
  mstr_symbols p3v3_stby *
  page188_i116
#ISCELL
  mstr_standard offpage *
  page188_i117
#ISCELL
  mstr_standard offpage *
  page188_i13
#ISCELL
  mstr_standard offpage *
  page188_i14
#ISCELL
  mstr_standard offpage *
  page188_i15
#ISCELL
  mstr_standard offpage *
  page188_i16
#ISCELL
  mstr_standard offpage *
  page188_i17
#ISCELL
  mstr_standard offpage *
  page188_i18
#CELL
  dev_discrete cap_a *
  page188_i2
#CELL
  dev_discrete cap_a *
  page188_i21
#CELL
  dev_discrete cap_a *
  page188_i23
#ISCELL
  mstr_symbols gnd *
  page188_i24
#CELL
  dev_discrete cap_a *
  page188_i25
#CELL
  mstr_sconn sconn64_h87568002_a *
  page188_i27
#ISCELL
  mstr_standard offpage *
  page188_i28
#ISCELL
  mstr_standard offpage *
  page188_i29
#CELL
  dev_discrete cap_a *
  page188_i3
#ISCELL
  mstr_standard offpage *
  page188_i30
#ISCELL
  mstr_standard offpage *
  page188_i31
#ISCELL
  mstr_standard offpage *
  page188_i32
#ISCELL
  mstr_standard offpage *
  page188_i33
#ISCELL
  mstr_standard offpage *
  page188_i34
#ISCELL
  mstr_standard offpage *
  page188_i35
#ISCELL
  mstr_standard offpage *
  page188_i36
#ISCELL
  mstr_standard offpage *
  page188_i37
#ISCELL
  mstr_standard offpage *
  page188_i38
#ISCELL
  mstr_symbols gnd *
  page188_i39
#CELL
  dev_discrete cap_a *
  page188_i40
#CELL
  mstr_discrete cap *
  page188_i41
#ISCELL
  mstr_standard offpage *
  page188_i42
#ISCELL
  mstr_standard offpage *
  page188_i45
#ISCELL
  mstr_standard offpage *
  page188_i46
#CELL
  dev_discrete cap_a *
  page188_i53
#CELL
  dev_discrete cap_a *
  page188_i55
#CELL
  dev_discrete cap_a *
  page188_i56
#CELL
  dev_discrete cap_a *
  page188_i57
#ISCELL
  mstr_symbols gnd *
  page188_i58
#ISCELL
  mstr_symbols p12v_stby *
  page188_i59
#ISCELL
  mstr_standard offpage *
  page188_i6
#ISCELL
  mstr_symbols p12v_stby *
  page188_i60
#ISCELL
  mstr_symbols p12v_stby *
  page188_i61
#ISCELL
  mstr_symbols p12v_stby *
  page188_i62
#ISCELL
  mstr_symbols p12v_stby *
  page188_i63
#CELL
  dev_discrete cap_a *
  page188_i64
#ISCELL
  mstr_standard offpage *
  page188_i65
#ISCELL
  mstr_standard offpage *
  page188_i66
#ISCELL
  mstr_standard offpage *
  page188_i67
#CELL
  dev_discrete cap_a *
  page188_i68
#ISCELL
  mstr_standard offpage *
  page188_i69
#ISCELL
  mstr_standard offpage *
  page188_i7
#ISCELL
  mstr_standard offpage *
  page188_i70
#ISCELL
  mstr_standard offpage *
  page188_i71
#CELL
  dev_discrete cap_a *
  page188_i72
#CELL
  dev_discrete cap_a *
  page188_i73
#ISCELL
  mstr_standard offpage *
  page188_i74
#ISCELL
  mstr_standard offpage *
  page188_i75
#ISCELL
  mstr_standard offpage *
  page188_i76
#ISCELL
  mstr_standard offpage *
  page188_i77
#ISCELL
  mstr_standard offpage *
  page188_i78
#ISCELL
  mstr_standard offpage *
  page188_i79
#ISCELL
  mstr_standard offpage *
  page188_i8
#CELL
  dev_discrete cap_a *
  page188_i80
#CELL
  dev_discrete cap_a *
  page188_i81
#CELL
  dev_discrete cap_a *
  page188_i82
#ISCELL
  mstr_standard offpage *
  page188_i83
#ISCELL
  mstr_standard offpage *
  page188_i84
#ISCELL
  mstr_standard offpage *
  page188_i85
#CELL
  dev_discrete cap_a *
  page188_i86
#ISCELL
  mstr_standard offpage *
  page188_i87
#CELL
  mstr_discrete res *
  page188_i88
#CELL
  mstr_discrete res *
  page188_i89
#ISCELL
  mstr_standard offpage *
  page188_i9
#CELL
  mstr_discrete res *
  page188_i90
#CELL
  mstr_discrete res *
  page188_i91
#CELL
  mstr_discrete res *
  page188_i92
#CELL
  mstr_discrete res *
  page188_i93
#CELL
  mstr_discrete res *
  page188_i94
#CELL
  mstr_discrete res *
  page188_i95
#ISCELL
  mstr_standard offpage *
  page188_i96
#ISCELL
  mstr_standard offpage *
  page188_i97
#ISCELL
  mstr_standard offpage *
  page188_i98
#ISCELL
  mstr_standard offpage *
  page188_i99
#ISCELL
  mstr_misc dns *
  *
#ISCELL
  mstr_symbols bom_note *
  *
#ISCELL
  mstr_symbols design_note *
  *
#ISCELL
  mstr_symbols intel_corp_bpage *
  *
#ISCELL
  mstr_standard offpage *
  page189_i1
#ISCELL
  mstr_standard offpage *
  page189_i10
#ISCELL
  mstr_standard offpage *
  page189_i11
#ISCELL
  mstr_standard offpage *
  page189_i12
#CELL
  mstr_discrete res *
  page189_i13
#ISCELL
  mstr_standard offpage *
  page189_i14
#ISCELL
  mstr_standard offpage *
  page189_i15
#ISCELL
  mstr_standard offpage *
  page189_i16
#CELL
  mstr_discrete res *
  page189_i17
#CELL
  mstr_discrete res *
  page189_i18
#CELL
  mstr_discrete res *
  page189_i19
#ISCELL
  mstr_standard offpage *
  page189_i2
#CELL
  mstr_discrete res *
  page189_i20
#CELL
  mstr_discrete res *
  page189_i21
#CELL
  mstr_discrete res *
  page189_i22
#CELL
  mstr_discrete res *
  page189_i23
#CELL
  mstr_discrete res *
  page189_i24
#CELL
  mstr_discrete res *
  page189_i25
#CELL
  mstr_discrete res *
  page189_i26
#CELL
  mstr_discrete res *
  page189_i27
#ISCELL
  mstr_standard offpage *
  page189_i28
#ISCELL
  mstr_standard offpage *
  page189_i29
#ISCELL
  mstr_standard offpage *
  page189_i3
#ISCELL
  mstr_standard offpage *
  page189_i30
#ISCELL
  mstr_standard offpage *
  page189_i31
#ISCELL
  mstr_standard offpage *
  page189_i32
#ISCELL
  mstr_standard offpage *
  page189_i33
#ISCELL
  mstr_standard offpage *
  page189_i34
#ISCELL
  mstr_standard offpage *
  page189_i35
#CELL
  mstr_discrete res *
  page189_i36
#CELL
  mstr_discrete res *
  page189_i37
#CELL
  mstr_discrete res *
  page189_i38
#ISCELL
  mstr_standard offpage *
  page189_i39
#ISCELL
  mstr_standard offpage *
  page189_i4
#ISCELL
  mstr_standard offpage *
  page189_i40
#ISCELL
  mstr_standard offpage *
  page189_i41
#ISCELL
  mstr_standard offpage *
  page189_i42
#ISCELL
  mstr_symbols p3v3_stby *
  page189_i43
#CELL
  mstr_discrete res *
  page189_i44
#CELL
  mstr_discrete res *
  page189_i45
#ISCELL
  mstr_symbols gnd *
  page189_i46
#CELL
  mstr_conn conn8_c77962004 *
  page189_i47
#ISCELL
  mstr_symbols p3v3_stby *
  page189_i48
#CELL
  mstr_discrete diode *
  page189_i49
#ISCELL
  mstr_standard offpage *
  page189_i5
#CELL
  mstr_discrete res *
  page189_i50
#CELL
  mstr_discrete res *
  page189_i51
#ISCELL
  mstr_symbols p3v3_stby *
  page189_i52
#CELL
  mstr_discrete res *
  page189_i53
#ISCELL
  mstr_symbols gnd *
  page189_i54
#ISCELL
  mstr_symbols gnd *
  page189_i55
#CELL
  mstr_discrete res *
  page189_i56
#ISCELL
  mstr_standard offpage *
  page189_i57
#ISCELL
  mstr_standard offpage *
  page189_i58
#ISCELL
  mstr_standard offpage *
  page189_i59
#ISCELL
  mstr_standard offpage *
  page189_i6
#ISCELL
  mstr_standard offpage *
  page189_i60
#ISCELL
  mstr_standard offpage *
  page189_i61
#ISCELL
  mstr_standard offpage *
  page189_i62
#CELL
  mstr_discrete res *
  page189_i63
#CELL
  mstr_discrete res *
  page189_i64
#CELL
  mstr_discrete res *
  page189_i65
#CELL
  mstr_discrete res *
  page189_i66
#CELL
  mstr_discrete res *
  page189_i7
#CELL
  mstr_discrete res *
  page189_i8
#CELL
  mstr_discrete res *
  page189_i9
#ISCELL
  mstr_symbols intel_corp_bpage *
  *
#CELL
  mstr_discrete res *
  page190_i116
#CELL
  mstr_discrete res *
  page190_i117
#ISCELL
  mstr_standard offpage *
  page190_i118
#ISCELL
  mstr_standard offpage *
  page190_i119
#ISCELL
  mstr_standard offpage *
  page190_i120
#ISCELL
  mstr_standard offpage *
  page190_i121
#ISCELL
  mstr_standard offpage *
  page190_i122
#ISCELL
  mstr_standard offpage *
  page190_i134
#ISCELL
  mstr_standard offpage *
  page190_i139
#ISCELL
  mstr_standard offpage *
  page190_i146
#ISCELL
  mstr_standard offpage *
  page190_i157
#ISCELL
  mstr_standard offpage *
  page190_i159
#ISCELL
  mstr_standard offpage *
  page190_i161
#ISCELL
  mstr_standard offpage *
  page190_i162
#ISCELL
  mstr_standard offpage *
  page190_i165
#ISCELL
  mstr_standard offpage *
  page190_i167
#ISCELL
  mstr_standard offpage *
  page190_i168
#ISCELL
  mstr_standard offpage *
  page190_i171
#CELL
  mstr_memory lcmxo2_a *
  page190_i179
#ISCELL
  mstr_standard offpage *
  page190_i220
#ISCELL
  mstr_standard offpage *
  page190_i221
#ISCELL
  mstr_standard offpage *
  page190_i224
#ISCELL
  mstr_standard offpage *
  page190_i225
#ISCELL
  mstr_standard offpage *
  page190_i226
#ISCELL
  mstr_standard offpage *
  page190_i227
#ISCELL
  mstr_standard offpage *
  page190_i231
#ISCELL
  mstr_standard offpage *
  page190_i234
#ISCELL
  mstr_standard offpage *
  page190_i235
#ISCELL
  mstr_standard offpage *
  page190_i236
#ISCELL
  mstr_standard offpage *
  page190_i237
#ISCELL
  mstr_standard offpage *
  page190_i239
#ISCELL
  mstr_standard offpage *
  page190_i240
#ISCELL
  mstr_standard offpage *
  page190_i241
#ISCELL
  mstr_standard offpage *
  page190_i243
#ISCELL
  mstr_standard offpage *
  page190_i244
#ISCELL
  mstr_standard offpage *
  page190_i246
#ISCELL
  mstr_standard offpage *
  page190_i248
#ISCELL
  mstr_standard offpage *
  page190_i252
#ISCELL
  mstr_standard offpage *
  page190_i255
#ISCELL
  mstr_standard offpage *
  page190_i260
#ISCELL
  mstr_standard offpage *
  page190_i261
#ISCELL
  mstr_standard offpage *
  page190_i263
#ISCELL
  mstr_standard offpage *
  page190_i267
#ISCELL
  mstr_standard offpage *
  page190_i268
#ISCELL
  mstr_standard offpage *
  page190_i269
#ISCELL
  mstr_standard offpage *
  page190_i270
#ISCELL
  mstr_standard offpage *
  page190_i271
#ISCELL
  mstr_standard offpage *
  page190_i272
#ISCELL
  mstr_standard offpage *
  page190_i273
#ISCELL
  mstr_standard offpage *
  page190_i274
#ISCELL
  mstr_standard offpage *
  page190_i275
#ISCELL
  mstr_standard offpage *
  page190_i276
#ISCELL
  mstr_standard offpage *
  page190_i277
#ISCELL
  mstr_standard offpage *
  page190_i279
#ISCELL
  mstr_standard offpage *
  page190_i280
#ISCELL
  mstr_standard offpage *
  page190_i284
#ISCELL
  mstr_standard offpage *
  page190_i285
#ISCELL
  mstr_standard offpage *
  page190_i298
#ISCELL
  mstr_standard offpage *
  page190_i299
#ISCELL
  mstr_standard offpage *
  page190_i301
#ISCELL
  mstr_standard offpage *
  page190_i302
#ISCELL
  mstr_standard offpage *
  page190_i303
#ISCELL
  mstr_standard offpage *
  page190_i304
#ISCELL
  mstr_standard offpage *
  page190_i305
#ISCELL
  mstr_standard offpage *
  page190_i306
#ISCELL
  mstr_standard offpage *
  page190_i307
#ISCELL
  mstr_standard offpage *
  page190_i308
#ISCELL
  mstr_standard offpage *
  page190_i309
#ISCELL
  mstr_standard offpage *
  page190_i312
#ISCELL
  mstr_standard offpage *
  page190_i313
#ISCELL
  mstr_standard offpage *
  page190_i314
#ISCELL
  mstr_standard offpage *
  page190_i317
#ISCELL
  mstr_standard offpage *
  page190_i318
#ISCELL
  mstr_standard offpage *
  page190_i319
#ISCELL
  mstr_standard offpage *
  page190_i320
#ISCELL
  mstr_standard offpage *
  page190_i321
#ISCELL
  mstr_standard offpage *
  page190_i322
#ISCELL
  mstr_standard offpage *
  page190_i323
#ISCELL
  mstr_standard offpage *
  page190_i324
#ISCELL
  mstr_standard offpage *
  page190_i325
#ISCELL
  mstr_standard offpage *
  page190_i326
#ISCELL
  mstr_standard offpage *
  page190_i327
#ISCELL
  mstr_standard offpage *
  page190_i328
#ISCELL
  mstr_standard offpage *
  page190_i329
#ISCELL
  mstr_standard offpage *
  page190_i330
#ISCELL
  mstr_standard offpage *
  page190_i331
#ISCELL
  mstr_standard offpage *
  page190_i332
#ISCELL
  mstr_standard offpage *
  page190_i333
#ISCELL
  mstr_standard offpage *
  page190_i334
#ISCELL
  mstr_standard offpage *
  page190_i335
#ISCELL
  mstr_standard offpage *
  page190_i336
#ISCELL
  mstr_standard offpage *
  page190_i337
#CELL
  mstr_discrete res *
  page190_i338
#ISCELL
  mstr_standard offpage *
  page190_i339
#ISCELL
  mstr_standard offpage *
  page190_i340
#ISCELL
  mstr_standard offpage *
  page190_i341
#ISCELL
  mstr_standard offpage *
  page190_i342
#ISCELL
  mstr_standard offpage *
  page190_i343
#ISCELL
  mstr_standard offpage *
  page190_i344
#ISCELL
  mstr_standard offpage *
  page190_i345
#ISCELL
  mstr_standard offpage *
  page190_i346
#ISCELL
  mstr_symbols cad_note *
  *
#ISCELL
  mstr_symbols design_note *
  *
#ISCELL
  mstr_symbols intel_corp_bpage *
  *
#ISCELL
  mstr_standard offpage *
  page191_i1
#ISCELL
  mstr_standard offpage *
  page191_i102
#ISCELL
  mstr_standard offpage *
  page191_i115
#ISCELL
  mstr_standard offpage *
  page191_i118
#ISCELL
  mstr_standard offpage *
  page191_i120
#ISCELL
  mstr_standard offpage *
  page191_i123
#ISCELL
  mstr_standard offpage *
  page191_i125
#ISCELL
  mstr_standard offpage *
  page191_i127
#ISCELL
  mstr_standard offpage *
  page191_i128
#ISCELL
  mstr_standard offpage *
  page191_i129
#ISCELL
  mstr_standard offpage *
  page191_i132
#ISCELL
  mstr_standard offpage *
  page191_i133
#ISCELL
  mstr_standard offpage *
  page191_i134
#ISCELL
  mstr_standard offpage *
  page191_i135
#ISCELL
  mstr_standard offpage *
  page191_i136
#ISCELL
  mstr_standard offpage *
  page191_i137
#ISCELL
  mstr_standard offpage *
  page191_i139
#ISCELL
  mstr_standard offpage *
  page191_i141
#ISCELL
  mstr_standard offpage *
  page191_i142
#ISCELL
  mstr_standard offpage *
  page191_i143
#ISCELL
  mstr_standard offpage *
  page191_i145
#ISCELL
  mstr_standard offpage *
  page191_i147
#ISCELL
  mstr_standard offpage *
  page191_i148
#ISCELL
  mstr_standard offpage *
  page191_i149
#ISCELL
  mstr_standard offpage *
  page191_i151
#ISCELL
  mstr_standard offpage *
  page191_i156
#ISCELL
  mstr_standard offpage *
  page191_i157
#ISCELL
  mstr_standard offpage *
  page191_i158
#ISCELL
  mstr_standard offpage *
  page191_i160
#ISCELL
  mstr_standard offpage *
  page191_i161
#ISCELL
  mstr_standard offpage *
  page191_i162
#ISCELL
  mstr_standard offpage *
  page191_i163
#ISCELL
  mstr_standard offpage *
  page191_i164
#ISCELL
  mstr_standard offpage *
  page191_i165
#CELL
  mstr_discrete res *
  page191_i166
#ISCELL
  mstr_standard offpage *
  page191_i167
#ISCELL
  mstr_standard offpage *
  page191_i168
#ISCELL
  mstr_standard offpage *
  page191_i169
#ISCELL
  mstr_standard offpage *
  page191_i17
#ISCELL
  mstr_standard offpage *
  page191_i170
#ISCELL
  mstr_symbols p3v3_stby *
  page191_i171
#CELL
  mstr_discrete res *
  page191_i172
#ISCELL
  mstr_standard offpage *
  page191_i173
#ISCELL
  mstr_standard offpage *
  page191_i174
#ISCELL
  mstr_standard offpage *
  page191_i175
#ISCELL
  mstr_standard offpage *
  page191_i176
#ISCELL
  mstr_standard offpage *
  page191_i177
#ISCELL
  mstr_standard offpage *
  page191_i178
#ISCELL
  mstr_standard offpage *
  page191_i179
#ISCELL
  mstr_standard offpage *
  page191_i18
#ISCELL
  mstr_standard offpage *
  page191_i180
#ISCELL
  mstr_standard offpage *
  page191_i181
#ISCELL
  mstr_standard offpage *
  page191_i182
#ISCELL
  mstr_standard offpage *
  page191_i183
#CELL
  mstr_discrete res *
  page191_i184
#ISCELL
  mstr_standard offpage *
  page191_i185
#ISCELL
  mstr_standard offpage *
  page191_i186
#ISCELL
  mstr_standard offpage *
  page191_i187
#ISCELL
  mstr_standard offpage *
  page191_i188
#ISCELL
  mstr_standard offpage *
  page191_i189
#ISCELL
  mstr_standard offpage *
  page191_i19
#ISCELL
  mstr_standard offpage *
  page191_i190
#ISCELL
  mstr_standard offpage *
  page191_i191
#ISCELL
  mstr_standard offpage *
  page191_i192
#CELL
  mstr_discrete res *
  page191_i193
#ISCELL
  mstr_symbols p3v3_stby *
  page191_i194
#ISCELL
  mstr_standard offpage *
  page191_i2
#ISCELL
  mstr_standard offpage *
  page191_i22
#ISCELL
  mstr_standard offpage *
  page191_i24
#ISCELL
  mstr_standard offpage *
  page191_i26
#ISCELL
  mstr_standard offpage *
  page191_i27
#ISCELL
  mstr_standard offpage *
  page191_i33
#ISCELL
  mstr_standard offpage *
  page191_i38
#ISCELL
  mstr_standard offpage *
  page191_i47
#ISCELL
  mstr_standard offpage *
  page191_i49
#CELL
  mstr_memory lcmxo2_a *
  page191_i59
#ISCELL
  mstr_standard offpage *
  page191_i84
#ISCELL
  mstr_standard offpage *
  page191_i87
#ISCELL
  mstr_standard offpage *
  page191_i88
#ISCELL
  mstr_standard offpage *
  page191_i93
#ISCELL
  mstr_standard offpage *
  page191_i95
#ISCELL
  mstr_standard offpage *
  page191_i96
#ISCELL
  mstr_standard offpage *
  page191_i97
#ISCELL
  mstr_standard offpage *
  page191_i99
#ISCELL
  mstr_misc dns *
  *
#ISCELL
  mstr_symbols intel_corp_bpage *
  *
#CELL
  dev_discrete cap_a *
  page192_i1
#CELL
  dev_discrete cap_a *
  page192_i10
#CELL
  dev_discrete cap_a *
  page192_i11
#CELL
  dev_discrete cap_a *
  page192_i12
#CELL
  mstr_memory lcmxo2_a *
  page192_i14
#CELL
  dev_discrete cap_a *
  page192_i15
#CELL
  dev_discrete cap_a *
  page192_i16
#CELL
  dev_discrete cap_a *
  page192_i17
#CELL
  dev_discrete cap_a *
  page192_i18
#CELL
  dev_discrete cap_a *
  page192_i19
#ISCELL
  mstr_symbols gnd *
  page192_i2
#CELL
  dev_discrete cap_a *
  page192_i20
#CELL
  dev_discrete cap_a *
  page192_i21
#CELL
  dev_discrete cap_a *
  page192_i22
#CELL
  dev_discrete cap_a *
  page192_i23
#CELL
  dev_discrete cap_a *
  page192_i25
#ISCELL
  mstr_symbols gnd *
  page192_i26
#CELL
  dev_discrete cap_a *
  page192_i28
#ISCELL
  mstr_symbols p3v3_stby *
  page192_i29
#CELL
  dev_discrete cap_a *
  page192_i3
#ISCELL
  mstr_symbols p3v3_stby *
  page192_i30
#ISCELL
  mstr_symbols p3v3_stby *
  page192_i31
#ISCELL
  mstr_symbols p3v3_stby *
  page192_i32
#CELL
  mstr_discrete res *
  page192_i33
#CELL
  mstr_discrete res *
  page192_i34
#ISCELL
  mstr_symbols p3v3_stby *
  page192_i35
#ISCELL
  mstr_standard offpage *
  page192_i36
#ISCELL
  mstr_standard offpage *
  page192_i37
#CELL
  mstr_discrete res *
  page192_i38
#ISCELL
  mstr_symbols p3v3_stby *
  page192_i39
#CELL
  dev_discrete cap_a *
  page192_i4
#ISCELL
  mstr_standard offpage *
  page192_i40
#CELL
  mstr_discrete res *
  page192_i41
#ISCELL
  mstr_symbols p3v3_stby *
  page192_i42
#ISCELL
  mstr_standard offpage *
  page192_i45
#CELL
  mstr_discrete res *
  page192_i48
#CELL
  mstr_discrete res *
  page192_i49
#ISCELL
  mstr_symbols gnd *
  page192_i5
#ISCELL
  mstr_standard offpage *
  page192_i50
#ISCELL
  mstr_standard offpage *
  page192_i51
#ISCELL
  mstr_symbols pvpp_abc *
  page192_i52
#ISCELL
  mstr_standard offpage *
  page192_i54
#CELL
  mstr_discrete res *
  page192_i55
#ISCELL
  mstr_symbols p3v3_stby *
  page192_i56
#CELL
  mstr_discrete res *
  page192_i57
#ISCELL
  mstr_symbols p3v3_stby *
  page192_i58
#CELL
  mstr_discrete res *
  page192_i59
#CELL
  dev_discrete cap_a *
  page192_i6
#ISCELL
  mstr_standard offpage *
  page192_i60
#ISCELL
  mstr_symbols gnd *
  page192_i61
#ISCELL
  mstr_symbols pvpp_klm *
  page192_i62
#CELL
  dev_discrete cap_a *
  page192_i7
#CELL
  dev_discrete cap_a *
  page192_i8
#CELL
  dev_discrete cap_a *
  page192_i9
#ISCELL
  mstr_symbols design_note *
  *
#ISCELL
  mstr_symbols intel_corp_bpage *
  *
#ISCELL
  mstr_symbols vcc_core *
  page193_i107
#ISCELL
  mstr_standard offpage *
  page193_i111
#ISCELL
  mstr_standard offpage *
  page193_i112
#ISCELL
  mstr_standard offpage *
  page193_i113
#ISCELL
  mstr_standard offpage *
  page193_i114
#ISCELL
  mstr_symbols vcc_core *
  page193_i131
#ISCELL
  mstr_symbols vcc_core *
  page193_i134
#ISCELL
  mstr_standard offpage *
  page193_i138
#CELL
  dev_discrete cap_a *
  page193_i140
#CELL
  dev_discrete cap_a *
  page193_i141
#ISCELL
  mstr_symbols pvccio_cpu1 *
  page193_i144
#ISCELL
  mstr_standard offpage *
  page193_i149
#ISCELL
  mstr_standard offpage *
  page193_i150
#ISCELL
  mstr_standard offpage *
  page193_i151
#ISCELL
  mstr_standard offpage *
  page193_i152
#ISCELL
  mstr_standard offpage *
  page193_i153
#ISCELL
  mstr_standard offpage *
  page193_i154
#ISCELL
  mstr_standard offpage *
  page193_i155
#ISCELL
  mstr_standard offpage *
  page193_i156
#ISCELL
  mstr_standard offpage *
  page193_i157
#ISCELL
  mstr_symbols vcc_core *
  page193_i161
#ISCELL
  mstr_symbols vcc_core *
  page193_i162
#ISCELL
  mstr_symbols vcc_core *
  page193_i164
#ISCELL
  mstr_symbols vcc_core *
  page193_i165
#ISCELL
  mstr_symbols vcc_core *
  page193_i166
#ISCELL
  mstr_symbols vcc_core *
  page193_i167
#ISCELL
  mstr_symbols vcc_core *
  page193_i168
#CELL
  mstr_discrete res *
  page193_i169
#CELL
  mstr_discrete res *
  page193_i170
#ISCELL
  mstr_symbols gnd *
  page193_i171
#ISCELL
  mstr_symbols p3v3 *
  page193_i173
#ISCELL
  mstr_standard offpage *
  page193_i174
#ISCELL
  mstr_standard offpage *
  page193_i2
#CELL
  mstr_discrete capp *
  page193_i29
#ISCELL
  mstr_symbols gnd *
  page193_i30
#CELL
  dev_discrete cap_a *
  page193_i31
#ISCELL
  mstr_symbols gnd *
  page193_i37
#CELL
  dev_discrete cap_a *
  page193_i38
#ISCELL
  mstr_standard offpage *
  page193_i4
#CELL
  mstr_sconn sconn120_h61426002 *
  page193_i45
#CELL
  mstr_sconn sconn120_h61426002 *
  page193_i46
#ISCELL
  mstr_standard offpage *
  page193_i49
#ISCELL
  mstr_standard offpage *
  page193_i5
#ISCELL
  mstr_standard offpage *
  page193_i50
#ISCELL
  mstr_symbols gnd *
  page193_i56
#ISCELL
  mstr_symbols gnd *
  page193_i60
#CELL
  mstr_discrete capp *
  page193_i61
#CELL
  mstr_discrete capp *
  page193_i62
#ISCELL
  mstr_symbols gnd *
  page193_i64
#CELL
  dev_discrete cap_a *
  page193_i68
#CELL
  dev_discrete cap_a *
  page193_i70
#ISCELL
  mstr_symbols gnd *
  page193_i75
#ISCELL
  mstr_symbols gnd *
  page193_i81
#ISCELL
  mstr_standard offpage *
  page193_i83
#ISCELL
  mstr_standard offpage *
  page193_i84
#ISCELL
  mstr_symbols gnd *
  page193_i85
#ISCELL
  mstr_symbols p12v_stby *
  page193_i86
#ISCELL
  mstr_symbols p3v3_stby *
  page193_i87
#ISCELL
  mstr_symbols p5v_stby *
  page193_i88
#ISCELL
  mstr_standard offpage *
  page193_i90
#ISCELL
  mstr_symbols gnd *
  page193_i94
#ISCELL
  mstr_symbols gnd *
  page193_i95
#ISCELL
  mstr_symbols design_note *
  *
#ISCELL
  mstr_symbols intel_corp_bpage *
  *
#ISCELL
  mstr_symbols gnd *
  page194_i100
#CELL
  mstr_discrete capp *
  page194_i101
#ISCELL
  mstr_symbols vcc_core *
  page194_i102
#ISCELL
  mstr_symbols gnd *
  page194_i110
#ISCELL
  mstr_symbols gnd *
  page194_i111
#ISCELL
  mstr_standard offpage *
  page194_i114
#ISCELL
  mstr_standard offpage *
  page194_i116
#ISCELL
  mstr_symbols p12v_stby *
  page194_i119
#ISCELL
  mstr_symbols p3v3_stby *
  page194_i120
#ISCELL
  mstr_symbols p5v_stby *
  page194_i121
#ISCELL
  mstr_standard offpage *
  page194_i123
#ISCELL
  mstr_standard offpage *
  page194_i124
#ISCELL
  mstr_standard offpage *
  page194_i125
#ISCELL
  mstr_symbols gnd *
  page194_i127
#ISCELL
  mstr_symbols vcc_core *
  page194_i130
#ISCELL
  mstr_standard offpage *
  page194_i131
#ISCELL
  mstr_standard offpage *
  page194_i132
#ISCELL
  mstr_standard offpage *
  page194_i133
#ISCELL
  mstr_standard offpage *
  page194_i134
#ISCELL
  mstr_symbols vcc_core *
  page194_i141
#ISCELL
  mstr_symbols vcc_core *
  page194_i142
#ISCELL
  mstr_symbols vcc_core *
  page194_i143
#ISCELL
  mstr_symbols vcc_core *
  page194_i144
#ISCELL
  mstr_standard offpage *
  page194_i148
#CELL
  dev_discrete cap_a *
  page194_i149
#CELL
  dev_discrete cap_a *
  page194_i150
#ISCELL
  mstr_symbols gnd *
  page194_i151
#ISCELL
  mstr_symbols pvccio_cpu0 *
  page194_i154
#CELL
  mstr_discrete res *
  page194_i155
#CELL
  mstr_discrete res *
  page194_i156
#ISCELL
  mstr_symbols gnd *
  page194_i157
#ISCELL
  mstr_standard offpage *
  page194_i158
#ISCELL
  mstr_standard offpage *
  page194_i159
#CELL
  dev_discrete cap_a *
  page194_i16
#ISCELL
  mstr_standard offpage *
  page194_i160
#ISCELL
  mstr_standard offpage *
  page194_i161
#ISCELL
  mstr_standard offpage *
  page194_i162
#ISCELL
  mstr_standard offpage *
  page194_i163
#ISCELL
  mstr_standard offpage *
  page194_i164
#ISCELL
  mstr_standard offpage *
  page194_i165
#ISCELL
  mstr_standard offpage *
  page194_i166
#ISCELL
  mstr_standard offpage *
  page194_i167
#ISCELL
  mstr_symbols p3v3 *
  page194_i170
#ISCELL
  mstr_standard offpage *
  page194_i171
#ISCELL
  mstr_symbols gnd *
  page194_i28
#CELL
  mstr_discrete capp *
  page194_i29
#ISCELL
  mstr_symbols vcc_core *
  page194_i30
#CELL
  mstr_discrete capp *
  page194_i31
#ISCELL
  mstr_symbols gnd *
  page194_i33
#CELL
  mstr_sconn sconn120_h61426002 *
  page194_i55
#CELL
  mstr_sconn sconn120_h61426002 *
  page194_i56
#ISCELL
  mstr_symbols gnd *
  page194_i61
#ISCELL
  mstr_symbols gnd *
  page194_i62
#ISCELL
  mstr_standard offpage *
  page194_i64
#ISCELL
  mstr_standard offpage *
  page194_i67
#ISCELL
  mstr_symbols vcc_core *
  page194_i68
#ISCELL
  mstr_symbols vcc_core *
  page194_i69
#CELL
  dev_discrete cap_a *
  page194_i86
#CELL
  dev_discrete cap_a *
  page194_i9
#ISCELL
  mstr_symbols gnd *
  page194_i92
#ISCELL
  mstr_symbols vcc_core *
  page194_i95
#CELL
  dev_discrete cap_a *
  page194_i99
#ISCELL
  mstr_misc dns *
  *
#ISCELL
  mstr_symbols intel_corp_bpage *
  *
#CELL
  mstr_discrete capp *
  page195_i100
#CELL
  mstr_discrete capp *
  page195_i101
#CELL
  mstr_discrete capp *
  page195_i102
#CELL
  mstr_discrete capp *
  page195_i103
#CELL
  mstr_discrete capp *
  page195_i104
#CELL
  mstr_discrete capp *
  page195_i105
#CELL
  mstr_discrete capp *
  page195_i106
#ISCELL
  mstr_symbols p12v_stby *
  page195_i107
#CELL
  mstr_discrete capp *
  page195_i108
#CELL
  mstr_discrete capp *
  page195_i109
#ISCELL
  mstr_symbols gnd *
  page195_i110
#CELL
  mstr_discrete capp *
  page195_i111
#CELL
  mstr_discrete capp *
  page195_i112
#CELL
  mstr_discrete capp *
  page195_i113
#ISCELL
  mstr_symbols p12v_psu *
  page195_i25
#CELL
  mstr_conn conn3_g98259001 *
  page195_i26
#ISCELL
  mstr_symbols gnd *
  page195_i27
#ISCELL
  mstr_symbols gnd *
  page195_i28
#CELL
  mstr_conn conn12_g98257001 *
  page195_i29
#ISCELL
  mstr_symbols gnd *
  page195_i30
#CELL
  mstr_discrete cap *
  page195_i31
#CELL
  mstr_discrete cap *
  page195_i32
#ISCELL
  mstr_symbols gnd *
  page195_i33
#ISCELL
  mstr_symbols p12v_psu *
  page195_i34
#CELL
  mstr_discrete cap *
  page195_i35
#CELL
  dev_discrete cap_a *
  page195_i36
#CELL
  dev_discrete cap_a *
  page195_i37
#CELL
  dev_discrete cap_a *
  page195_i38
#CELL
  dev_discrete cap_a *
  page195_i39
#ISCELL
  mstr_symbols p12v_psu *
  page195_i40
#ISCELL
  mstr_symbols gnd *
  page195_i48
#CELL
  mstr_misc mtg_keyhole *
  page195_i49
#CELL
  mstr_misc mtg_keyhole *
  page195_i52
#ISCELL
  mstr_symbols gnd *
  page195_i53
#CELL
  mstr_misc mtg_keyhole *
  page195_i54
#ISCELL
  mstr_symbols gnd *
  page195_i55
#CELL
  mstr_misc mtg_keyhole *
  page195_i56
#ISCELL
  mstr_symbols gnd *
  page195_i57
#CELL
  mstr_misc mtg_keyhole *
  page195_i62
#ISCELL
  mstr_symbols gnd *
  page195_i63
#ISCELL
  mstr_symbols gnd *
  page195_i64
#CELL
  mstr_misc mtg_keyhole *
  page195_i65
#ISCELL
  mstr_symbols gnd *
  page195_i66
#CELL
  mstr_misc mtg_keyhole *
  page195_i67
#CELL
  mstr_misc captive_screw *
  page195_i76
#ISCELL
  mstr_symbols p12v_psu *
  page195_i77
#CELL
  mstr_conn conn12_g98257001 *
  page195_i78
#ISCELL
  mstr_symbols gnd *
  page195_i79
#ISCELL
  mstr_symbols p12v_psu *
  page195_i80
#ISCELL
  mstr_symbols gnd *
  page195_i81
#CELL
  mstr_discrete capp *
  page195_i82
#CELL
  mstr_discrete capp *
  page195_i83
#CELL
  mstr_discrete capp *
  page195_i84
#CELL
  mstr_discrete capp *
  page195_i85
#ISCELL
  mstr_symbols p12v_stby *
  page195_i92
#ISCELL
  mstr_symbols p12v_stby *
  page195_i93
#ISCELL
  mstr_symbols gnd *
  page195_i94
#ISCELL
  mstr_symbols gnd *
  page195_i95
#CELL
  mstr_discrete capp *
  page195_i96
#CELL
  mstr_discrete capp *
  page195_i97
#CELL
  mstr_discrete capp *
  page195_i98
#CELL
  mstr_discrete capp *
  page195_i99
#ISCELL
  mstr_misc dns *
  *
#ISCELL
  mstr_symbols cad_note *
  *
#ISCELL
  mstr_symbols design_note *
  *
#ISCELL
  mstr_symbols intel_corp_bpage *
  *
#CELL
  dev_discrete cap_a *
  page196_i102
#CELL
  mstr_discrete diode *
  page196_i103
#CELL
  mstr_vreg tps3700 *
  page196_i104
#CELL
  dev_discrete cap_a *
  page196_i105
#CELL
  mstr_discrete res *
  page196_i106
#ISCELL
  mstr_standard offpage *
  page196_i107
#ISCELL
  mstr_symbols gnd *
  page196_i108
#ISCELL
  mstr_symbols gnd *
  page196_i110
#ISCELL
  mstr_symbols p3v3_stby *
  page196_i111
#CELL
  mstr_discrete res *
  page196_i112
#CELL
  mstr_discrete res *
  page196_i113
#CELL
  mstr_discrete res *
  page196_i114
#CELL
  mstr_discrete res *
  page196_i115
#ISCELL
  mstr_symbols p5v *
  page196_i116
#ISCELL
  mstr_symbols p12v *
  page196_i117
#ISCELL
  mstr_symbols gnd *
  page196_i118
#ISCELL
  mstr_symbols gnd *
  page196_i119
#CELL
  mstr_discrete res *
  page196_i120
#CELL
  mstr_discrete res *
  page196_i121
#CELL
  mstr_discrete res *
  page196_i122
#ISCELL
  mstr_symbols p3v3_stby *
  page196_i123
#CELL
  mstr_discrete fet_n *
  page196_i124
#ISCELL
  mstr_symbols gnd *
  page196_i125
#ISCELL
  mstr_symbols p3v3_stby *
  page196_i126
#ISCELL
  mstr_symbols p3v3_stby *
  page196_i127
#CELL
  mstr_discrete diode *
  page196_i128
#ISCELL
  mstr_symbols gnd *
  page196_i43
#ISCELL
  mstr_standard offpage *
  page196_i45
#CELL
  mstr_discrete res *
  page196_i46
#CELL
  mstr_misc battery *
  page196_i47
#CELL
  mstr_discrete vert_batt_3pin *
  page196_i51
#ISCELL
  mstr_symbols gnd *
  page196_i52
#CELL
  mstr_discrete diode2a_dual *
  page196_i53
#ISCELL
  mstr_symbols p3v3_stby *
  page196_i54
#ISCELL
  mstr_symbols p3v3_stby *
  page196_i56
#ISCELL
  mstr_symbols p12v_stby *
  page196_i57
#ISCELL
  mstr_symbols p3v3_stby *
  page196_i58
#CELL
  mstr_discrete res *
  page196_i59
#CELL
  mstr_discrete cap *
  page196_i60
#ISCELL
  mstr_symbols gnd *
  page196_i61
#ISCELL
  mstr_symbols gnd *
  page196_i62
#ISCELL
  mstr_standard offpage *
  page196_i63
#ISCELL
  mstr_standard offpage *
  page196_i64
#CELL
  mstr_discrete res *
  page196_i65
#CELL
  mstr_discrete res *
  page196_i68
#ISCELL
  mstr_symbols p3v3_stby *
  page196_i69
#CELL
  mstr_analog adm1085 *
  page196_i70
#CELL
  mstr_discrete res *
  page196_i71
#CELL
  dev_discrete cap_a *
  page196_i72
#ISCELL
  mstr_symbols gnd *
  page196_i73
#CELL
  mstr_discrete res *
  page196_i74
#CELL
  mstr_discrete res *
  page196_i75
#ISCELL
  mstr_symbols gnd *
  page196_i76
#CELL
  mstr_analog adm809 *
  page196_i80
#CELL
  dev_discrete cap_a *
  page196_i81
#ISCELL
  mstr_symbols gnd *
  page196_i82
#ISCELL
  mstr_symbols p3v3 *
  page196_i83
#ISCELL
  mstr_standard offpage *
  page196_i88
#CELL
  mstr_analog adm809 *
  page196_i89
#CELL
  mstr_discrete res *
  page196_i90
#ISCELL
  mstr_standard offpage *
  page196_i91
#CELL
  dev_discrete cap_a *
  page196_i94
#ISCELL
  mstr_symbols gnd *
  page196_i95
#ISCELL
  mstr_standard offpage *
  page196_i96
#ISCELL
  mstr_symbols p3v3_rtc_stby *
  page196_i97
#ISCELL
  mstr_standard offpage *
  page196_i98
#ISCELL
  mstr_symbols cad_note *
  *
#ISCELL
  mstr_symbols intel_corp_bpage *
  *
#ISCELL
  mstr_symbols p12v_nvdimm_abc *
  page197_i101
#ISCELL
  mstr_symbols gnd *
  page197_i103
#CELL
  mstr_discrete res *
  page197_i110
#ISCELL
  mstr_standard offpage *
  page197_i111
#ISCELL
  mstr_standard offpage *
  page197_i112
#CELL
  mstr_discrete res *
  page197_i113
#ISCELL
  mstr_symbols gnd *
  page197_i114
#CELL
  mstr_vreg max9634 *
  page197_i120
#CELL
  mstr_discrete res *
  page197_i121
#ISCELL
  mstr_symbols p12v_nvdimm_def *
  page197_i122
#ISCELL
  mstr_standard offpage *
  page197_i123
#CELL
  mstr_discrete res *
  page197_i126
#ISCELL
  mstr_symbols gnd *
  page197_i129
#CELL
  mstr_discrete res *
  page197_i131
#ISCELL
  mstr_symbols p12v_nvdimm_ghj *
  page197_i132
#CELL
  mstr_vreg max9634 *
  page197_i133
#ISCELL
  mstr_standard offpage *
  page197_i134
#CELL
  mstr_discrete res *
  page197_i137
#ISCELL
  mstr_symbols gnd *
  page197_i140
#CELL
  mstr_discrete res *
  page197_i142
#ISCELL
  mstr_symbols p12v_nvdimm_klm *
  page197_i143
#CELL
  mstr_vreg max9634 *
  page197_i144
#ISCELL
  mstr_symbols p12v_stby *
  page197_i145
#ISCELL
  mstr_symbols p12v_stby *
  page197_i146
#ISCELL
  mstr_symbols p12v_stby *
  page197_i147
#ISCELL
  mstr_symbols p12v_stby *
  page197_i148
#ISCELL
  mstr_symbols gnd *
  page197_i51
#CELL
  mstr_discrete cap *
  page197_i52
#ISCELL
  mstr_symbols p12v_nvdimm_abc *
  page197_i53
#CELL
  mstr_discrete cap *
  page197_i54
#ISCELL
  mstr_symbols gnd *
  page197_i55
#ISCELL
  mstr_symbols p12v_nvdimm_abc *
  page197_i56
#ISCELL
  mstr_symbols gnd *
  page197_i57
#ISCELL
  mstr_symbols gnd *
  page197_i58
#CELL
  mstr_discrete cap *
  page197_i59
#ISCELL
  mstr_symbols p12v_nvdimm_def *
  page197_i60
#ISCELL
  mstr_symbols gnd *
  page197_i61
#CELL
  mstr_discrete cap *
  page197_i62
#ISCELL
  mstr_symbols p12v_nvdimm_def *
  page197_i63
#ISCELL
  mstr_symbols gnd *
  page197_i64
#CELL
  mstr_discrete cap *
  page197_i65
#ISCELL
  mstr_symbols p12v_nvdimm_abc *
  page197_i66
#CELL
  mstr_discrete cap *
  page197_i67
#ISCELL
  mstr_symbols p12v_nvdimm_def *
  page197_i68
#ISCELL
  mstr_symbols gnd *
  page197_i69
#CELL
  mstr_discrete cap *
  page197_i70
#ISCELL
  mstr_symbols p12v_nvdimm_ghj *
  page197_i71
#ISCELL
  mstr_symbols gnd *
  page197_i72
#CELL
  mstr_discrete cap *
  page197_i73
#ISCELL
  mstr_symbols p12v_nvdimm_ghj *
  page197_i74
#ISCELL
  mstr_symbols gnd *
  page197_i75
#CELL
  mstr_discrete cap *
  page197_i76
#ISCELL
  mstr_symbols p12v_nvdimm_ghj *
  page197_i77
#ISCELL
  mstr_symbols gnd *
  page197_i78
#CELL
  mstr_discrete cap *
  page197_i79
#ISCELL
  mstr_symbols p12v_nvdimm_klm *
  page197_i80
#ISCELL
  mstr_symbols gnd *
  page197_i81
#CELL
  mstr_discrete cap *
  page197_i82
#ISCELL
  mstr_symbols p12v_nvdimm_klm *
  page197_i83
#ISCELL
  mstr_symbols gnd *
  page197_i84
#CELL
  mstr_discrete cap *
  page197_i85
#ISCELL
  mstr_symbols p12v_nvdimm_klm *
  page197_i86
#CELL
  mstr_vreg max9634 *
  page197_i97
#CELL
  mstr_discrete res *
  page197_i99
#ISCELL
  mstr_misc dns *
  *
#ISCELL
  mstr_symbols intel_corp_bpage *
  *
#CELL
  mstr_vreg slg55021 *
  page198_i1
#ISCELL
  mstr_symbols gnd *
  page198_i12
#CELL
  mstr_vreg slg55021 *
  page198_i13
#ISCELL
  mstr_symbols p5v_stby *
  page198_i15
#ISCELL
  mstr_symbols gnd *
  page198_i18
#CELL
  mstr_vreg slg55021 *
  page198_i19
#ISCELL
  mstr_symbols p5v_stby *
  page198_i2
#ISCELL
  mstr_symbols p5v_stby *
  page198_i20
#ISCELL
  mstr_symbols p5v *
  page198_i21
#ISCELL
  mstr_symbols p12v *
  page198_i22
#ISCELL
  mstr_symbols p12v_stby *
  page198_i23
#CELL
  dev_discrete cap_a *
  page198_i24
#ISCELL
  mstr_symbols gnd *
  page198_i25
#CELL
  dev_discrete cap_a *
  page198_i26
#ISCELL
  mstr_symbols gnd *
  page198_i27
#CELL
  dev_discrete cap_a *
  page198_i28
#ISCELL
  mstr_symbols gnd *
  page198_i29
#ISCELL
  mstr_symbols gnd *
  page198_i3
#ISCELL
  mstr_standard offpage *
  page198_i32
#CELL
  dev_discrete cap_a *
  page198_i37
#CELL
  mstr_discrete cap *
  page198_i38
#ISCELL
  mstr_symbols gnd *
  page198_i39
#CELL
  mstr_discrete cap *
  page198_i40
#CELL
  dev_discrete cap_a *
  page198_i41
#ISCELL
  mstr_symbols gnd *
  page198_i42
#CELL
  dev_discrete cap_a *
  page198_i43
#CELL
  mstr_discrete cap *
  page198_i44
#ISCELL
  mstr_symbols gnd *
  page198_i45
#CELL
  dev_discrete cap_a *
  page198_i46
#CELL
  mstr_discrete cap *
  page198_i47
#ISCELL
  mstr_symbols gnd *
  page198_i48
#CELL
  dev_discrete cap_a *
  page198_i49
#CELL
  mstr_discrete cap *
  page198_i50
#ISCELL
  mstr_symbols gnd *
  page198_i51
#CELL
  dev_discrete cap_a *
  page198_i52
#CELL
  mstr_discrete cap *
  page198_i53
#ISCELL
  mstr_symbols gnd *
  page198_i54
#ISCELL
  mstr_standard offpage *
  page198_i58
#ISCELL
  mstr_standard offpage *
  page198_i59
#ISCELL
  mstr_symbols p3v3_stby *
  page198_i6
#CELL
  mstr_discrete cap *
  page198_i61
#ISCELL
  mstr_symbols gnd *
  page198_i63
#CELL
  dev_discrete cap_a *
  page198_i64
#ISCELL
  mstr_standard offpage *
  page198_i65
#ISCELL
  mstr_symbols gnd *
  page198_i66
#CELL
  dev_discrete cap_a *
  page198_i67
#ISCELL
  mstr_symbols p5v_stby *
  page198_i68
#CELL
  mstr_vreg slg55021 *
  page198_i69
#ISCELL
  mstr_symbols p3v3 *
  page198_i7
#ISCELL
  mstr_symbols gnd *
  page198_i70
#ISCELL
  mstr_symbols p12v_stby *
  page198_i73
#CELL
  mstr_discrete cap *
  page198_i74
#ISCELL
  mstr_symbols gnd *
  page198_i75
#CELL
  dev_discrete cap_a *
  page198_i76
#ISCELL
  mstr_symbols p12v_fan *
  page198_i77
#CELL
  mstr_discrete res *
  page198_i78
#ISCELL
  mstr_symbols p3v3_stby *
  page198_i79
#CELL
  mstr_discrete res *
  page198_i83
#ISCELL
  mstr_symbols gnd *
  page198_i84
#CELL
  mstr_discrete mosfet_n *
  page198_i85
#CELL
  mstr_discrete mosfet_n *
  page198_i86
#CELL
  mstr_discrete mosfet_n *
  page198_i87
#CELL
  mstr_discrete mosfet_n *
  page198_i88
#ISCELL
  mstr_symbols p5v_stby *
  page198_i9
#ISCELL
  mstr_misc dns *
  *
#ISCELL
  mstr_symbols design_note *
  *
#ISCELL
  mstr_symbols intel_corp_bpage *
  *
#CELL
  mstr_controller adm1278 *
  page199_i10
#CELL
  mstr_discrete res *
  page199_i100
#ISCELL
  mstr_symbols agnd0 *
  page199_i101
#CELL
  mstr_discrete res *
  page199_i102
#CELL
  dev_discrete cap_a *
  page199_i105
#ISCELL
  mstr_symbols agnd0 *
  page199_i106
#CELL
  dev_discrete cap_a *
  page199_i107
#CELL
  mstr_discrete res *
  page199_i108
#CELL
  mstr_discrete res *
  page199_i109
#ISCELL
  mstr_symbols gnd *
  page199_i11
#CELL
  mstr_discrete res *
  page199_i110
#ISCELL
  mstr_symbols agnd0 *
  page199_i112
#ISCELL
  mstr_symbols agnd0 *
  page199_i113
#ISCELL
  mstr_symbols agnd0 *
  page199_i115
#ISCELL
  mstr_symbols gnd *
  page199_i116
#ISCELL
  mstr_symbols agnd0 *
  page199_i117
#ISCELL
  mstr_symbols agnd0 *
  page199_i118
#CELL
  mstr_discrete cap *
  page199_i119
#CELL
  mstr_discrete res *
  page199_i12
#ISCELL
  mstr_symbols agnd0 *
  page199_i120
#CELL
  dev_discrete cap_a *
  page199_i121
#ISCELL
  mstr_symbols agnd0 *
  page199_i122
#CELL
  mstr_conn conn3_c95678002 *
  page199_i123
#CELL
  mstr_sconn sconn3_d53458001 *
  page199_i124
#ISCELL
  mstr_standard offpage *
  page199_i125
#ISCELL
  mstr_standard offpage *
  page199_i126
#CELL
  mstr_discrete res *
  page199_i13
#CELL
  mstr_discrete res *
  page199_i15
#CELL
  mstr_discrete res *
  page199_i16
#CELL
  mstr_discrete res *
  page199_i17
#ISCELL
  mstr_symbols agnd0 *
  page199_i18
#CELL
  mstr_discrete res *
  page199_i19
#CELL
  mstr_discrete res *
  page199_i2
#ISCELL
  mstr_symbols gnd *
  page199_i20
#ISCELL
  mstr_symbols agnd0 *
  page199_i21
#ISCELL
  mstr_symbols agnd0 *
  page199_i23
#CELL
  mstr_discrete cap *
  page199_i24
#CELL
  mstr_discrete res *
  page199_i26
#CELL
  mstr_discrete res *
  page199_i27
#CELL
  mstr_discrete res *
  page199_i28
#CELL
  mstr_discrete cap *
  page199_i3
#ISCELL
  mstr_standard offpage *
  page199_i30
#ISCELL
  mstr_standard offpage *
  page199_i31
#CELL
  mstr_discrete res *
  page199_i33
#ISCELL
  mstr_symbols agnd0 *
  page199_i34
#CELL
  mstr_discrete res *
  page199_i36
#CELL
  mstr_discrete res *
  page199_i37
#CELL
  mstr_discrete res *
  page199_i38
#CELL
  mstr_discrete res *
  page199_i41
#CELL
  mstr_discrete res *
  page199_i43
#ISCELL
  mstr_symbols gnd *
  page199_i44
#ISCELL
  mstr_standard offpage *
  page199_i45
#ISCELL
  mstr_standard offpage *
  page199_i49
#ISCELL
  mstr_standard offpage *
  page199_i50
#ISCELL
  mstr_symbols agnd0 *
  page199_i52
#CELL
  dev_discrete cap_a *
  page199_i53
#CELL
  mstr_discrete res *
  page199_i54
#CELL
  mstr_discrete res *
  page199_i55
#ISCELL
  mstr_symbols agnd0 *
  page199_i56
#CELL
  mstr_discrete npn *
  page199_i58
#ISCELL
  mstr_symbols gnd *
  page199_i59
#CELL
  mstr_discrete res *
  page199_i6
#ISCELL
  mstr_standard offpage *
  page199_i63
#ISCELL
  mstr_standard offpage *
  page199_i64
#CELL
  mstr_discrete res *
  page199_i65
#CELL
  dev_discrete cap_a *
  page199_i67
#ISCELL
  mstr_symbols agnd0 *
  page199_i68
#ISCELL
  mstr_standard offpage *
  page199_i69
#CELL
  dev_discrete cap_a *
  page199_i7
#ISCELL
  mstr_standard offpage *
  page199_i71
#ISCELL
  mstr_standard offpage *
  page199_i72
#ISCELL
  mstr_standard offpage *
  page199_i73
#ISCELL
  mstr_standard offpage *
  page199_i74
#ISCELL
  mstr_symbols p12v_stby *
  page199_i75
#ISCELL
  mstr_symbols p12v_stby *
  page199_i76
#ISCELL
  mstr_symbols p12v_stby *
  page199_i77
#ISCELL
  mstr_symbols p12v_psu *
  page199_i79
#CELL
  mstr_discrete fet_n_dual *
  page199_i82
#ISCELL
  mstr_symbols agnd0 *
  page199_i83
#CELL
  mstr_discrete res *
  page199_i84
#CELL
  mstr_discrete res *
  page199_i85
#CELL
  mstr_discrete fet_n_dual *
  page199_i86
#CELL
  mstr_discrete res *
  page199_i87
#CELL
  mstr_discrete res *
  page199_i88
#ISCELL
  mstr_symbols agnd0 *
  page199_i89
#CELL
  mstr_discrete res *
  page199_i9
#ISCELL
  mstr_symbols p12v_psu *
  page199_i90
#CELL
  mstr_discrete res *
  page199_i92
#ISCELL
  mstr_standard offpage *
  page199_i98
#CELL
  mstr_discrete zener *
  page199_i99
#ISCELL
  mstr_misc dns *
  *
#ISCELL
  mstr_symbols intel_corp_bpage *
  *
#CELL
  mstr_ttl ttl1g126_a *
  page200_i103
#ISCELL
  mstr_symbols agnd0 *
  page200_i106
#CELL
  mstr_discrete res *
  page200_i107
#CELL
  mstr_discrete res *
  page200_i108
#ISCELL
  mstr_symbols p12v_stby *
  page200_i109
#ISCELL
  mstr_symbols gnd *
  page200_i114
#ISCELL
  mstr_standard offpage *
  page200_i118
#ISCELL
  mstr_standard offpage *
  page200_i121
#ISCELL
  mstr_standard offpage *
  page200_i134
#ISCELL
  mstr_standard offpage *
  page200_i135
#ISCELL
  mstr_symbols p12v_stby *
  page200_i144
#CELL
  mstr_discrete res *
  page200_i145
#CELL
  mstr_discrete res *
  page200_i146
#ISCELL
  mstr_symbols agnd0 *
  page200_i147
#CELL
  mstr_discrete res *
  page200_i149
#ISCELL
  mstr_symbols p3v3_stby *
  page200_i150
#ISCELL
  mstr_standard offpage *
  page200_i153
#CELL
  mstr_discrete res *
  page200_i154
#CELL
  mstr_discrete cap *
  page200_i155
#ISCELL
  mstr_symbols gnd *
  page200_i156
#ISCELL
  mstr_symbols p3v3_stby *
  page200_i157
#CELL
  mstr_discrete res *
  page200_i158
#CELL
  mstr_vreg tps3700 *
  page200_i163
#CELL
  mstr_vreg tps3700 *
  page200_i170
#CELL
  mstr_discrete res *
  page200_i172
#CELL
  mstr_discrete res *
  page200_i173
#CELL
  mstr_discrete res *
  page200_i174
#CELL
  mstr_discrete res *
  page200_i175
#ISCELL
  mstr_symbols gnd *
  page200_i178
#ISCELL
  mstr_symbols gnd *
  page200_i179
#ISCELL
  mstr_symbols agnd0 *
  page200_i180
#ISCELL
  mstr_symbols agnd0 *
  page200_i181
#ISCELL
  mstr_symbols gnd *
  page200_i183
#ISCELL
  mstr_symbols p12v_stby *
  page200_i184
#CELL
  dev_discrete cap_a *
  page200_i185
#ISCELL
  mstr_symbols agnd0 *
  page200_i186
#CELL
  dev_discrete cap_a *
  page200_i187
#ISCELL
  mstr_symbols agnd0 *
  page200_i188
#CELL
  mstr_discrete res *
  page200_i189
#ISCELL
  mstr_symbols p3v3_stby *
  page200_i190
#CELL
  mstr_discrete res *
  page200_i191
#CELL
  mstr_discrete res *
  page200_i192
#ISCELL
  mstr_symbols p3v3_stby *
  page200_i194
#CELL
  mstr_discrete fet_n_dual *
  page200_i196
#ISCELL
  mstr_symbols gnd *
  page200_i197
#CELL
  mstr_discrete res *
  page200_i198
#CELL
  mstr_discrete fet_n_dual *
  page200_i199
#CELL
  mstr_vreg tps3700 *
  page200_i200
#CELL
  dev_discrete cap_a *
  page200_i201
#ISCELL
  mstr_symbols gnd *
  page200_i202
#CELL
  mstr_discrete fet_n *
  page200_i203
#CELL
  mstr_discrete res *
  page200_i204
#ISCELL
  mstr_symbols p3v3_stby *
  page200_i205
#ISCELL
  mstr_symbols gnd *
  page200_i206
#ISCELL
  mstr_standard offpage *
  page200_i207
#CELL
  mstr_discrete res *
  page200_i210
#ISCELL
  mstr_symbols p3v3_stby *
  page200_i211
#CELL
  mstr_discrete diode *
  page200_i213
#CELL
  mstr_discrete diode *
  page200_i214
#CELL
  mstr_discrete res *
  page200_i215
#ISCELL
  mstr_symbols p3v3_stby *
  page200_i216
#ISCELL
  mstr_symbols agnd0 *
  page200_i217
#CELL
  mstr_discrete res *
  page200_i218
#ISCELL
  mstr_symbols agnd0 *
  page200_i219
#CELL
  mstr_discrete diode *
  page200_i220
#ISCELL
  mstr_symbols gnd *
  page200_i221
#CELL
  mstr_discrete res *
  page200_i222
#ISCELL
  mstr_symbols p12v_stby *
  page200_i223
#ISCELL
  mstr_standard offpage *
  page200_i224
#CELL
  mstr_discrete fet_n *
  page200_i225
#ISCELL
  mstr_standard offpage *
  page200_i226
#ISCELL
  mstr_symbols gnd *
  page200_i227
#CELL
  mstr_discrete res *
  page200_i229
#CELL
  mstr_discrete res *
  page200_i230
#ISCELL
  mstr_symbols gnd *
  page200_i231
#ISCELL
  mstr_symbols p3v3_stby *
  page200_i232
#CELL
  w_hdl sc22p50v2jn-4gp *
  page200_i235
#CELL
  w_hdl sc22p50v2jn-4gp *
  page200_i236
#ISCELL
  mstr_symbols agnd0 *
  page200_i237
#ISCELL
  mstr_symbols agnd0 *
  page200_i238
#CELL
  w_hdl 232kr2f-2-gp *
  page200_i239
#CELL
  dev_discrete cap_a *
  page200_i36
#ISCELL
  mstr_standard offpage *
  page200_i37
#ISCELL
  mstr_standard offpage *
  page200_i38
#ISCELL
  mstr_symbols agnd0 *
  page200_i39
#CELL
  dev_discrete cap_a *
  page200_i40
#ISCELL
  mstr_symbols agnd0 *
  page200_i41
#CELL
  dev_discrete cap_a *
  page200_i42
#CELL
  mstr_discrete res *
  page200_i43
#CELL
  mstr_discrete res *
  page200_i44
#ISCELL
  mstr_standard offpage *
  page200_i45
#ISCELL
  mstr_standard offpage *
  page200_i46
#CELL
  mstr_discrete res *
  page200_i47
#CELL
  mstr_discrete res *
  page200_i48
#CELL
  mstr_discrete res_pwr *
  page200_i49
#CELL
  mstr_discrete res_pwr *
  page200_i50
#CELL
  mstr_discrete res *
  page200_i51
#CELL
  mstr_discrete res *
  page200_i52
#ISCELL
  mstr_symbols p12v_psu *
  page200_i53
#CELL
  mstr_discrete mosfetn_1d3s *
  page200_i54
#ISCELL
  mstr_standard offpage *
  page200_i55
#CELL
  mstr_discrete res *
  page200_i56
#CELL
  mstr_discrete mosfetn_1d3s *
  page200_i57
#CELL
  mstr_discrete res *
  page200_i58
#CELL
  mstr_discrete mosfetn_1d3s *
  page200_i59
#CELL
  mstr_discrete res *
  page200_i60
#ISCELL
  mstr_symbols p12v_stby *
  page200_i64
#CELL
  mstr_discrete res *
  page200_i70
#CELL
  mstr_discrete res *
  page200_i71
#ISCELL
  mstr_standard offpage *
  page200_i72
#ISCELL
  mstr_symbols p3v3_stby *
  page200_i78
#CELL
  mstr_discrete res *
  page200_i86
#ISCELL
  mstr_standard offpage *
  page200_i92
#ISCELL
  mstr_standard offpage *
  page200_i94
#ISCELL
  mstr_misc dns *
  *
#ISCELL
  mstr_symbols design_note *
  *
#ISCELL
  mstr_symbols intel_corp_bpage *
  *
#ISCELL
  mstr_standard offpage *
  page201_i1
#ISCELL
  mstr_standard offpage *
  page201_i10
#CELL
  mstr_discrete res *
  page201_i102
#CELL
  mstr_discrete res *
  page201_i103
#CELL
  mstr_discrete res *
  page201_i109
#ISCELL
  mstr_standard offpage *
  page201_i11
#CELL
  mstr_discrete res *
  page201_i110
#CELL
  mstr_discrete res *
  page201_i111
#ISCELL
  mstr_symbols p3v3_stby *
  page201_i112
#ISCELL
  mstr_symbols p3v3_stby *
  page201_i113
#ISCELL
  mstr_symbols p3v3_stby *
  page201_i115
#CELL
  mstr_discrete res *
  page201_i116
#ISCELL
  mstr_standard offpage *
  page201_i118
#ISCELL
  mstr_standard offpage *
  page201_i12
#CELL
  mstr_discrete res *
  page201_i120
#CELL
  mstr_discrete res *
  page201_i121
#CELL
  mstr_conn conn3_c95678002 *
  page201_i122
#ISCELL
  mstr_symbols gnd *
  page201_i123
#CELL
  mstr_discrete res *
  page201_i124
#CELL
  mstr_discrete cap *
  page201_i125
#ISCELL
  mstr_symbols gnd *
  page201_i126
#CELL
  mstr_discrete res *
  page201_i127
#CELL
  mstr_discrete res *
  page201_i128
#CELL
  mstr_discrete res *
  page201_i131
#CELL
  mstr_discrete res *
  page201_i132
#CELL
  mstr_discrete res *
  page201_i139
#ISCELL
  mstr_standard offpage *
  page201_i14
#ISCELL
  mstr_standard offpage *
  page201_i146
#CELL
  mstr_discrete res *
  page201_i147
#CELL
  mstr_discrete res *
  page201_i148
#CELL
  mstr_discrete res *
  page201_i149
#ISCELL
  mstr_standard offpage *
  page201_i15
#CELL
  mstr_discrete res *
  page201_i150
#ISCELL
  mstr_standard offpage *
  page201_i152
#CELL
  mstr_discrete res *
  page201_i154
#CELL
  mstr_controller pxe1610b *
  page201_i155
#ISCELL
  mstr_standard offpage *
  page201_i17
#ISCELL
  mstr_symbols pvccio_cpu0 *
  page201_i18
#CELL
  mstr_discrete res *
  page201_i19
#ISCELL
  mstr_standard offpage *
  page201_i2
#CELL
  mstr_discrete res *
  page201_i20
#CELL
  mstr_discrete res *
  page201_i22
#CELL
  mstr_discrete res *
  page201_i25
#CELL
  mstr_discrete res *
  page201_i26
#CELL
  mstr_discrete res *
  page201_i27
#CELL
  mstr_discrete res *
  page201_i28
#ISCELL
  mstr_symbols gnd *
  page201_i29
#ISCELL
  mstr_standard offpage *
  page201_i3
#CELL
  dev_discrete cap_a *
  page201_i30
#CELL
  mstr_discrete res *
  page201_i31
#CELL
  dev_discrete cap_a *
  page201_i32
#ISCELL
  mstr_symbols gnd *
  page201_i33
#ISCELL
  mstr_symbols gnd *
  page201_i35
#ISCELL
  mstr_symbols gnd *
  page201_i36
#CELL
  dev_discrete cap_a *
  page201_i37
#ISCELL
  mstr_symbols gnd *
  page201_i38
#CELL
  dev_discrete cap_a *
  page201_i39
#ISCELL
  mstr_standard offpage *
  page201_i4
#CELL
  mstr_discrete res *
  page201_i40
#ISCELL
  mstr_symbols gnd *
  page201_i48
#ISCELL
  mstr_standard offpage *
  page201_i5
#ISCELL
  mstr_symbols gnd *
  page201_i50
#ISCELL
  mstr_symbols pvccio_cpu0 *
  page201_i51
#CELL
  mstr_discrete res *
  page201_i52
#ISCELL
  mstr_symbols vcc_core *
  page201_i53
#CELL
  mstr_discrete res *
  page201_i54
#CELL
  mstr_discrete res *
  page201_i55
#CELL
  mstr_discrete res *
  page201_i56
#ISCELL
  mstr_symbols gnd *
  page201_i58
#ISCELL
  mstr_standard offpage *
  page201_i6
#CELL
  mstr_discrete cap *
  page201_i60
#ISCELL
  mstr_symbols gnd *
  page201_i61
#CELL
  mstr_discrete cap *
  page201_i64
#CELL
  mstr_discrete cap *
  page201_i66
#ISCELL
  mstr_symbols gnd *
  page201_i67
#CELL
  mstr_discrete cap *
  page201_i68
#ISCELL
  mstr_symbols gnd *
  page201_i69
#ISCELL
  mstr_standard offpage *
  page201_i7
#CELL
  mstr_discrete cap *
  page201_i70
#ISCELL
  mstr_standard offpage *
  page201_i73
#ISCELL
  mstr_standard offpage *
  page201_i74
#ISCELL
  mstr_standard offpage *
  page201_i75
#ISCELL
  mstr_standard offpage *
  page201_i76
#ISCELL
  mstr_standard offpage *
  page201_i77
#ISCELL
  mstr_standard offpage *
  page201_i78
#ISCELL
  mstr_standard offpage *
  page201_i79
#ISCELL
  mstr_standard offpage *
  page201_i8
#ISCELL
  mstr_standard offpage *
  page201_i80
#ISCELL
  mstr_standard offpage *
  page201_i82
#ISCELL
  mstr_standard offpage *
  page201_i83
#ISCELL
  mstr_standard offpage *
  page201_i84
#ISCELL
  mstr_standard offpage *
  page201_i85
#ISCELL
  mstr_standard offpage *
  page201_i87
#ISCELL
  mstr_standard offpage *
  page201_i88
#ISCELL
  mstr_standard offpage *
  page201_i89
#ISCELL
  mstr_standard offpage *
  page201_i9
#ISCELL
  mstr_standard offpage *
  page201_i90
#ISCELL
  mstr_standard offpage *
  page201_i91
#ISCELL
  mstr_standard offpage *
  page201_i92
#ISCELL
  mstr_standard offpage *
  page201_i93
#ISCELL
  mstr_standard offpage *
  page201_i94
#ISCELL
  mstr_standard offpage *
  page201_i95
#ISCELL
  mstr_standard offpage *
  page201_i96
#ISCELL
  mstr_standard offpage *
  page201_i97
#CELL
  mstr_discrete res *
  page201_i98
#ISCELL
  mstr_misc dns *
  *
#ISCELL
  mstr_symbols intel_corp_bpage *
  *
#ISCELL
  mstr_standard offpage *
  page202_i1
#ISCELL
  mstr_standard offpage *
  page202_i10
#ISCELL
  mstr_standard offpage *
  page202_i11
#ISCELL
  mstr_standard offpage *
  page202_i12
#ISCELL
  mstr_symbols gnd *
  page202_i13
#CELL
  mstr_discrete cap *
  page202_i18
#CELL
  dev_discrete cap_a *
  page202_i19
#ISCELL
  mstr_standard offpage *
  page202_i2
#CELL
  mstr_discrete cap *
  page202_i22
#CELL
  mstr_discrete cap *
  page202_i24
#CELL
  dev_discrete cap_a *
  page202_i25
#ISCELL
  mstr_symbols pvccin_cpu0 *
  page202_i26
#CELL
  dev_discrete cap_a *
  page202_i27
#ISCELL
  mstr_symbols gnd *
  page202_i28
#CELL
  mstr_discrete inductor *
  page202_i29
#ISCELL
  mstr_standard offpage *
  page202_i3
#ISCELL
  mstr_symbols gnd *
  page202_i30
#CELL
  mstr_discrete cap *
  page202_i32
#CELL
  mstr_discrete res *
  page202_i33
#CELL
  mstr_discrete cap *
  page202_i34
#CELL
  dev_discrete cap_a *
  page202_i35
#CELL
  mstr_discrete cap *
  page202_i36
#CELL
  mstr_discrete cap *
  page202_i37
#CELL
  mstr_discrete cap *
  page202_i38
#CELL
  mstr_discrete res *
  page202_i39
#ISCELL
  mstr_symbols pvccin_cpu0 *
  page202_i4
#ISCELL
  mstr_standard offpage *
  page202_i40
#ISCELL
  mstr_symbols vcc_core *
  page202_i41
#CELL
  mstr_discrete cap *
  page202_i42
#ISCELL
  mstr_symbols gnd *
  page202_i43
#ISCELL
  mstr_symbols vcc_core *
  page202_i44
#CELL
  mstr_discrete cap *
  page202_i45
#CELL
  dev_discrete cap_a *
  page202_i46
#CELL
  mstr_discrete cap *
  page202_i47
#CELL
  mstr_discrete cap *
  page202_i48
#CELL
  mstr_discrete cap *
  page202_i49
#CELL
  mstr_discrete inductor *
  page202_i5
#ISCELL
  mstr_standard offpage *
  page202_i50
#CELL
  mstr_discrete cap *
  page202_i51
#ISCELL
  mstr_symbols gnd *
  page202_i52
#ISCELL
  mstr_symbols p5v_stby *
  page202_i59
#ISCELL
  mstr_symbols p5v_stby *
  page202_i60
#CELL
  dev_discrete cap_a *
  page202_i61
#CELL
  dev_discrete cap_a *
  page202_i62
#CELL
  mstr_discrete ir354xx *
  page202_i63
#CELL
  mstr_discrete ir354xx *
  page202_i64
#CELL
  mstr_discrete res *
  page202_i65
#ISCELL
  mstr_symbols gnd *
  page202_i66
#CELL
  mstr_discrete res *
  page202_i67
#ISCELL
  mstr_symbols gnd *
  page202_i68
#CELL
  dev_discrete cap_a *
  page202_i70
#ISCELL
  mstr_symbols gnd *
  page202_i71
#ISCELL
  mstr_symbols gnd *
  page202_i73
#CELL
  w_hdl 3d01r5f-gp *
  page202_i75
#CELL
  w_hdl sc2k2p50v3kx-gp *
  page202_i76
#ISCELL
  mstr_symbols gnd *
  page202_i77
#CELL
  mstr_discrete cap *
  page202_i78
#ISCELL
  mstr_symbols gnd *
  page202_i8
#ISCELL
  mstr_symbols gnd *
  page202_i80
#CELL
  dev_discrete cap_a *
  page202_i81
#CELL
  w_hdl sc2k2p50v3kx-gp *
  page202_i82
#CELL
  w_hdl 3d01r5f-gp *
  page202_i83
#ISCELL
  mstr_symbols gnd *
  page202_i84
#ISCELL
  mstr_symbols gnd *
  page202_i86
#CELL
  mstr_discrete cap *
  page202_i87
#CELL
  mstr_discrete res *
  page202_i88
#CELL
  mstr_discrete res *
  page202_i89
#CELL
  dev_discrete cap_a *
  page202_i9
#ISCELL
  mstr_misc dns *
  *
#ISCELL
  mstr_symbols intel_corp_bpage *
  *
#CELL
  mstr_discrete cap *
  page203_i1
#ISCELL
  mstr_symbols gnd *
  page203_i100
#CELL
  w_hdl sc2k2p50v3kx-gp *
  page203_i101
#CELL
  w_hdl 3d01r5f-gp *
  page203_i102
#ISCELL
  mstr_symbols gnd *
  page203_i103
#ISCELL
  mstr_symbols gnd *
  page203_i104
#CELL
  w_hdl 3d01r5f-gp *
  page203_i105
#CELL
  w_hdl sc2k2p50v3kx-gp *
  page203_i106
#ISCELL
  mstr_symbols gnd *
  page203_i107
#CELL
  mstr_discrete cap *
  page203_i108
#ISCELL
  mstr_symbols pvccin_cpu0 *
  page203_i109
#CELL
  mstr_discrete res *
  page203_i110
#CELL
  mstr_discrete res *
  page203_i111
#ISCELL
  mstr_symbols pvccin_cpu0 *
  page203_i12
#ISCELL
  mstr_symbols gnd *
  page203_i14
#CELL
  mstr_discrete inductor *
  page203_i15
#CELL
  mstr_discrete capp *
  page203_i16
#ISCELL
  mstr_symbols gnd *
  page203_i17
#CELL
  mstr_discrete capp *
  page203_i18
#ISCELL
  mstr_standard offpage *
  page203_i19
#CELL
  mstr_discrete cap *
  page203_i2
#ISCELL
  mstr_standard offpage *
  page203_i20
#ISCELL
  mstr_standard offpage *
  page203_i21
#CELL
  mstr_discrete inductor *
  page203_i24
#CELL
  dev_discrete cap_a *
  page203_i25
#ISCELL
  mstr_symbols gnd *
  page203_i26
#ISCELL
  mstr_symbols gnd *
  page203_i27
#CELL
  mstr_discrete capp *
  page203_i28
#CELL
  mstr_discrete capp *
  page203_i29
#CELL
  mstr_discrete cap *
  page203_i3
#CELL
  mstr_discrete capp *
  page203_i30
#CELL
  mstr_discrete capp *
  page203_i32
#ISCELL
  mstr_symbols pvccin_cpu0 *
  page203_i33
#CELL
  mstr_discrete capp *
  page203_i34
#CELL
  mstr_discrete res *
  page203_i38
#ISCELL
  mstr_symbols vcc_core *
  page203_i39
#CELL
  mstr_discrete cap *
  page203_i40
#CELL
  dev_discrete cap_a *
  page203_i41
#CELL
  mstr_discrete cap *
  page203_i42
#CELL
  mstr_discrete cap *
  page203_i45
#CELL
  dev_discrete cap_a *
  page203_i46
#CELL
  mstr_discrete cap *
  page203_i47
#CELL
  mstr_discrete cap *
  page203_i48
#CELL
  dev_discrete cap_a *
  page203_i49
#ISCELL
  mstr_standard offpage *
  page203_i5
#CELL
  mstr_discrete res *
  page203_i50
#CELL
  mstr_discrete cap *
  page203_i51
#CELL
  dev_discrete cap_a *
  page203_i52
#CELL
  mstr_discrete cap *
  page203_i53
#CELL
  mstr_discrete cap *
  page203_i54
#ISCELL
  mstr_standard offpage *
  page203_i55
#ISCELL
  mstr_symbols gnd *
  page203_i56
#CELL
  mstr_discrete cap *
  page203_i57
#CELL
  mstr_discrete cap *
  page203_i58
#CELL
  mstr_discrete cap *
  page203_i59
#ISCELL
  mstr_standard offpage *
  page203_i6
#ISCELL
  mstr_standard offpage *
  page203_i60
#ISCELL
  mstr_symbols vcc_core *
  page203_i61
#ISCELL
  mstr_symbols gnd *
  page203_i62
#ISCELL
  mstr_symbols gnd *
  page203_i63
#ISCELL
  mstr_symbols p5v_stby *
  page203_i64
#ISCELL
  mstr_symbols p5v_stby *
  page203_i65
#CELL
  dev_discrete cap_a *
  page203_i66
#CELL
  mstr_discrete res *
  page203_i67
#CELL
  dev_discrete cap_a *
  page203_i68
#CELL
  dev_discrete cap_a *
  page203_i69
#ISCELL
  mstr_standard offpage *
  page203_i7
#CELL
  mstr_discrete ir354xx *
  page203_i70
#CELL
  mstr_discrete ir354xx *
  page203_i71
#CELL
  mstr_discrete res *
  page203_i89
#ISCELL
  mstr_symbols gnd *
  page203_i90
#CELL
  mstr_discrete res *
  page203_i91
#ISCELL
  mstr_symbols gnd *
  page203_i92
#CELL
  dev_discrete cap_a *
  page203_i93
#ISCELL
  mstr_symbols gnd *
  page203_i94
#CELL
  dev_discrete cap_a *
  page203_i96
#ISCELL
  mstr_symbols gnd *
  page203_i97
#CELL
  mstr_discrete cap *
  page203_i99
#ISCELL
  mstr_misc dns *
  *
#ISCELL
  mstr_symbols design_note *
  *
#ISCELL
  mstr_symbols intel_corp_bpage *
  *
#ISCELL
  mstr_standard offpage *
  page204_i1
#ISCELL
  mstr_symbols gnd *
  page204_i13
#CELL
  mstr_discrete cap *
  page204_i18
#CELL
  dev_discrete cap_a *
  page204_i19
#ISCELL
  mstr_standard offpage *
  page204_i2
#CELL
  mstr_discrete cap *
  page204_i22
#ISCELL
  mstr_standard offpage *
  page204_i3
#CELL
  mstr_discrete res *
  page204_i33
#CELL
  mstr_discrete cap *
  page204_i34
#CELL
  dev_discrete cap_a *
  page204_i35
#CELL
  mstr_discrete cap *
  page204_i36
#CELL
  mstr_discrete cap *
  page204_i37
#CELL
  mstr_discrete cap *
  page204_i38
#ISCELL
  mstr_symbols pvccin_cpu0 *
  page204_i4
#ISCELL
  mstr_standard offpage *
  page204_i40
#ISCELL
  mstr_symbols vcc_core *
  page204_i41
#CELL
  mstr_discrete cap *
  page204_i42
#ISCELL
  mstr_symbols gnd *
  page204_i43
#ISCELL
  mstr_symbols vcc_core *
  page204_i44
#CELL
  mstr_discrete res *
  page204_i45
#CELL
  mstr_discrete inductor *
  page204_i46
#CELL
  mstr_discrete capp *
  page204_i48
#ISCELL
  mstr_symbols gnd *
  page204_i49
#CELL
  mstr_discrete inductor *
  page204_i5
#CELL
  mstr_discrete capp *
  page204_i50
#CELL
  dev_discrete cap_a *
  page204_i51
#ISCELL
  mstr_symbols gnd *
  page204_i52
#CELL
  mstr_analog adm4073 *
  page204_i53
#ISCELL
  mstr_symbols gnd *
  page204_i54
#ISCELL
  mstr_standard offpage *
  page204_i55
#ISCELL
  mstr_standard offpage *
  page204_i56
#ISCELL
  mstr_standard offpage *
  page204_i57
#ISCELL
  mstr_symbols pvccin_cpu0 *
  page204_i58
#ISCELL
  mstr_symbols gnd *
  page204_i59
#CELL
  mstr_discrete res *
  page204_i60
#CELL
  mstr_discrete res *
  page204_i61
#CELL
  mstr_discrete res *
  page204_i62
#CELL
  mstr_discrete res *
  page204_i63
#CELL
  mstr_discrete res *
  page204_i64
#ISCELL
  mstr_standard offpage *
  page204_i65
#ISCELL
  mstr_standard offpage *
  page204_i66
#CELL
  mstr_discrete capp *
  page204_i67
#ISCELL
  mstr_symbols p12v_stby *
  page204_i68
#ISCELL
  mstr_symbols p5v_stby *
  page204_i69
#CELL
  dev_discrete cap_a *
  page204_i70
#CELL
  mstr_discrete ir354xx *
  page204_i71
#ISCELL
  mstr_symbols gnd *
  page204_i8
#CELL
  mstr_discrete res *
  page204_i83
#ISCELL
  mstr_symbols gnd *
  page204_i84
#CELL
  dev_discrete cap_a *
  page204_i85
#ISCELL
  mstr_symbols gnd *
  page204_i86
#CELL
  mstr_discrete cap *
  page204_i88
#ISCELL
  mstr_symbols gnd *
  page204_i89
#CELL
  dev_discrete cap_a *
  page204_i9
#CELL
  w_hdl sc2k2p50v3kx-gp *
  page204_i90
#CELL
  w_hdl 3d01r5f-gp *
  page204_i91
#ISCELL
  mstr_symbols gnd *
  page204_i92
#CELL
  mstr_discrete res *
  page204_i93
#ISCELL
  mstr_misc dns *
  *
#ISCELL
  mstr_symbols design_note *
  *
#ISCELL
  mstr_symbols intel_corp_bpage *
  *
#ISCELL
  mstr_standard offpage *
  page205_i1
#ISCELL
  mstr_symbols pvsa_cpu0 *
  page205_i11
#CELL
  mstr_discrete capp *
  page205_i12
#ISCELL
  mstr_symbols gnd *
  page205_i13
#CELL
  mstr_discrete capp *
  page205_i14
#ISCELL
  mstr_symbols gnd *
  page205_i15
#CELL
  mstr_discrete cap *
  page205_i16
#CELL
  dev_discrete cap_a *
  page205_i18
#CELL
  mstr_discrete res *
  page205_i19
#ISCELL
  mstr_standard offpage *
  page205_i2
#CELL
  mstr_discrete cap *
  page205_i20
#ISCELL
  mstr_standard offpage *
  page205_i22
#ISCELL
  mstr_symbols pvsa_cpu0 *
  page205_i23
#CELL
  mstr_discrete res *
  page205_i24
#CELL
  mstr_discrete cap *
  page205_i25
#CELL
  mstr_discrete res *
  page205_i26
#ISCELL
  mstr_standard offpage *
  page205_i27
#ISCELL
  mstr_symbols gnd *
  page205_i28
#CELL
  mstr_discrete res *
  page205_i29
#ISCELL
  mstr_standard offpage *
  page205_i3
#CELL
  mstr_discrete res *
  page205_i30
#CELL
  dev_discrete cap_a *
  page205_i31
#CELL
  mstr_discrete cap *
  page205_i32
#CELL
  mstr_discrete cap *
  page205_i33
#CELL
  mstr_discrete cap *
  page205_i34
#CELL
  mstr_discrete cap *
  page205_i35
#ISCELL
  mstr_symbols vcc_core *
  page205_i36
#CELL
  mstr_discrete res *
  page205_i37
#ISCELL
  mstr_standard offpage *
  page205_i38
#ISCELL
  mstr_symbols gnd *
  page205_i39
#ISCELL
  mstr_symbols pvsa_cpu0 *
  page205_i4
#ISCELL
  mstr_standard offpage *
  page205_i40
#ISCELL
  mstr_standard offpage *
  page205_i41
#ISCELL
  mstr_symbols p5v_stby *
  page205_i42
#CELL
  dev_discrete cap_a *
  page205_i43
#CELL
  mstr_discrete res *
  page205_i45
#CELL
  mstr_discrete ir354xx *
  page205_i46
#CELL
  dev_discrete cap_a *
  page205_i5
#ISCELL
  mstr_symbols gnd *
  page205_i6
#CELL
  mstr_discrete res *
  page205_i62
#ISCELL
  mstr_symbols gnd *
  page205_i63
#CELL
  w_hdl sc2k2p50v3kx-gp *
  page205_i64
#CELL
  mstr_discrete cap *
  page205_i65
#ISCELL
  mstr_symbols gnd *
  page205_i66
#ISCELL
  mstr_symbols gnd *
  page205_i67
#CELL
  w_hdl 3d01r5f-gp *
  page205_i68
#CELL
  dev_discrete cap_a *
  page205_i69
#CELL
  mstr_discrete inductor *
  page205_i7
#ISCELL
  mstr_symbols gnd *
  page205_i70
#CELL
  mstr_discrete res *
  page205_i72
#ISCELL
  mstr_misc dns *
  *
#ISCELL
  mstr_symbols design_note *
  *
#ISCELL
  mstr_symbols intel_corp_bpage *
  *
#ISCELL
  mstr_symbols pvccio_cpu1 *
  page206_i1
#ISCELL
  mstr_standard offpage *
  page206_i10
#ISCELL
  mstr_standard offpage *
  page206_i100
#ISCELL
  mstr_standard offpage *
  page206_i101
#ISCELL
  mstr_standard offpage *
  page206_i102
#ISCELL
  mstr_symbols p3v3_stby *
  page206_i103
#ISCELL
  mstr_symbols p3v3_stby *
  page206_i104
#ISCELL
  mstr_standard offpage *
  page206_i109
#ISCELL
  mstr_standard offpage *
  page206_i11
#CELL
  mstr_discrete res *
  page206_i111
#CELL
  mstr_discrete res *
  page206_i112
#CELL
  mstr_discrete res *
  page206_i113
#CELL
  mstr_discrete cap *
  page206_i114
#ISCELL
  mstr_symbols gnd *
  page206_i115
#CELL
  mstr_discrete res *
  page206_i116
#CELL
  mstr_discrete res *
  page206_i117
#CELL
  mstr_discrete res *
  page206_i119
#ISCELL
  mstr_standard offpage *
  page206_i12
#CELL
  mstr_discrete res *
  page206_i120
#CELL
  mstr_discrete res *
  page206_i122
#CELL
  mstr_discrete res *
  page206_i123
#CELL
  mstr_discrete res *
  page206_i124
#CELL
  mstr_discrete res *
  page206_i125
#CELL
  mstr_discrete res *
  page206_i126
#ISCELL
  mstr_standard offpage *
  page206_i127
#CELL
  mstr_discrete res *
  page206_i128
#ISCELL
  mstr_standard offpage *
  page206_i129
#ISCELL
  mstr_standard offpage *
  page206_i13
#CELL
  mstr_controller pxe1610b *
  page206_i130
#ISCELL
  mstr_standard offpage *
  page206_i14
#ISCELL
  mstr_standard offpage *
  page206_i15
#ISCELL
  mstr_standard offpage *
  page206_i16
#ISCELL
  mstr_standard offpage *
  page206_i17
#ISCELL
  mstr_standard offpage *
  page206_i18
#ISCELL
  mstr_standard offpage *
  page206_i23
#ISCELL
  mstr_standard offpage *
  page206_i24
#ISCELL
  mstr_standard offpage *
  page206_i26
#CELL
  mstr_discrete res *
  page206_i27
#CELL
  mstr_discrete res *
  page206_i28
#CELL
  dev_discrete cap_a *
  page206_i29
#ISCELL
  mstr_symbols gnd *
  page206_i30
#CELL
  dev_discrete cap_a *
  page206_i31
#ISCELL
  mstr_symbols gnd *
  page206_i32
#CELL
  mstr_discrete res *
  page206_i33
#CELL
  mstr_discrete res *
  page206_i34
#CELL
  mstr_discrete res *
  page206_i35
#CELL
  mstr_discrete res *
  page206_i36
#CELL
  mstr_discrete res *
  page206_i37
#CELL
  mstr_discrete res *
  page206_i38
#CELL
  mstr_discrete res *
  page206_i4
#ISCELL
  mstr_symbols gnd *
  page206_i40
#CELL
  dev_discrete cap_a *
  page206_i41
#CELL
  dev_discrete cap_a *
  page206_i42
#ISCELL
  mstr_symbols gnd *
  page206_i43
#ISCELL
  mstr_symbols gnd *
  page206_i44
#CELL
  mstr_discrete res *
  page206_i46
#ISCELL
  mstr_symbols pvccio_cpu1 *
  page206_i47
#ISCELL
  mstr_symbols vcc_core *
  page206_i48
#CELL
  mstr_discrete res *
  page206_i49
#ISCELL
  mstr_standard offpage *
  page206_i5
#ISCELL
  mstr_standard offpage *
  page206_i50
#CELL
  mstr_discrete res *
  page206_i53
#CELL
  mstr_discrete res *
  page206_i54
#CELL
  mstr_discrete res *
  page206_i56
#ISCELL
  mstr_symbols gnd *
  page206_i57
#CELL
  mstr_discrete res *
  page206_i6
#ISCELL
  mstr_symbols gnd *
  page206_i65
#ISCELL
  mstr_symbols gnd *
  page206_i67
#CELL
  mstr_discrete cap *
  page206_i68
#CELL
  mstr_discrete cap *
  page206_i69
#CELL
  mstr_discrete res *
  page206_i7
#ISCELL
  mstr_symbols gnd *
  page206_i70
#CELL
  mstr_discrete cap *
  page206_i71
#ISCELL
  mstr_symbols gnd *
  page206_i72
#CELL
  mstr_discrete cap *
  page206_i73
#ISCELL
  mstr_symbols gnd *
  page206_i74
#CELL
  mstr_discrete res *
  page206_i77
#CELL
  mstr_discrete cap *
  page206_i78
#CELL
  mstr_discrete res *
  page206_i79
#ISCELL
  mstr_standard offpage *
  page206_i8
#ISCELL
  mstr_standard offpage *
  page206_i80
#ISCELL
  mstr_standard offpage *
  page206_i81
#ISCELL
  mstr_standard offpage *
  page206_i82
#ISCELL
  mstr_standard offpage *
  page206_i83
#ISCELL
  mstr_standard offpage *
  page206_i84
#ISCELL
  mstr_standard offpage *
  page206_i85
#ISCELL
  mstr_standard offpage *
  page206_i86
#ISCELL
  mstr_standard offpage *
  page206_i87
#ISCELL
  mstr_standard offpage *
  page206_i88
#ISCELL
  mstr_standard offpage *
  page206_i89
#ISCELL
  mstr_standard offpage *
  page206_i9
#ISCELL
  mstr_standard offpage *
  page206_i90
#ISCELL
  mstr_standard offpage *
  page206_i91
#ISCELL
  mstr_standard offpage *
  page206_i92
#ISCELL
  mstr_standard offpage *
  page206_i94
#ISCELL
  mstr_standard offpage *
  page206_i95
#ISCELL
  mstr_standard offpage *
  page206_i96
#ISCELL
  mstr_standard offpage *
  page206_i97
#ISCELL
  mstr_standard offpage *
  page206_i98
#ISCELL
  mstr_standard offpage *
  page206_i99
#ISCELL
  mstr_misc dns *
  *
#ISCELL
  mstr_symbols intel_corp_bpage *
  *
#ISCELL
  mstr_standard offpage *
  page207_i1
#CELL
  mstr_discrete inductor *
  page207_i10
#ISCELL
  mstr_standard offpage *
  page207_i11
#ISCELL
  mstr_standard offpage *
  page207_i13
#ISCELL
  mstr_symbols pvccin_cpu1 *
  page207_i14
#CELL
  mstr_discrete inductor *
  page207_i16
#ISCELL
  mstr_symbols gnd *
  page207_i17
#CELL
  dev_discrete cap_a *
  page207_i18
#ISCELL
  mstr_symbols gnd *
  page207_i19
#CELL
  mstr_discrete ir354xx *
  page207_i20
#ISCELL
  mstr_symbols gnd *
  page207_i23
#CELL
  mstr_discrete ir354xx *
  page207_i24
#CELL
  mstr_discrete res *
  page207_i26
#ISCELL
  mstr_symbols vcc_core *
  page207_i27
#CELL
  mstr_discrete cap *
  page207_i28
#CELL
  dev_discrete cap_a *
  page207_i29
#ISCELL
  mstr_standard offpage *
  page207_i3
#CELL
  mstr_discrete cap *
  page207_i30
#CELL
  mstr_discrete cap *
  page207_i32
#CELL
  dev_discrete cap_a *
  page207_i33
#CELL
  mstr_discrete cap *
  page207_i34
#CELL
  mstr_discrete cap *
  page207_i36
#CELL
  dev_discrete cap_a *
  page207_i37
#CELL
  mstr_discrete cap *
  page207_i38
#CELL
  mstr_discrete res *
  page207_i39
#CELL
  mstr_discrete cap *
  page207_i40
#CELL
  dev_discrete cap_a *
  page207_i41
#CELL
  mstr_discrete cap *
  page207_i42
#CELL
  mstr_discrete cap *
  page207_i43
#CELL
  mstr_discrete cap *
  page207_i44
#ISCELL
  mstr_standard offpage *
  page207_i45
#CELL
  mstr_discrete cap *
  page207_i48
#ISCELL
  mstr_symbols gnd *
  page207_i49
#CELL
  mstr_discrete cap *
  page207_i50
#CELL
  mstr_discrete cap *
  page207_i51
#ISCELL
  mstr_standard offpage *
  page207_i52
#ISCELL
  mstr_symbols vcc_core *
  page207_i53
#CELL
  mstr_discrete cap *
  page207_i54
#ISCELL
  mstr_symbols gnd *
  page207_i55
#ISCELL
  mstr_symbols p5v_stby *
  page207_i56
#ISCELL
  mstr_symbols p5v_stby *
  page207_i57
#CELL
  dev_discrete cap_a *
  page207_i58
#CELL
  dev_discrete cap_a *
  page207_i59
#ISCELL
  mstr_standard offpage *
  page207_i62
#ISCELL
  mstr_standard offpage *
  page207_i64
#CELL
  mstr_discrete res *
  page207_i67
#CELL
  mstr_discrete res *
  page207_i68
#ISCELL
  mstr_symbols gnd *
  page207_i69
#ISCELL
  mstr_symbols pvccin_cpu1 *
  page207_i7
#ISCELL
  mstr_symbols gnd *
  page207_i70
#CELL
  dev_discrete cap_a *
  page207_i71
#ISCELL
  mstr_symbols gnd *
  page207_i72
#CELL
  mstr_discrete cap *
  page207_i74
#ISCELL
  mstr_symbols gnd *
  page207_i75
#CELL
  w_hdl 3d01r5f-gp *
  page207_i76
#CELL
  w_hdl sc2k2p50v3kx-gp *
  page207_i77
#ISCELL
  mstr_symbols gnd *
  page207_i78
#CELL
  dev_discrete cap_a *
  page207_i8
#ISCELL
  mstr_symbols gnd *
  page207_i80
#CELL
  dev_discrete cap_a *
  page207_i81
#CELL
  mstr_discrete cap *
  page207_i82
#ISCELL
  mstr_symbols gnd *
  page207_i83
#CELL
  w_hdl sc2k2p50v3kx-gp *
  page207_i84
#CELL
  w_hdl 3d01r5f-gp *
  page207_i85
#ISCELL
  mstr_symbols gnd *
  page207_i86
#CELL
  mstr_discrete res *
  page207_i87
#CELL
  mstr_discrete res *
  page207_i88
#ISCELL
  mstr_symbols gnd *
  page207_i9
#ISCELL
  mstr_misc dns *
  *
#ISCELL
  mstr_symbols intel_corp_bpage *
  *
#ISCELL
  mstr_standard offpage *
  page208_i1
#ISCELL
  mstr_symbols gnd *
  page208_i10
#CELL
  mstr_discrete inductor *
  page208_i11
#CELL
  mstr_discrete capp *
  page208_i12
#ISCELL
  mstr_symbols gnd *
  page208_i13
#CELL
  mstr_discrete capp *
  page208_i14
#ISCELL
  mstr_standard offpage *
  page208_i16
#ISCELL
  mstr_standard offpage *
  page208_i17
#ISCELL
  mstr_symbols pvccin_cpu1 *
  page208_i18
#CELL
  mstr_discrete inductor *
  page208_i20
#ISCELL
  mstr_symbols gnd *
  page208_i21
#CELL
  dev_discrete cap_a *
  page208_i22
#ISCELL
  mstr_symbols gnd *
  page208_i23
#CELL
  mstr_discrete capp *
  page208_i24
#CELL
  mstr_discrete capp *
  page208_i25
#CELL
  mstr_discrete capp *
  page208_i26
#CELL
  mstr_discrete ir354xx *
  page208_i27
#CELL
  mstr_discrete capp *
  page208_i28
#ISCELL
  mstr_symbols pvccin_cpu1 *
  page208_i29
#ISCELL
  mstr_standard offpage *
  page208_i3
#CELL
  mstr_discrete capp *
  page208_i30
#ISCELL
  mstr_symbols gnd *
  page208_i33
#CELL
  mstr_discrete res *
  page208_i36
#ISCELL
  mstr_symbols vcc_core *
  page208_i37
#CELL
  mstr_discrete cap *
  page208_i38
#CELL
  dev_discrete cap_a *
  page208_i39
#CELL
  mstr_discrete cap *
  page208_i40
#CELL
  mstr_discrete cap *
  page208_i43
#CELL
  dev_discrete cap_a *
  page208_i44
#CELL
  mstr_discrete cap *
  page208_i45
#CELL
  mstr_discrete cap *
  page208_i46
#CELL
  dev_discrete cap_a *
  page208_i47
#CELL
  mstr_discrete cap *
  page208_i48
#CELL
  mstr_discrete res *
  page208_i49
#CELL
  mstr_discrete cap *
  page208_i50
#CELL
  dev_discrete cap_a *
  page208_i51
#CELL
  mstr_discrete cap *
  page208_i52
#CELL
  mstr_discrete cap *
  page208_i53
#CELL
  mstr_discrete cap *
  page208_i54
#CELL
  mstr_discrete cap *
  page208_i55
#ISCELL
  mstr_standard offpage *
  page208_i56
#ISCELL
  mstr_symbols gnd *
  page208_i57
#CELL
  mstr_discrete cap *
  page208_i58
#CELL
  mstr_discrete cap *
  page208_i59
#CELL
  mstr_discrete cap *
  page208_i60
#ISCELL
  mstr_standard offpage *
  page208_i61
#ISCELL
  mstr_symbols vcc_core *
  page208_i62
#ISCELL
  mstr_symbols gnd *
  page208_i63
#ISCELL
  mstr_symbols p5v_stby *
  page208_i64
#ISCELL
  mstr_symbols p5v_stby *
  page208_i65
#CELL
  dev_discrete cap_a *
  page208_i66
#CELL
  dev_discrete cap_a *
  page208_i67
#CELL
  mstr_discrete res *
  page208_i7
#ISCELL
  mstr_standard offpage *
  page208_i70
#CELL
  mstr_discrete ir354xx *
  page208_i71
#ISCELL
  mstr_standard offpage *
  page208_i72
#CELL
  mstr_discrete res *
  page208_i75
#CELL
  mstr_discrete res *
  page208_i76
#ISCELL
  mstr_symbols gnd *
  page208_i77
#ISCELL
  mstr_symbols gnd *
  page208_i78
#ISCELL
  mstr_symbols gnd *
  page208_i79
#ISCELL
  mstr_symbols pvccin_cpu1 *
  page208_i8
#CELL
  dev_discrete cap_a *
  page208_i80
#CELL
  mstr_discrete cap *
  page208_i82
#ISCELL
  mstr_symbols gnd *
  page208_i83
#CELL
  w_hdl sc2k2p50v3kx-gp *
  page208_i84
#ISCELL
  mstr_symbols gnd *
  page208_i85
#CELL
  w_hdl 3d01r5f-gp *
  page208_i86
#CELL
  dev_discrete cap_a *
  page208_i87
#ISCELL
  mstr_symbols gnd *
  page208_i88
#CELL
  dev_discrete cap_a *
  page208_i9
#CELL
  mstr_discrete cap *
  page208_i90
#ISCELL
  mstr_symbols gnd *
  page208_i91
#CELL
  w_hdl sc2k2p50v3kx-gp *
  page208_i92
#ISCELL
  mstr_symbols gnd *
  page208_i93
#CELL
  w_hdl 3d01r5f-gp *
  page208_i94
#CELL
  mstr_discrete res *
  page208_i96
#CELL
  mstr_discrete res *
  page208_i97
#ISCELL
  mstr_misc dns *
  *
#ISCELL
  mstr_symbols design_note *
  *
#ISCELL
  mstr_symbols intel_corp_bpage *
  *
#ISCELL
  mstr_standard offpage *
  page209_i1
#CELL
  mstr_discrete res *
  page209_i10
#CELL
  mstr_discrete res *
  page209_i11
#ISCELL
  mstr_symbols gnd *
  page209_i12
#ISCELL
  mstr_standard offpage *
  page209_i13
#ISCELL
  mstr_standard offpage *
  page209_i14
#CELL
  mstr_discrete res *
  page209_i15
#CELL
  mstr_discrete cap *
  page209_i16
#CELL
  dev_discrete cap_a *
  page209_i17
#CELL
  mstr_discrete cap *
  page209_i18
#ISCELL
  mstr_symbols pvccin_cpu1 *
  page209_i19
#ISCELL
  mstr_standard offpage *
  page209_i2
#CELL
  mstr_discrete cap *
  page209_i20
#CELL
  dev_discrete cap_a *
  page209_i21
#CELL
  mstr_discrete cap *
  page209_i22
#ISCELL
  mstr_symbols vcc_core *
  page209_i23
#CELL
  mstr_discrete res *
  page209_i24
#ISCELL
  mstr_symbols gnd *
  page209_i26
#ISCELL
  mstr_standard offpage *
  page209_i27
#ISCELL
  mstr_symbols gnd *
  page209_i29
#CELL
  mstr_discrete res *
  page209_i3
#CELL
  dev_discrete cap_a *
  page209_i30
#CELL
  mstr_discrete inductor *
  page209_i32
#ISCELL
  mstr_symbols gnd *
  page209_i34
#CELL
  mstr_discrete capp *
  page209_i35
#ISCELL
  mstr_symbols gnd *
  page209_i36
#CELL
  mstr_discrete capp *
  page209_i37
#CELL
  mstr_discrete capp *
  page209_i38
#CELL
  mstr_discrete res *
  page209_i39
#ISCELL
  mstr_symbols gnd *
  page209_i4
#CELL
  mstr_discrete inductor *
  page209_i40
#ISCELL
  mstr_symbols gnd *
  page209_i41
#CELL
  dev_discrete cap_a *
  page209_i42
#ISCELL
  mstr_symbols pvccin_cpu1 *
  page209_i43
#ISCELL
  mstr_standard offpage *
  page209_i44
#ISCELL
  mstr_symbols vcc_core *
  page209_i45
#ISCELL
  mstr_standard offpage *
  page209_i49
#CELL
  mstr_discrete cap *
  page209_i5
#CELL
  mstr_analog adm4073 *
  page209_i52
#ISCELL
  mstr_symbols p12v_stby *
  page209_i53
#ISCELL
  mstr_symbols p5v_stby *
  page209_i54
#CELL
  dev_discrete cap_a *
  page209_i55
#CELL
  mstr_discrete ir354xx *
  page209_i56
#ISCELL
  mstr_standard offpage *
  page209_i57
#ISCELL
  mstr_standard offpage *
  page209_i58
#CELL
  mstr_discrete res *
  page209_i59
#ISCELL
  mstr_symbols gnd *
  page209_i60
#CELL
  dev_discrete cap_a *
  page209_i62
#ISCELL
  mstr_symbols gnd *
  page209_i63
#CELL
  w_hdl sc2k2p50v3kx-gp *
  page209_i64
#ISCELL
  mstr_symbols gnd *
  page209_i65
#CELL
  w_hdl 3d01r5f-gp *
  page209_i66
#CELL
  mstr_discrete cap *
  page209_i67
#ISCELL
  mstr_symbols gnd *
  page209_i68
#CELL
  mstr_discrete res *
  page209_i69
#CELL
  mstr_discrete cap *
  page209_i7
#CELL
  mstr_discrete cap *
  page209_i8
#CELL
  mstr_discrete res *
  page209_i9
#ISCELL
  mstr_misc dns *
  *
#ISCELL
  mstr_symbols design_note *
  *
#ISCELL
  mstr_symbols intel_corp_bpage *
  *
#ISCELL
  mstr_standard offpage *
  page210_i1
#CELL
  mstr_discrete inductor *
  page210_i10
#CELL
  mstr_discrete capp *
  page210_i12
#ISCELL
  mstr_symbols gnd *
  page210_i13
#CELL
  mstr_discrete capp *
  page210_i14
#ISCELL
  mstr_symbols gnd *
  page210_i15
#ISCELL
  mstr_standard offpage *
  page210_i17
#ISCELL
  mstr_standard offpage *
  page210_i18
#ISCELL
  mstr_standard offpage *
  page210_i2
#CELL
  mstr_discrete res *
  page210_i20
#ISCELL
  mstr_symbols vcc_core *
  page210_i21
#CELL
  mstr_discrete cap *
  page210_i22
#CELL
  dev_discrete cap_a *
  page210_i23
#CELL
  mstr_discrete cap *
  page210_i24
#CELL
  mstr_discrete cap *
  page210_i26
#CELL
  dev_discrete cap_a *
  page210_i27
#CELL
  mstr_discrete cap *
  page210_i28
#CELL
  mstr_discrete res *
  page210_i29
#ISCELL
  mstr_symbols gnd *
  page210_i30
#CELL
  mstr_discrete res *
  page210_i31
#CELL
  mstr_discrete res *
  page210_i32
#CELL
  mstr_discrete res *
  page210_i33
#CELL
  mstr_discrete res *
  page210_i34
#CELL
  mstr_discrete cap *
  page210_i35
#CELL
  mstr_discrete cap *
  page210_i36
#CELL
  mstr_discrete cap *
  page210_i38
#ISCELL
  mstr_symbols gnd *
  page210_i39
#ISCELL
  mstr_standard offpage *
  page210_i40
#ISCELL
  mstr_standard offpage *
  page210_i41
#ISCELL
  mstr_symbols p5v_stby *
  page210_i42
#CELL
  dev_discrete cap_a *
  page210_i44
#CELL
  mstr_discrete res *
  page210_i45
#ISCELL
  mstr_symbols pvsa_cpu1 *
  page210_i46
#ISCELL
  mstr_symbols pvsa_cpu1 *
  page210_i47
#ISCELL
  mstr_standard offpage *
  page210_i50
#CELL
  mstr_discrete ir354xx *
  page210_i51
#CELL
  mstr_discrete res *
  page210_i52
#ISCELL
  mstr_symbols gnd *
  page210_i53
#ISCELL
  mstr_symbols gnd *
  page210_i54
#CELL
  dev_discrete cap_a *
  page210_i55
#CELL
  w_hdl sc2k2p50v3kx-gp *
  page210_i57
#ISCELL
  mstr_symbols gnd *
  page210_i58
#CELL
  w_hdl 3d01r5f-gp *
  page210_i59
#ISCELL
  mstr_standard offpage *
  page210_i6
#CELL
  mstr_discrete cap *
  page210_i60
#ISCELL
  mstr_symbols gnd *
  page210_i61
#CELL
  mstr_discrete res *
  page210_i62
#ISCELL
  mstr_symbols pvsa_cpu1 *
  page210_i7
#CELL
  dev_discrete cap_a *
  page210_i8
#ISCELL
  mstr_symbols gnd *
  page210_i9
#ISCELL
  mstr_misc dns *
  *
#ISCELL
  mstr_symbols design_note *
  *
#ISCELL
  mstr_symbols intel_corp_bpage *
  *
#CELL
  dev_discrete cap_a *
  page211_i11
#ISCELL
  mstr_symbols gnd *
  page211_i12
#CELL
  dev_discrete cap_a *
  page211_i13
#ISCELL
  mstr_symbols gnd *
  page211_i14
#ISCELL
  mstr_standard offpage *
  page211_i15
#CELL
  mstr_discrete res *
  page211_i16
#CELL
  mstr_discrete res *
  page211_i17
#ISCELL
  mstr_symbols pvccio_cpu0 *
  page211_i18
#ISCELL
  mstr_standard offpage *
  page211_i19
#ISCELL
  mstr_symbols gnd *
  page211_i2
#CELL
  dev_discrete cap_a *
  page211_i20
#ISCELL
  mstr_symbols gnd *
  page211_i21
#CELL
  dev_discrete cap_a *
  page211_i22
#ISCELL
  mstr_symbols gnd *
  page211_i23
#CELL
  mstr_discrete res *
  page211_i24
#ISCELL
  mstr_symbols p3v3_stby *
  page211_i25
#ISCELL
  mstr_standard offpage *
  page211_i26
#ISCELL
  mstr_symbols pvccio_cpu0 *
  page211_i27
#CELL
  mstr_discrete res *
  page211_i28
#CELL
  mstr_discrete res *
  page211_i29
#ISCELL
  mstr_standard offpage *
  page211_i3
#ISCELL
  mstr_symbols vcc_core *
  page211_i30
#CELL
  mstr_discrete res *
  page211_i31
#CELL
  mstr_discrete res *
  page211_i32
#CELL
  mstr_discrete cap *
  page211_i33
#ISCELL
  mstr_symbols gnd *
  page211_i34
#ISCELL
  mstr_symbols gnd *
  page211_i35
#ISCELL
  mstr_standard offpage *
  page211_i36
#ISCELL
  mstr_standard offpage *
  page211_i37
#ISCELL
  mstr_standard offpage *
  page211_i39
#ISCELL
  mstr_standard offpage *
  page211_i40
#ISCELL
  mstr_standard offpage *
  page211_i42
#ISCELL
  mstr_standard offpage *
  page211_i43
#CELL
  mstr_discrete res *
  page211_i46
#CELL
  mstr_discrete res *
  page211_i47
#ISCELL
  mstr_standard offpage *
  page211_i48
#ISCELL
  mstr_standard offpage *
  page211_i49
#ISCELL
  mstr_symbols gnd *
  page211_i51
#CELL
  mstr_discrete res *
  page211_i52
#ISCELL
  mstr_symbols gnd *
  page211_i54
#CELL
  mstr_discrete res *
  page211_i56
#ISCELL
  mstr_standard offpage *
  page211_i57
#CELL
  mstr_discrete res *
  page211_i58
#ISCELL
  mstr_symbols p3v3_stby *
  page211_i59
#ISCELL
  mstr_standard offpage *
  page211_i6
#CELL
  mstr_discrete res *
  page211_i60
#CELL
  mstr_discrete res *
  page211_i61
#ISCELL
  mstr_standard offpage *
  page211_i62
#CELL
  mstr_discrete res *
  page211_i64
#CELL
  mstr_discrete res *
  page211_i65
#CELL
  mstr_discrete cap *
  page211_i71
#ISCELL
  mstr_symbols gnd *
  page211_i72
#CELL
  mstr_discrete res *
  page211_i81
#ISCELL
  mstr_standard offpage *
  page211_i82
#CELL
  mstr_discrete cap *
  page211_i83
#ISCELL
  mstr_standard offpage *
  page211_i84
#CELL
  mstr_discrete res *
  page211_i87
#CELL
  mstr_discrete res *
  page211_i88
#CELL
  mstr_discrete res *
  page211_i91
#ISCELL
  mstr_standard offpage *
  page211_i92
#CELL
  mstr_controller pxe1110b *
  page211_i93
#ISCELL
  mstr_misc dns *
  *
#ISCELL
  mstr_symbols design_note *
  *
#ISCELL
  mstr_symbols intel_corp_bpage *
  *
#CELL
  mstr_discrete ir354xx *
  page212_i101
#ISCELL
  mstr_symbols gnd *
  page212_i102
#CELL
  mstr_discrete res *
  page212_i103
#CELL
  mstr_misc shunt *
  page212_i104
#CELL
  mstr_misc shunt *
  page212_i105
#CELL
  dev_discrete cap_a *
  page212_i106
#ISCELL
  mstr_symbols gnd *
  page212_i107
#CELL
  mstr_discrete cap *
  page212_i109
#ISCELL
  mstr_symbols gnd *
  page212_i110
#CELL
  w_hdl sc2k2p50v3kx-gp *
  page212_i111
#CELL
  w_hdl 3d01r5f-gp *
  page212_i112
#ISCELL
  mstr_symbols gnd *
  page212_i113
#CELL
  mstr_discrete res *
  page212_i114
#ISCELL
  mstr_symbols gnd *
  page212_i13
#CELL
  mstr_discrete capp *
  page212_i16
#CELL
  mstr_discrete capp *
  page212_i17
#CELL
  mstr_discrete capp *
  page212_i18
#ISCELL
  mstr_standard offpage *
  page212_i19
#ISCELL
  mstr_standard offpage *
  page212_i20
#ISCELL
  mstr_standard offpage *
  page212_i21
#ISCELL
  mstr_symbols pvccio_cpu0 *
  page212_i22
#CELL
  dev_discrete cap_a *
  page212_i23
#ISCELL
  mstr_symbols gnd *
  page212_i24
#CELL
  mstr_discrete inductor *
  page212_i25
#ISCELL
  mstr_symbols gnd *
  page212_i29
#CELL
  mstr_discrete res *
  page212_i32
#CELL
  mstr_discrete cap *
  page212_i33
#CELL
  dev_discrete cap_a *
  page212_i34
#CELL
  mstr_discrete cap *
  page212_i36
#CELL
  mstr_discrete cap *
  page212_i37
#CELL
  dev_discrete cap_a *
  page212_i38
#CELL
  mstr_discrete cap *
  page212_i39
#CELL
  mstr_discrete cap *
  page212_i40
#CELL
  mstr_discrete cap *
  page212_i41
#CELL
  mstr_discrete cap *
  page212_i43
#ISCELL
  mstr_symbols gnd *
  page212_i44
#ISCELL
  mstr_standard offpage *
  page212_i45
#CELL
  mstr_discrete cap *
  page212_i51
#ISCELL
  mstr_symbols gnd *
  page212_i52
#CELL
  mstr_discrete cap *
  page212_i54
#ISCELL
  mstr_symbols gnd *
  page212_i55
#CELL
  mstr_discrete inductor *
  page212_i56
#ISCELL
  mstr_symbols p12v_stby *
  page212_i57
#ISCELL
  mstr_symbols p5v_stby *
  page212_i58
#ISCELL
  mstr_standard offpage *
  page212_i59
#CELL
  dev_discrete cap_a *
  page212_i60
#ISCELL
  mstr_standard offpage *
  page212_i61
#CELL
  mstr_discrete res *
  page212_i68
#ISCELL
  mstr_symbols gnd *
  page212_i69
#ISCELL
  mstr_standard offpage *
  page212_i70
#CELL
  mstr_discrete res *
  page212_i74
#ISCELL
  mstr_symbols pvccio_cpu0 *
  page212_i75
#ISCELL
  mstr_standard offpage *
  page212_i76
#CELL
  dev_discrete cap_a *
  page212_i77
#CELL
  mstr_discrete res *
  page212_i78
#ISCELL
  mstr_symbols vcc_core *
  page212_i79
#ISCELL
  mstr_symbols vcc_core *
  page212_i80
#ISCELL
  mstr_symbols pvccio_cpu0 *
  page212_i82
#ISCELL
  mstr_misc dns *
  *
#ISCELL
  mstr_symbols design_note *
  *
#ISCELL
  mstr_symbols intel_corp_bpage *
  *
#ISCELL
  mstr_symbols p3v3_stby *
  page213_i1
#ISCELL
  mstr_symbols gnd *
  page213_i10
#CELL
  dev_discrete cap_a *
  page213_i11
#ISCELL
  mstr_symbols gnd *
  page213_i12
#CELL
  mstr_discrete res *
  page213_i13
#CELL
  mstr_discrete res *
  page213_i14
#CELL
  mstr_discrete res *
  page213_i15
#CELL
  mstr_discrete res *
  page213_i16
#CELL
  dev_discrete cap_a *
  page213_i17
#ISCELL
  mstr_symbols gnd *
  page213_i18
#ISCELL
  mstr_standard offpage *
  page213_i2
#ISCELL
  mstr_symbols gnd *
  page213_i21
#ISCELL
  mstr_symbols p3v3_stby *
  page213_i24
#CELL
  mstr_discrete res *
  page213_i25
#ISCELL
  mstr_symbols pvccio_cpu1 *
  page213_i26
#CELL
  mstr_discrete res *
  page213_i27
#ISCELL
  mstr_symbols pvccio_cpu1 *
  page213_i28
#ISCELL
  mstr_standard offpage *
  page213_i3
#CELL
  mstr_discrete res *
  page213_i30
#CELL
  mstr_discrete res *
  page213_i31
#CELL
  mstr_discrete res *
  page213_i32
#CELL
  mstr_discrete cap *
  page213_i33
#ISCELL
  mstr_standard offpage *
  page213_i34
#CELL
  dev_discrete cap_a *
  page213_i35
#ISCELL
  mstr_symbols gnd *
  page213_i36
#CELL
  mstr_discrete res *
  page213_i37
#CELL
  mstr_discrete res *
  page213_i38
#CELL
  mstr_discrete res *
  page213_i39
#CELL
  mstr_discrete res *
  page213_i42
#ISCELL
  mstr_symbols gnd *
  page213_i44
#ISCELL
  mstr_symbols gnd *
  page213_i45
#CELL
  mstr_discrete res *
  page213_i46
#ISCELL
  mstr_symbols gnd *
  page213_i47
#ISCELL
  mstr_symbols gnd *
  page213_i49
#ISCELL
  mstr_standard offpage *
  page213_i5
#ISCELL
  mstr_standard offpage *
  page213_i50
#ISCELL
  mstr_standard offpage *
  page213_i51
#ISCELL
  mstr_standard offpage *
  page213_i52
#ISCELL
  mstr_standard offpage *
  page213_i53
#ISCELL
  mstr_standard offpage *
  page213_i54
#ISCELL
  mstr_standard offpage *
  page213_i55
#ISCELL
  mstr_standard offpage *
  page213_i57
#ISCELL
  mstr_standard offpage *
  page213_i58
#ISCELL
  mstr_standard offpage *
  page213_i61
#ISCELL
  mstr_standard offpage *
  page213_i62
#CELL
  mstr_discrete res *
  page213_i63
#CELL
  mstr_discrete res *
  page213_i65
#CELL
  mstr_discrete cap *
  page213_i73
#ISCELL
  mstr_symbols gnd *
  page213_i74
#ISCELL
  mstr_standard offpage *
  page213_i8
#CELL
  mstr_discrete cap *
  page213_i83
#CELL
  mstr_discrete res *
  page213_i84
#ISCELL
  mstr_standard offpage *
  page213_i86
#ISCELL
  mstr_standard offpage *
  page213_i87
#CELL
  dev_discrete cap_a *
  page213_i9
#CELL
  mstr_discrete res *
  page213_i90
#CELL
  mstr_discrete res *
  page213_i91
#ISCELL
  mstr_symbols universal_power *
  page213_i92
#CELL
  mstr_discrete res *
  page213_i94
#ISCELL
  mstr_standard offpage *
  page213_i95
#CELL
  mstr_controller pxe1110b *
  page213_i96
#ISCELL
  mstr_misc dns *
  *
#ISCELL
  mstr_symbols design_note *
  *
#ISCELL
  mstr_symbols intel_corp_bpage *
  *
#CELL
  mstr_discrete res *
  page214_i101
#ISCELL
  mstr_symbols gnd *
  page214_i102
#ISCELL
  mstr_standard offpage *
  page214_i103
#CELL
  mstr_discrete res *
  page214_i105
#ISCELL
  mstr_standard offpage *
  page214_i106
#ISCELL
  mstr_symbols pvccio_cpu1 *
  page214_i107
#CELL
  dev_discrete cap_a *
  page214_i108
#CELL
  mstr_discrete res *
  page214_i109
#CELL
  mstr_discrete ir354xx *
  page214_i126
#CELL
  mstr_discrete res *
  page214_i127
#ISCELL
  mstr_symbols gnd *
  page214_i128
#CELL
  mstr_misc shunt *
  page214_i129
#CELL
  mstr_misc shunt *
  page214_i130
#CELL
  w_hdl sc2k2p50v3kx-gp *
  page214_i131
#CELL
  w_hdl 3d01r5f-gp *
  page214_i132
#ISCELL
  mstr_symbols gnd *
  page214_i133
#CELL
  mstr_discrete cap *
  page214_i134
#ISCELL
  mstr_symbols gnd *
  page214_i135
#ISCELL
  mstr_symbols gnd *
  page214_i136
#CELL
  dev_discrete cap_a *
  page214_i137
#CELL
  mstr_discrete res *
  page214_i139
#CELL
  mstr_discrete capp *
  page214_i20
#CELL
  mstr_discrete capp *
  page214_i21
#CELL
  mstr_discrete capp *
  page214_i24
#ISCELL
  mstr_symbols gnd *
  page214_i28
#CELL
  mstr_discrete cap *
  page214_i29
#ISCELL
  mstr_symbols pvccio_cpu1 *
  page214_i3
#ISCELL
  mstr_symbols universal_power *
  page214_i30
#CELL
  mstr_discrete cap *
  page214_i31
#ISCELL
  mstr_symbols gnd *
  page214_i32
#ISCELL
  mstr_standard offpage *
  page214_i58
#ISCELL
  mstr_standard offpage *
  page214_i59
#ISCELL
  mstr_symbols gnd *
  page214_i6
#ISCELL
  mstr_standard offpage *
  page214_i60
#ISCELL
  mstr_symbols pvccio_cpu1 *
  page214_i64
#CELL
  dev_discrete cap_a *
  page214_i65
#ISCELL
  mstr_symbols gnd *
  page214_i66
#CELL
  mstr_discrete inductor *
  page214_i67
#ISCELL
  mstr_symbols gnd *
  page214_i68
#CELL
  mstr_discrete res *
  page214_i71
#CELL
  mstr_discrete cap *
  page214_i73
#CELL
  dev_discrete cap_a *
  page214_i74
#CELL
  mstr_discrete cap *
  page214_i76
#CELL
  dev_discrete cap_a *
  page214_i77
#CELL
  mstr_discrete cap *
  page214_i78
#CELL
  mstr_discrete cap *
  page214_i79
#CELL
  mstr_discrete cap *
  page214_i8
#CELL
  mstr_discrete cap *
  page214_i80
#CELL
  mstr_discrete cap *
  page214_i81
#ISCELL
  mstr_standard offpage *
  page214_i82
#CELL
  mstr_discrete cap *
  page214_i83
#ISCELL
  mstr_symbols gnd *
  page214_i84
#ISCELL
  mstr_symbols p5v_stby *
  page214_i88
#ISCELL
  mstr_symbols universal_power *
  page214_i89
#ISCELL
  mstr_symbols gnd *
  page214_i9
#ISCELL
  mstr_standard offpage *
  page214_i95
#CELL
  dev_discrete cap_a *
  page214_i96
#ISCELL
  mstr_standard offpage *
  page214_i97
#ISCELL
  mstr_misc dns *
  *
#ISCELL
  mstr_symbols design_note *
  *
#ISCELL
  mstr_symbols intel_corp_bpage *
  *
#ISCELL
  mstr_standard offpage *
  page215_i284
#ISCELL
  mstr_standard offpage *
  page215_i285
#ISCELL
  mstr_standard offpage *
  page215_i286
#ISCELL
  mstr_standard offpage *
  page215_i287
#ISCELL
  mstr_standard offpage *
  page215_i288
#ISCELL
  mstr_standard offpage *
  page215_i289
#ISCELL
  mstr_standard offpage *
  page215_i290
#ISCELL
  mstr_standard offpage *
  page215_i291
#ISCELL
  mstr_standard offpage *
  page215_i292
#ISCELL
  mstr_standard offpage *
  page215_i293
#ISCELL
  mstr_symbols pvccio_cpu0 *
  page215_i294
#CELL
  mstr_discrete res *
  page215_i295
#CELL
  mstr_discrete res *
  page215_i296
#CELL
  mstr_discrete res *
  page215_i297
#CELL
  mstr_discrete res *
  page215_i298
#ISCELL
  mstr_symbols p3v3_stby *
  page215_i299
#CELL
  mstr_discrete res *
  page215_i300
#CELL
  mstr_discrete res *
  page215_i301
#CELL
  mstr_discrete res *
  page215_i302
#CELL
  mstr_discrete res *
  page215_i303
#CELL
  mstr_discrete res *
  page215_i304
#CELL
  mstr_discrete cap *
  page215_i305
#ISCELL
  mstr_symbols gnd *
  page215_i306
#CELL
  mstr_discrete res *
  page215_i307
#ISCELL
  mstr_symbols gnd *
  page215_i308
#CELL
  dev_discrete cap_a *
  page215_i309
#ISCELL
  mstr_symbols gnd *
  page215_i310
#CELL
  dev_discrete cap_a *
  page215_i311
#ISCELL
  mstr_symbols gnd *
  page215_i312
#CELL
  mstr_discrete res *
  page215_i313
#ISCELL
  mstr_symbols p3v3_stby *
  page215_i314
#CELL
  mstr_discrete res *
  page215_i315
#CELL
  mstr_discrete res *
  page215_i317
#ISCELL
  mstr_symbols gnd *
  page215_i318
#ISCELL
  mstr_symbols gnd *
  page215_i319
#CELL
  mstr_discrete cap *
  page215_i320
#CELL
  mstr_discrete res *
  page215_i321
#ISCELL
  mstr_symbols gnd *
  page215_i322
#ISCELL
  mstr_symbols gnd *
  page215_i323
#CELL
  dev_discrete cap_a *
  page215_i325
#ISCELL
  mstr_symbols gnd *
  page215_i326
#CELL
  dev_discrete cap_a *
  page215_i327
#ISCELL
  mstr_symbols gnd *
  page215_i328
#ISCELL
  mstr_symbols pvccio_cpu0 *
  page215_i329
#CELL
  mstr_discrete res *
  page215_i330
#CELL
  mstr_discrete res *
  page215_i331
#CELL
  mstr_discrete res *
  page215_i332
#ISCELL
  mstr_symbols vcc_core *
  page215_i335
#CELL
  mstr_discrete res *
  page215_i336
#CELL
  mstr_discrete res *
  page215_i337
#ISCELL
  mstr_symbols gnd *
  page215_i338
#CELL
  mstr_discrete cap *
  page215_i339
#ISCELL
  mstr_symbols gnd *
  page215_i340
#CELL
  mstr_discrete res *
  page215_i341
#CELL
  mstr_discrete cap *
  page215_i342
#CELL
  mstr_discrete res *
  page215_i343
#CELL
  mstr_discrete res *
  page215_i344
#ISCELL
  mstr_standard offpage *
  page215_i345
#ISCELL
  mstr_standard offpage *
  page215_i346
#ISCELL
  mstr_standard offpage *
  page215_i347
#ISCELL
  mstr_standard offpage *
  page215_i348
#ISCELL
  mstr_standard offpage *
  page215_i349
#ISCELL
  mstr_standard offpage *
  page215_i350
#ISCELL
  mstr_standard offpage *
  page215_i351
#ISCELL
  mstr_standard offpage *
  page215_i352
#ISCELL
  mstr_standard offpage *
  page215_i353
#ISCELL
  mstr_standard offpage *
  page215_i354
#ISCELL
  mstr_standard offpage *
  page215_i355
#ISCELL
  mstr_standard offpage *
  page215_i356
#ISCELL
  mstr_standard offpage *
  page215_i357
#CELL
  mstr_controller pxm1310b *
  page215_i358
#ISCELL
  mstr_symbols gnd *
  page215_i359
#CELL
  dev_discrete cap_a *
  page215_i360
#ISCELL
  mstr_misc dns *
  *
#ISCELL
  mstr_symbols intel_corp_bpage *
  *
#ISCELL
  mstr_symbols pvddq_abc *
  page216_i1
#CELL
  mstr_discrete ir354xx *
  page216_i102
#CELL
  mstr_discrete ir354xx *
  page216_i103
#CELL
  mstr_discrete res *
  page216_i104
#ISCELL
  mstr_symbols gnd *
  page216_i105
#CELL
  mstr_discrete res *
  page216_i106
#ISCELL
  mstr_symbols gnd *
  page216_i107
#CELL
  dev_discrete cap_a *
  page216_i108
#ISCELL
  mstr_symbols gnd *
  page216_i109
#CELL
  dev_discrete cap_a *
  page216_i111
#ISCELL
  mstr_symbols gnd *
  page216_i112
#CELL
  w_hdl 3d01r5f-gp *
  page216_i114
#ISCELL
  mstr_symbols gnd *
  page216_i115
#ISCELL
  mstr_symbols gnd *
  page216_i117
#CELL
  mstr_discrete cap *
  page216_i118
#CELL
  w_hdl sc2k2p50v3kx-gp *
  page216_i119
#ISCELL
  mstr_symbols gnd *
  page216_i120
#CELL
  mstr_discrete cap *
  page216_i121
#ISCELL
  mstr_symbols gnd *
  page216_i122
#CELL
  w_hdl 3d01r5f-gp *
  page216_i123
#CELL
  w_hdl sc2k2p50v3kx-gp *
  page216_i124
#CELL
  mstr_discrete inductor *
  page216_i125
#CELL
  mstr_discrete res *
  page216_i126
#CELL
  mstr_discrete res *
  page216_i127
#CELL
  mstr_discrete cap *
  page216_i128
#ISCELL
  mstr_symbols gnd *
  page216_i19
#ISCELL
  mstr_standard offpage *
  page216_i3
#ISCELL
  mstr_standard offpage *
  page216_i33
#ISCELL
  mstr_symbols gnd *
  page216_i35
#ISCELL
  mstr_standard offpage *
  page216_i4
#CELL
  mstr_discrete cap *
  page216_i44
#CELL
  mstr_discrete cap *
  page216_i45
#CELL
  mstr_discrete cap *
  page216_i46
#CELL
  mstr_discrete cap *
  page216_i47
#CELL
  mstr_discrete cap *
  page216_i48
#CELL
  mstr_discrete cap *
  page216_i50
#CELL
  dev_discrete cap_a *
  page216_i51
#CELL
  mstr_discrete res *
  page216_i52
#CELL
  dev_discrete cap_a *
  page216_i53
#CELL
  mstr_discrete cap *
  page216_i54
#ISCELL
  mstr_standard offpage *
  page216_i58
#CELL
  mstr_discrete cap *
  page216_i6
#ISCELL
  mstr_standard offpage *
  page216_i61
#ISCELL
  mstr_standard offpage *
  page216_i62
#ISCELL
  mstr_standard offpage *
  page216_i63
#ISCELL
  mstr_symbols pvddq_abc *
  page216_i64
#CELL
  mstr_discrete inductor *
  page216_i65
#CELL
  mstr_discrete cap *
  page216_i68
#ISCELL
  mstr_symbols gnd *
  page216_i69
#ISCELL
  mstr_symbols gnd *
  page216_i7
#ISCELL
  mstr_symbols gnd *
  page216_i70
#CELL
  mstr_discrete cap *
  page216_i72
#CELL
  dev_discrete cap_a *
  page216_i73
#CELL
  mstr_discrete res *
  page216_i76
#CELL
  mstr_discrete cap *
  page216_i77
#CELL
  dev_discrete cap_a *
  page216_i78
#CELL
  mstr_discrete cap *
  page216_i79
#CELL
  mstr_discrete cap *
  page216_i80
#CELL
  mstr_discrete cap *
  page216_i81
#ISCELL
  mstr_standard offpage *
  page216_i82
#ISCELL
  mstr_symbols vcc_core *
  page216_i83
#CELL
  mstr_discrete cap *
  page216_i84
#ISCELL
  mstr_symbols gnd *
  page216_i85
#ISCELL
  mstr_symbols vcc_core *
  page216_i86
#ISCELL
  mstr_symbols p5v_stby *
  page216_i87
#ISCELL
  mstr_symbols p5v_stby *
  page216_i88
#ISCELL
  mstr_misc dns *
  *
#ISCELL
  mstr_symbols intel_corp_bpage *
  *
#ISCELL
  mstr_symbols pvddq_abc *
  page217_i109
#CELL
  mstr_discrete cap *
  page217_i110
#ISCELL
  mstr_symbols gnd *
  page217_i114
#ISCELL
  mstr_symbols vcc_core *
  page217_i120
#ISCELL
  mstr_symbols gnd *
  page217_i123
#CELL
  mstr_discrete inductor *
  page217_i124
#CELL
  mstr_discrete capp *
  page217_i175
#ISCELL
  mstr_symbols p12v_stby *
  page217_i183
#CELL
  mstr_discrete cap *
  page217_i184
#CELL
  mstr_discrete cap *
  page217_i186
#ISCELL
  mstr_symbols gnd *
  page217_i187
#CELL
  mstr_discrete cap *
  page217_i188
#CELL
  mstr_discrete cap *
  page217_i189
#CELL
  mstr_discrete cap *
  page217_i190
#ISCELL
  mstr_symbols pvddq_abc *
  page217_i192
#CELL
  mstr_discrete cap *
  page217_i193
#ISCELL
  mstr_symbols pvddq_abc *
  page217_i201
#ISCELL
  mstr_symbols gnd *
  page217_i203
#CELL
  dev_discrete cap_a *
  page217_i205
#CELL
  dev_discrete cap_a *
  page217_i206
#CELL
  dev_discrete cap_a *
  page217_i207
#CELL
  dev_discrete cap_a *
  page217_i208
#CELL
  dev_discrete cap_a *
  page217_i209
#CELL
  dev_discrete cap_a *
  page217_i210
#CELL
  dev_discrete cap_a *
  page217_i211
#CELL
  dev_discrete cap_a *
  page217_i212
#CELL
  dev_discrete cap_a *
  page217_i213
#ISCELL
  mstr_symbols pvddq_abc *
  page217_i214
#ISCELL
  mstr_symbols gnd *
  page217_i215
#CELL
  dev_discrete cap_a *
  page217_i216
#CELL
  dev_discrete cap_a *
  page217_i217
#CELL
  dev_discrete cap_a *
  page217_i218
#CELL
  dev_discrete cap_a *
  page217_i219
#CELL
  dev_discrete cap_a *
  page217_i220
#CELL
  dev_discrete cap_a *
  page217_i221
#CELL
  dev_discrete cap_a *
  page217_i222
#CELL
  dev_discrete cap_a *
  page217_i223
#CELL
  dev_discrete cap_a *
  page217_i224
#CELL
  dev_discrete cap_a *
  page217_i225
#CELL
  dev_discrete cap_a *
  page217_i226
#CELL
  dev_discrete cap_a *
  page217_i227
#CELL
  dev_discrete cap_a *
  page217_i228
#CELL
  dev_discrete cap_a *
  page217_i229
#CELL
  dev_discrete cap_a *
  page217_i230
#CELL
  dev_discrete cap_a *
  page217_i231
#CELL
  dev_discrete cap_a *
  page217_i232
#CELL
  dev_discrete cap_a *
  page217_i233
#CELL
  dev_discrete cap_a *
  page217_i234
#CELL
  dev_discrete cap_a *
  page217_i235
#CELL
  dev_discrete cap_a *
  page217_i236
#CELL
  dev_discrete cap_a *
  page217_i237
#CELL
  dev_discrete cap_a *
  page217_i238
#CELL
  dev_discrete cap_a *
  page217_i239
#CELL
  dev_discrete cap_a *
  page217_i240
#CELL
  dev_discrete cap_a *
  page217_i241
#ISCELL
  mstr_symbols pvddq_abc *
  page217_i242
#CELL
  dev_discrete cap_a *
  page217_i243
#CELL
  dev_discrete cap_a *
  page217_i244
#CELL
  dev_discrete cap_a *
  page217_i245
#CELL
  dev_discrete cap_a *
  page217_i246
#CELL
  dev_discrete cap_a *
  page217_i247
#ISCELL
  mstr_symbols gnd *
  page217_i248
#ISCELL
  mstr_symbols pvddq_abc *
  page217_i249
#CELL
  dev_discrete cap_a *
  page217_i250
#ISCELL
  mstr_symbols gnd *
  page217_i251
#CELL
  mstr_misc shunt *
  page217_i259
#CELL
  mstr_misc shunt *
  page217_i260
#CELL
  mstr_discrete res *
  page217_i58
#ISCELL
  mstr_symbols gnd *
  page217_i65
#ISCELL
  mstr_standard offpage *
  page217_i70
#ISCELL
  mstr_standard offpage *
  page217_i72
#ISCELL
  mstr_symbols pvddq_abc *
  page217_i73
#CELL
  mstr_discrete res *
  page217_i74
#CELL
  mstr_discrete capp *
  page217_i75
#CELL
  mstr_discrete capp *
  page217_i76
#CELL
  mstr_discrete capp *
  page217_i77
#CELL
  mstr_discrete capp *
  page217_i78
#ISCELL
  mstr_symbols pvddq_abc *
  page217_i80
#ISCELL
  mstr_symbols gnd *
  page217_i81
#CELL
  mstr_discrete cap *
  page217_i82
#CELL
  mstr_discrete cap *
  page217_i83
#CELL
  mstr_discrete cap *
  page217_i88
#CELL
  mstr_discrete cap *
  page217_i89
#CELL
  mstr_discrete cap *
  page217_i90
#CELL
  mstr_discrete cap *
  page217_i91
#CELL
  mstr_discrete cap *
  page217_i92
#ISCELL
  mstr_symbols pvddq_abc *
  page217_i93
#ISCELL
  mstr_symbols gnd *
  page217_i94
#ISCELL
  mstr_misc dns *
  *
#ISCELL
  mstr_symbols design_note *
  *
#ISCELL
  mstr_symbols intel_corp_bpage *
  *
#ISCELL
  mstr_standard offpage *
  page218_i1
#ISCELL
  mstr_standard offpage *
  page218_i10
#CELL
  mstr_discrete res *
  page218_i11
#CELL
  mstr_discrete res *
  page218_i12
#ISCELL
  mstr_symbols p3v3_stby *
  page218_i13
#CELL
  mstr_discrete res *
  page218_i14
#CELL
  mstr_discrete res *
  page218_i15
#CELL
  mstr_discrete res *
  page218_i16
#CELL
  mstr_discrete res *
  page218_i17
#ISCELL
  mstr_standard offpage *
  page218_i18
#ISCELL
  mstr_standard offpage *
  page218_i19
#ISCELL
  mstr_standard offpage *
  page218_i2
#ISCELL
  mstr_standard offpage *
  page218_i20
#CELL
  mstr_discrete res *
  page218_i21
#CELL
  dev_discrete cap_a *
  page218_i22
#CELL
  dev_discrete cap_a *
  page218_i23
#CELL
  mstr_discrete res *
  page218_i24
#CELL
  mstr_discrete res *
  page218_i25
#CELL
  mstr_discrete cap *
  page218_i26
#ISCELL
  mstr_symbols gnd *
  page218_i27
#ISCELL
  mstr_symbols gnd *
  page218_i28
#CELL
  dev_discrete cap_a *
  page218_i29
#ISCELL
  mstr_standard offpage *
  page218_i3
#ISCELL
  mstr_symbols gnd *
  page218_i30
#CELL
  dev_discrete cap_a *
  page218_i31
#ISCELL
  mstr_symbols gnd *
  page218_i32
#ISCELL
  mstr_symbols p3v3_stby *
  page218_i33
#CELL
  mstr_discrete res *
  page218_i34
#CELL
  mstr_discrete res *
  page218_i35
#CELL
  mstr_discrete res *
  page218_i37
#ISCELL
  mstr_symbols gnd *
  page218_i38
#CELL
  mstr_discrete cap *
  page218_i39
#ISCELL
  mstr_standard offpage *
  page218_i4
#CELL
  mstr_discrete res *
  page218_i40
#ISCELL
  mstr_symbols gnd *
  page218_i41
#ISCELL
  mstr_symbols gnd *
  page218_i42
#ISCELL
  mstr_symbols gnd *
  page218_i43
#ISCELL
  mstr_symbols gnd *
  page218_i44
#ISCELL
  mstr_symbols gnd *
  page218_i45
#ISCELL
  mstr_symbols pvccio_cpu0 *
  page218_i46
#CELL
  mstr_discrete res *
  page218_i47
#CELL
  mstr_discrete res *
  page218_i48
#CELL
  mstr_discrete res *
  page218_i50
#ISCELL
  mstr_symbols vcc_core *
  page218_i52
#CELL
  mstr_discrete res *
  page218_i53
#CELL
  mstr_discrete res *
  page218_i54
#CELL
  mstr_discrete cap *
  page218_i55
#ISCELL
  mstr_symbols gnd *
  page218_i56
#CELL
  mstr_discrete res *
  page218_i57
#ISCELL
  mstr_symbols gnd *
  page218_i58
#CELL
  mstr_discrete res *
  page218_i59
#ISCELL
  mstr_symbols pvccio_cpu0 *
  page218_i6
#CELL
  mstr_discrete res *
  page218_i60
#CELL
  mstr_discrete cap *
  page218_i61
#ISCELL
  mstr_standard offpage *
  page218_i62
#ISCELL
  mstr_standard offpage *
  page218_i63
#ISCELL
  mstr_standard offpage *
  page218_i64
#ISCELL
  mstr_standard offpage *
  page218_i65
#ISCELL
  mstr_standard offpage *
  page218_i66
#ISCELL
  mstr_standard offpage *
  page218_i67
#ISCELL
  mstr_standard offpage *
  page218_i68
#ISCELL
  mstr_standard offpage *
  page218_i69
#CELL
  mstr_discrete res *
  page218_i7
#ISCELL
  mstr_standard offpage *
  page218_i70
#ISCELL
  mstr_standard offpage *
  page218_i71
#ISCELL
  mstr_standard offpage *
  page218_i72
#ISCELL
  mstr_standard offpage *
  page218_i73
#ISCELL
  mstr_standard offpage *
  page218_i74
#CELL
  mstr_controller pxm1310b *
  page218_i75
#ISCELL
  mstr_symbols gnd *
  page218_i76
#CELL
  dev_discrete cap_a *
  page218_i77
#ISCELL
  mstr_standard offpage *
  page218_i8
#ISCELL
  mstr_standard offpage *
  page218_i9
#ISCELL
  mstr_misc dns *
  *
#ISCELL
  mstr_symbols intel_corp_bpage *
  *
#ISCELL
  mstr_symbols pvddq_def *
  page219_i1
#CELL
  mstr_discrete ir354xx *
  page219_i106
#CELL
  mstr_discrete ir354xx *
  page219_i107
#CELL
  mstr_discrete res *
  page219_i108
#ISCELL
  mstr_symbols gnd *
  page219_i109
#CELL
  mstr_discrete res *
  page219_i110
#ISCELL
  mstr_symbols gnd *
  page219_i111
#ISCELL
  mstr_symbols p5v_stby *
  page219_i112
#CELL
  dev_discrete cap_a *
  page219_i113
#ISCELL
  mstr_symbols gnd *
  page219_i114
#CELL
  dev_discrete cap_a *
  page219_i116
#ISCELL
  mstr_symbols gnd *
  page219_i117
#CELL
  mstr_discrete cap *
  page219_i119
#ISCELL
  mstr_symbols gnd *
  page219_i120
#CELL
  w_hdl sc2k2p50v3kx-gp *
  page219_i121
#ISCELL
  mstr_symbols gnd *
  page219_i122
#CELL
  w_hdl 3d01r5f-gp *
  page219_i123
#CELL
  mstr_discrete cap *
  page219_i124
#ISCELL
  mstr_symbols gnd *
  page219_i125
#CELL
  w_hdl 3d01r5f-gp *
  page219_i126
#CELL
  w_hdl sc2k2p50v3kx-gp *
  page219_i127
#ISCELL
  mstr_symbols gnd *
  page219_i128
#CELL
  mstr_discrete res *
  page219_i129
#CELL
  mstr_discrete res *
  page219_i130
#ISCELL
  mstr_symbols gnd *
  page219_i19
#ISCELL
  mstr_standard offpage *
  page219_i3
#ISCELL
  mstr_standard offpage *
  page219_i33
#ISCELL
  mstr_symbols gnd *
  page219_i35
#ISCELL
  mstr_standard offpage *
  page219_i4
#CELL
  mstr_discrete cap *
  page219_i44
#CELL
  mstr_discrete cap *
  page219_i45
#CELL
  mstr_discrete cap *
  page219_i46
#CELL
  mstr_discrete cap *
  page219_i47
#CELL
  mstr_discrete cap *
  page219_i48
#CELL
  mstr_discrete cap *
  page219_i50
#CELL
  dev_discrete cap_a *
  page219_i51
#CELL
  mstr_discrete res *
  page219_i52
#CELL
  dev_discrete cap_a *
  page219_i53
#CELL
  mstr_discrete cap *
  page219_i54
#CELL
  mstr_discrete inductor *
  page219_i55
#ISCELL
  mstr_standard offpage *
  page219_i58
#ISCELL
  mstr_standard offpage *
  page219_i61
#ISCELL
  mstr_standard offpage *
  page219_i62
#ISCELL
  mstr_standard offpage *
  page219_i63
#ISCELL
  mstr_symbols pvddq_def *
  page219_i64
#CELL
  mstr_discrete inductor *
  page219_i65
#CELL
  mstr_discrete cap *
  page219_i68
#ISCELL
  mstr_symbols gnd *
  page219_i69
#ISCELL
  mstr_symbols gnd *
  page219_i7
#ISCELL
  mstr_symbols gnd *
  page219_i70
#CELL
  mstr_discrete cap *
  page219_i72
#CELL
  dev_discrete cap_a *
  page219_i73
#CELL
  mstr_discrete cap *
  page219_i75
#CELL
  mstr_discrete res *
  page219_i76
#CELL
  mstr_discrete cap *
  page219_i77
#CELL
  dev_discrete cap_a *
  page219_i78
#CELL
  mstr_discrete cap *
  page219_i79
#CELL
  mstr_discrete cap *
  page219_i80
#CELL
  mstr_discrete cap *
  page219_i81
#ISCELL
  mstr_standard offpage *
  page219_i82
#ISCELL
  mstr_symbols vcc_core *
  page219_i83
#CELL
  mstr_discrete cap *
  page219_i84
#ISCELL
  mstr_symbols gnd *
  page219_i85
#ISCELL
  mstr_symbols vcc_core *
  page219_i86
#CELL
  mstr_discrete cap *
  page219_i87
#ISCELL
  mstr_symbols p5v_stby *
  page219_i89
#ISCELL
  mstr_misc dns *
  *
#ISCELL
  mstr_symbols intel_corp_bpage *
  *
#ISCELL
  mstr_symbols pvddq_def *
  page220_i109
#CELL
  mstr_discrete cap *
  page220_i110
#ISCELL
  mstr_symbols gnd *
  page220_i114
#ISCELL
  mstr_symbols vcc_core *
  page220_i120
#ISCELL
  mstr_symbols gnd *
  page220_i123
#CELL
  mstr_discrete inductor *
  page220_i124
#CELL
  mstr_discrete capp *
  page220_i175
#ISCELL
  mstr_symbols p12v_stby *
  page220_i176
#CELL
  mstr_discrete cap *
  page220_i177
#CELL
  mstr_discrete cap *
  page220_i179
#CELL
  mstr_discrete cap *
  page220_i180
#ISCELL
  mstr_symbols gnd *
  page220_i181
#CELL
  mstr_discrete cap *
  page220_i182
#CELL
  mstr_discrete cap *
  page220_i183
#CELL
  mstr_discrete cap *
  page220_i184
#ISCELL
  mstr_symbols pvddq_def *
  page220_i185
#ISCELL
  mstr_symbols pvddq_def *
  page220_i189
#ISCELL
  mstr_symbols gnd *
  page220_i191
#CELL
  dev_discrete cap_a *
  page220_i192
#CELL
  dev_discrete cap_a *
  page220_i193
#CELL
  dev_discrete cap_a *
  page220_i194
#CELL
  dev_discrete cap_a *
  page220_i195
#CELL
  dev_discrete cap_a *
  page220_i196
#CELL
  dev_discrete cap_a *
  page220_i197
#CELL
  dev_discrete cap_a *
  page220_i198
#CELL
  dev_discrete cap_a *
  page220_i199
#CELL
  dev_discrete cap_a *
  page220_i200
#ISCELL
  mstr_symbols pvddq_def *
  page220_i201
#ISCELL
  mstr_symbols gnd *
  page220_i202
#CELL
  dev_discrete cap_a *
  page220_i203
#CELL
  dev_discrete cap_a *
  page220_i204
#CELL
  dev_discrete cap_a *
  page220_i205
#CELL
  dev_discrete cap_a *
  page220_i206
#CELL
  dev_discrete cap_a *
  page220_i207
#CELL
  dev_discrete cap_a *
  page220_i208
#CELL
  dev_discrete cap_a *
  page220_i209
#CELL
  dev_discrete cap_a *
  page220_i210
#CELL
  dev_discrete cap_a *
  page220_i211
#CELL
  dev_discrete cap_a *
  page220_i212
#CELL
  dev_discrete cap_a *
  page220_i213
#CELL
  dev_discrete cap_a *
  page220_i214
#CELL
  dev_discrete cap_a *
  page220_i215
#CELL
  dev_discrete cap_a *
  page220_i216
#CELL
  dev_discrete cap_a *
  page220_i217
#ISCELL
  mstr_symbols pvddq_def *
  page220_i218
#CELL
  dev_discrete cap_a *
  page220_i219
#ISCELL
  mstr_symbols gnd *
  page220_i220
#CELL
  dev_discrete cap_a *
  page220_i221
#CELL
  dev_discrete cap_a *
  page220_i222
#CELL
  dev_discrete cap_a *
  page220_i223
#CELL
  dev_discrete cap_a *
  page220_i224
#CELL
  dev_discrete cap_a *
  page220_i225
#CELL
  dev_discrete cap_a *
  page220_i226
#CELL
  dev_discrete cap_a *
  page220_i227
#CELL
  dev_discrete cap_a *
  page220_i228
#CELL
  dev_discrete cap_a *
  page220_i229
#CELL
  dev_discrete cap_a *
  page220_i230
#CELL
  dev_discrete cap_a *
  page220_i231
#CELL
  dev_discrete cap_a *
  page220_i232
#CELL
  dev_discrete cap_a *
  page220_i233
#CELL
  dev_discrete cap_a *
  page220_i234
#ISCELL
  mstr_symbols pvddq_def *
  page220_i235
#CELL
  dev_discrete cap_a *
  page220_i236
#CELL
  dev_discrete cap_a *
  page220_i237
#ISCELL
  mstr_symbols gnd *
  page220_i238
#CELL
  mstr_misc shunt *
  page220_i239
#CELL
  mstr_misc shunt *
  page220_i240
#CELL
  mstr_discrete res *
  page220_i58
#ISCELL
  mstr_symbols gnd *
  page220_i65
#ISCELL
  mstr_standard offpage *
  page220_i70
#ISCELL
  mstr_standard offpage *
  page220_i72
#ISCELL
  mstr_symbols pvddq_def *
  page220_i73
#CELL
  mstr_discrete res *
  page220_i74
#CELL
  mstr_discrete capp *
  page220_i75
#CELL
  mstr_discrete capp *
  page220_i76
#CELL
  mstr_discrete capp *
  page220_i77
#CELL
  mstr_discrete capp *
  page220_i78
#ISCELL
  mstr_symbols pvddq_def *
  page220_i80
#ISCELL
  mstr_symbols gnd *
  page220_i81
#CELL
  mstr_discrete cap *
  page220_i82
#CELL
  mstr_discrete cap *
  page220_i83
#CELL
  mstr_discrete cap *
  page220_i88
#CELL
  mstr_discrete cap *
  page220_i89
#CELL
  mstr_discrete cap *
  page220_i90
#CELL
  mstr_discrete cap *
  page220_i91
#CELL
  mstr_discrete cap *
  page220_i92
#ISCELL
  mstr_symbols pvddq_def *
  page220_i93
#ISCELL
  mstr_symbols gnd *
  page220_i94
#ISCELL
  mstr_misc dns *
  *
#ISCELL
  mstr_misc prelim *
  *
#ISCELL
  mstr_symbols cad_note *
  *
#ISCELL
  mstr_symbols intel_corp_bpage *
  *
#CELL
  mstr_vreg mic5166 *
  page221_i1
#ISCELL
  mstr_symbols pvtt_abc *
  page221_i11
#ISCELL
  mstr_symbols gnd *
  page221_i14
#CELL
  mstr_discrete cap *
  page221_i15
#ISCELL
  mstr_symbols gnd *
  page221_i19
#CELL
  mstr_discrete cap *
  page221_i20
#CELL
  mstr_discrete cap *
  page221_i22
#ISCELL
  mstr_symbols gnd *
  page221_i23
#CELL
  mstr_discrete cap *
  page221_i24
#ISCELL
  mstr_symbols gnd *
  page221_i25
#CELL
  mstr_discrete cap *
  page221_i26
#CELL
  mstr_discrete res *
  page221_i28
#ISCELL
  mstr_symbols gnd *
  page221_i29
#ISCELL
  mstr_symbols pvddq_abc *
  page221_i31
#CELL
  mstr_discrete res *
  page221_i32
#CELL
  mstr_discrete cap *
  page221_i34
#ISCELL
  mstr_symbols gnd *
  page221_i35
#ISCELL
  mstr_symbols gnd *
  page221_i36
#CELL
  mstr_discrete res *
  page221_i37
#CELL
  mstr_discrete res *
  page221_i38
#CELL
  mstr_discrete cap *
  page221_i39
#ISCELL
  mstr_symbols gnd *
  page221_i40
#ISCELL
  mstr_standard offpage *
  page221_i41
#ISCELL
  mstr_symbols p3v3 *
  page221_i43
#CELL
  mstr_discrete res *
  page221_i45
#ISCELL
  mstr_symbols p3v3 *
  page221_i46
#ISCELL
  mstr_symbols gnd *
  page221_i48
#CELL
  mstr_discrete cap *
  page221_i49
#CELL
  dev_discrete cap_a *
  page221_i50
#CELL
  dev_discrete cap_a *
  page221_i51
#CELL
  dev_discrete cap_a *
  page221_i52
#CELL
  mstr_discrete res *
  page221_i54
#CELL
  mstr_discrete res *
  page221_i55
#CELL
  mstr_misc shunt *
  page221_i56
#ISCELL
  mstr_standard offpage *
  page221_i6
#ISCELL
  mstr_symbols pvtt_abc *
  page221_i7
#ISCELL
  mstr_symbols gnd *
  page221_i8
#ISCELL
  mstr_misc dns *
  *
#ISCELL
  mstr_misc prelim *
  *
#ISCELL
  mstr_symbols cad_note *
  *
#ISCELL
  mstr_symbols intel_corp_bpage *
  *
#ISCELL
  mstr_standard offpage *
  page222_i10
#CELL
  mstr_discrete cap *
  page222_i12
#ISCELL
  mstr_symbols gnd *
  page222_i13
#CELL
  mstr_discrete cap *
  page222_i16
#ISCELL
  mstr_symbols gnd *
  page222_i17
#CELL
  mstr_discrete res *
  page222_i19
#CELL
  mstr_discrete cap *
  page222_i21
#ISCELL
  mstr_symbols gnd *
  page222_i22
#ISCELL
  mstr_symbols gnd *
  page222_i23
#CELL
  mstr_discrete cap *
  page222_i24
#ISCELL
  mstr_symbols gnd *
  page222_i25
#CELL
  mstr_discrete cap *
  page222_i26
#ISCELL
  mstr_symbols gnd *
  page222_i27
#CELL
  mstr_discrete cap *
  page222_i28
#ISCELL
  mstr_symbols gnd *
  page222_i29
#CELL
  mstr_discrete res *
  page222_i30
#CELL
  mstr_vreg mic5166 *
  page222_i31
#CELL
  mstr_discrete res *
  page222_i34
#ISCELL
  mstr_symbols pvddq_def *
  page222_i35
#CELL
  mstr_discrete res *
  page222_i37
#CELL
  mstr_discrete res *
  page222_i38
#ISCELL
  mstr_symbols gnd *
  page222_i39
#CELL
  mstr_discrete cap *
  page222_i40
#ISCELL
  mstr_standard offpage *
  page222_i41
#ISCELL
  mstr_symbols p3v3 *
  page222_i42
#ISCELL
  mstr_symbols p3v3 *
  page222_i43
#ISCELL
  mstr_symbols gnd *
  page222_i45
#CELL
  mstr_discrete cap *
  page222_i46
#CELL
  dev_discrete cap_a *
  page222_i47
#CELL
  dev_discrete cap_a *
  page222_i48
#CELL
  dev_discrete cap_a *
  page222_i49
#CELL
  mstr_discrete res *
  page222_i51
#CELL
  mstr_discrete res *
  page222_i52
#CELL
  mstr_misc shunt *
  page222_i53
#ISCELL
  mstr_symbols pvtt_def *
  page222_i6
#ISCELL
  mstr_symbols gnd *
  page222_i8
#ISCELL
  mstr_symbols pvtt_def *
  page222_i9
#ISCELL
  mstr_misc dns *
  *
#ISCELL
  mstr_symbols design_note *
  *
#ISCELL
  mstr_symbols intel_corp_bpage *
  *
#ISCELL
  mstr_standard offpage *
  page223_i1
#ISCELL
  mstr_standard offpage *
  page223_i10
#ISCELL
  mstr_standard offpage *
  page223_i11
#CELL
  mstr_discrete res *
  page223_i13
#CELL
  mstr_discrete res *
  page223_i14
#ISCELL
  mstr_symbols p3v3_stby *
  page223_i15
#CELL
  mstr_discrete res *
  page223_i16
#CELL
  mstr_discrete res *
  page223_i17
#ISCELL
  mstr_standard offpage *
  page223_i18
#ISCELL
  mstr_standard offpage *
  page223_i19
#ISCELL
  mstr_standard offpage *
  page223_i2
#ISCELL
  mstr_standard offpage *
  page223_i20
#CELL
  mstr_discrete res *
  page223_i21
#CELL
  mstr_discrete res *
  page223_i22
#CELL
  mstr_discrete res *
  page223_i23
#ISCELL
  mstr_symbols gnd *
  page223_i24
#CELL
  dev_discrete cap_a *
  page223_i25
#ISCELL
  mstr_symbols gnd *
  page223_i26
#CELL
  dev_discrete cap_a *
  page223_i27
#ISCELL
  mstr_symbols gnd *
  page223_i28
#ISCELL
  mstr_symbols p3v3_stby *
  page223_i29
#CELL
  mstr_discrete res *
  page223_i30
#CELL
  mstr_discrete res *
  page223_i32
#ISCELL
  mstr_standard offpage *
  page223_i34
#ISCELL
  mstr_symbols gnd *
  page223_i35
#CELL
  mstr_discrete cap *
  page223_i36
#CELL
  mstr_discrete cap *
  page223_i39
#ISCELL
  mstr_standard offpage *
  page223_i4
#ISCELL
  mstr_standard offpage *
  page223_i40
#CELL
  dev_discrete cap_a *
  page223_i41
#ISCELL
  mstr_symbols gnd *
  page223_i42
#ISCELL
  mstr_symbols gnd *
  page223_i43
#CELL
  dev_discrete cap_a *
  page223_i44
#ISCELL
  mstr_standard offpage *
  page223_i45
#ISCELL
  mstr_symbols gnd *
  page223_i46
#ISCELL
  mstr_symbols gnd *
  page223_i47
#ISCELL
  mstr_symbols gnd *
  page223_i48
#ISCELL
  mstr_symbols pvccio_cpu1 *
  page223_i49
#CELL
  mstr_discrete res *
  page223_i50
#CELL
  mstr_discrete res *
  page223_i53
#ISCELL
  mstr_symbols vcc_core *
  page223_i56
#CELL
  mstr_discrete res *
  page223_i57
#CELL
  mstr_discrete res *
  page223_i58
#CELL
  mstr_discrete cap *
  page223_i59
#ISCELL
  mstr_symbols gnd *
  page223_i60
#ISCELL
  mstr_symbols gnd *
  page223_i61
#ISCELL
  mstr_standard offpage *
  page223_i62
#ISCELL
  mstr_standard offpage *
  page223_i63
#ISCELL
  mstr_standard offpage *
  page223_i64
#ISCELL
  mstr_standard offpage *
  page223_i65
#ISCELL
  mstr_standard offpage *
  page223_i67
#ISCELL
  mstr_standard offpage *
  page223_i68
#ISCELL
  mstr_symbols pvccio_cpu1 *
  page223_i7
#ISCELL
  mstr_standard offpage *
  page223_i70
#ISCELL
  mstr_standard offpage *
  page223_i71
#ISCELL
  mstr_standard offpage *
  page223_i72
#ISCELL
  mstr_standard offpage *
  page223_i74
#CELL
  mstr_discrete res *
  page223_i77
#CELL
  mstr_discrete res *
  page223_i78
#CELL
  mstr_discrete res *
  page223_i79
#CELL
  mstr_discrete res *
  page223_i8
#CELL
  mstr_discrete cap *
  page223_i80
#ISCELL
  mstr_symbols gnd *
  page223_i81
#CELL
  mstr_discrete res *
  page223_i82
#CELL
  mstr_discrete res *
  page223_i84
#CELL
  mstr_discrete res *
  page223_i85
#CELL
  mstr_discrete res *
  page223_i87
#CELL
  mstr_discrete res *
  page223_i88
#ISCELL
  mstr_standard offpage *
  page223_i89
#ISCELL
  mstr_standard offpage *
  page223_i9
#CELL
  mstr_controller pxm1310b *
  page223_i90
#ISCELL
  mstr_symbols gnd *
  page223_i91
#CELL
  dev_discrete cap_a *
  page223_i92
#ISCELL
  mstr_misc dns *
  *
#ISCELL
  mstr_symbols intel_corp_bpage *
  *
#ISCELL
  mstr_symbols pvddq_ghj *
  page224_i1
#CELL
  mstr_discrete ir354xx *
  page224_i110
#CELL
  mstr_discrete ir354xx *
  page224_i111
#CELL
  mstr_discrete res *
  page224_i112
#ISCELL
  mstr_symbols gnd *
  page224_i113
#CELL
  mstr_discrete res *
  page224_i114
#ISCELL
  mstr_symbols gnd *
  page224_i115
#CELL
  dev_discrete cap_a *
  page224_i117
#ISCELL
  mstr_symbols gnd *
  page224_i118
#CELL
  w_hdl 3d01r5f-gp *
  page224_i119
#ISCELL
  mstr_symbols gnd *
  page224_i120
#CELL
  w_hdl sc2k2p50v3kx-gp *
  page224_i121
#CELL
  mstr_discrete cap *
  page224_i122
#ISCELL
  mstr_symbols gnd *
  page224_i123
#CELL
  dev_discrete cap_a *
  page224_i124
#ISCELL
  mstr_symbols gnd *
  page224_i125
#CELL
  w_hdl sc2k2p50v3kx-gp *
  page224_i127
#ISCELL
  mstr_symbols gnd *
  page224_i128
#CELL
  w_hdl 3d01r5f-gp *
  page224_i129
#CELL
  mstr_discrete cap *
  page224_i130
#ISCELL
  mstr_symbols gnd *
  page224_i131
#CELL
  mstr_discrete res *
  page224_i132
#CELL
  mstr_discrete res *
  page224_i133
#ISCELL
  mstr_symbols gnd *
  page224_i19
#ISCELL
  mstr_standard offpage *
  page224_i3
#ISCELL
  mstr_standard offpage *
  page224_i33
#ISCELL
  mstr_symbols gnd *
  page224_i35
#ISCELL
  mstr_standard offpage *
  page224_i4
#CELL
  mstr_discrete cap *
  page224_i44
#CELL
  mstr_discrete cap *
  page224_i45
#CELL
  mstr_discrete cap *
  page224_i46
#CELL
  mstr_discrete cap *
  page224_i47
#CELL
  mstr_discrete cap *
  page224_i48
#CELL
  mstr_discrete cap *
  page224_i50
#CELL
  dev_discrete cap_a *
  page224_i51
#CELL
  mstr_discrete res *
  page224_i52
#CELL
  dev_discrete cap_a *
  page224_i53
#CELL
  mstr_discrete cap *
  page224_i54
#CELL
  mstr_discrete inductor *
  page224_i55
#ISCELL
  mstr_standard offpage *
  page224_i58
#CELL
  mstr_discrete cap *
  page224_i6
#ISCELL
  mstr_standard offpage *
  page224_i61
#ISCELL
  mstr_standard offpage *
  page224_i62
#ISCELL
  mstr_standard offpage *
  page224_i63
#ISCELL
  mstr_symbols pvddq_ghj *
  page224_i64
#CELL
  mstr_discrete inductor *
  page224_i65
#CELL
  mstr_discrete cap *
  page224_i68
#ISCELL
  mstr_symbols gnd *
  page224_i69
#ISCELL
  mstr_symbols gnd *
  page224_i7
#ISCELL
  mstr_symbols gnd *
  page224_i70
#CELL
  mstr_discrete cap *
  page224_i72
#CELL
  dev_discrete cap_a *
  page224_i73
#CELL
  mstr_discrete cap *
  page224_i75
#CELL
  mstr_discrete res *
  page224_i76
#CELL
  mstr_discrete cap *
  page224_i77
#CELL
  dev_discrete cap_a *
  page224_i78
#CELL
  mstr_discrete cap *
  page224_i79
#CELL
  mstr_discrete cap *
  page224_i80
#CELL
  mstr_discrete cap *
  page224_i81
#ISCELL
  mstr_standard offpage *
  page224_i82
#ISCELL
  mstr_symbols vcc_core *
  page224_i83
#CELL
  mstr_discrete cap *
  page224_i84
#ISCELL
  mstr_symbols gnd *
  page224_i85
#ISCELL
  mstr_symbols p5v_stby *
  page224_i87
#ISCELL
  mstr_symbols p5v_stby *
  page224_i88
#ISCELL
  mstr_symbols vcc_core *
  page224_i89
#ISCELL
  mstr_misc dns *
  *
#ISCELL
  mstr_symbols intel_corp_bpage *
  *
#ISCELL
  mstr_symbols pvddq_ghj *
  page225_i109
#CELL
  mstr_discrete cap *
  page225_i110
#ISCELL
  mstr_symbols gnd *
  page225_i114
#ISCELL
  mstr_symbols vcc_core *
  page225_i120
#ISCELL
  mstr_symbols gnd *
  page225_i123
#CELL
  mstr_discrete inductor *
  page225_i124
#ISCELL
  mstr_symbols p12v_stby *
  page225_i176
#CELL
  mstr_discrete cap *
  page225_i178
#CELL
  mstr_discrete cap *
  page225_i179
#CELL
  mstr_discrete cap *
  page225_i180
#CELL
  mstr_discrete cap *
  page225_i181
#ISCELL
  mstr_symbols gnd *
  page225_i182
#CELL
  mstr_discrete cap *
  page225_i183
#CELL
  mstr_discrete cap *
  page225_i184
#ISCELL
  mstr_symbols pvddq_ghj *
  page225_i185
#ISCELL
  mstr_symbols pvddq_ghj *
  page225_i189
#ISCELL
  mstr_symbols gnd *
  page225_i191
#CELL
  mstr_discrete cap *
  page225_i192
#CELL
  mstr_discrete cap *
  page225_i193
#CELL
  mstr_discrete cap *
  page225_i194
#CELL
  mstr_discrete cap *
  page225_i195
#CELL
  dev_discrete cap_a *
  page225_i196
#CELL
  dev_discrete cap_a *
  page225_i197
#CELL
  dev_discrete cap_a *
  page225_i198
#CELL
  dev_discrete cap_a *
  page225_i199
#CELL
  dev_discrete cap_a *
  page225_i200
#CELL
  dev_discrete cap_a *
  page225_i201
#CELL
  dev_discrete cap_a *
  page225_i202
#CELL
  dev_discrete cap_a *
  page225_i203
#CELL
  dev_discrete cap_a *
  page225_i204
#ISCELL
  mstr_symbols pvddq_ghj *
  page225_i205
#ISCELL
  mstr_symbols gnd *
  page225_i206
#CELL
  dev_discrete cap_a *
  page225_i207
#CELL
  dev_discrete cap_a *
  page225_i208
#CELL
  dev_discrete cap_a *
  page225_i209
#CELL
  dev_discrete cap_a *
  page225_i210
#CELL
  dev_discrete cap_a *
  page225_i211
#CELL
  dev_discrete cap_a *
  page225_i212
#CELL
  dev_discrete cap_a *
  page225_i213
#CELL
  dev_discrete cap_a *
  page225_i214
#CELL
  dev_discrete cap_a *
  page225_i215
#CELL
  dev_discrete cap_a *
  page225_i216
#CELL
  dev_discrete cap_a *
  page225_i217
#CELL
  dev_discrete cap_a *
  page225_i218
#CELL
  dev_discrete cap_a *
  page225_i219
#CELL
  dev_discrete cap_a *
  page225_i220
#CELL
  dev_discrete cap_a *
  page225_i221
#ISCELL
  mstr_symbols pvddq_ghj *
  page225_i222
#CELL
  dev_discrete cap_a *
  page225_i223
#ISCELL
  mstr_symbols gnd *
  page225_i224
#CELL
  dev_discrete cap_a *
  page225_i225
#CELL
  dev_discrete cap_a *
  page225_i226
#CELL
  dev_discrete cap_a *
  page225_i227
#CELL
  dev_discrete cap_a *
  page225_i228
#CELL
  dev_discrete cap_a *
  page225_i229
#CELL
  dev_discrete cap_a *
  page225_i230
#CELL
  dev_discrete cap_a *
  page225_i231
#CELL
  dev_discrete cap_a *
  page225_i232
#CELL
  dev_discrete cap_a *
  page225_i233
#CELL
  dev_discrete cap_a *
  page225_i234
#CELL
  dev_discrete cap_a *
  page225_i235
#CELL
  dev_discrete cap_a *
  page225_i236
#CELL
  dev_discrete cap_a *
  page225_i237
#CELL
  dev_discrete cap_a *
  page225_i238
#CELL
  dev_discrete cap_a *
  page225_i239
#ISCELL
  mstr_symbols pvddq_ghj *
  page225_i240
#CELL
  dev_discrete cap_a *
  page225_i241
#ISCELL
  mstr_symbols gnd *
  page225_i242
#CELL
  mstr_misc shunt *
  page225_i243
#CELL
  mstr_misc shunt *
  page225_i244
#CELL
  mstr_discrete res *
  page225_i58
#ISCELL
  mstr_symbols gnd *
  page225_i65
#ISCELL
  mstr_standard offpage *
  page225_i70
#ISCELL
  mstr_standard offpage *
  page225_i72
#ISCELL
  mstr_symbols pvddq_ghj *
  page225_i73
#CELL
  mstr_discrete res *
  page225_i74
#CELL
  mstr_discrete capp *
  page225_i75
#CELL
  mstr_discrete capp *
  page225_i76
#CELL
  mstr_discrete capp *
  page225_i77
#CELL
  mstr_discrete capp *
  page225_i78
#ISCELL
  mstr_symbols pvddq_ghj *
  page225_i80
#ISCELL
  mstr_symbols gnd *
  page225_i81
#CELL
  mstr_discrete cap *
  page225_i82
#CELL
  mstr_discrete cap *
  page225_i83
#CELL
  mstr_discrete cap *
  page225_i88
#CELL
  mstr_discrete cap *
  page225_i89
#CELL
  mstr_discrete cap *
  page225_i90
#CELL
  mstr_discrete cap *
  page225_i91
#CELL
  mstr_discrete cap *
  page225_i92
#ISCELL
  mstr_symbols pvddq_ghj *
  page225_i93
#ISCELL
  mstr_symbols gnd *
  page225_i94
#ISCELL
  mstr_misc dns *
  *
#ISCELL
  mstr_symbols design_note *
  *
#ISCELL
  mstr_symbols intel_corp_bpage *
  *
#ISCELL
  mstr_standard offpage *
  page226_i1
#ISCELL
  mstr_standard offpage *
  page226_i10
#ISCELL
  mstr_standard offpage *
  page226_i11
#CELL
  mstr_discrete res *
  page226_i13
#CELL
  mstr_discrete res *
  page226_i14
#ISCELL
  mstr_symbols p3v3_stby *
  page226_i15
#CELL
  mstr_discrete res *
  page226_i16
#CELL
  mstr_discrete res *
  page226_i17
#ISCELL
  mstr_standard offpage *
  page226_i18
#ISCELL
  mstr_standard offpage *
  page226_i19
#ISCELL
  mstr_standard offpage *
  page226_i2
#ISCELL
  mstr_standard offpage *
  page226_i20
#CELL
  mstr_discrete res *
  page226_i21
#CELL
  mstr_discrete res *
  page226_i22
#CELL
  mstr_discrete res *
  page226_i23
#ISCELL
  mstr_symbols gnd *
  page226_i24
#CELL
  dev_discrete cap_a *
  page226_i25
#ISCELL
  mstr_symbols gnd *
  page226_i26
#CELL
  dev_discrete cap_a *
  page226_i27
#ISCELL
  mstr_symbols gnd *
  page226_i28
#ISCELL
  mstr_symbols p3v3_stby *
  page226_i29
#CELL
  mstr_discrete res *
  page226_i30
#CELL
  mstr_discrete res *
  page226_i32
#ISCELL
  mstr_standard offpage *
  page226_i34
#ISCELL
  mstr_symbols gnd *
  page226_i35
#CELL
  mstr_discrete cap *
  page226_i36
#CELL
  mstr_discrete cap *
  page226_i39
#ISCELL
  mstr_standard offpage *
  page226_i4
#ISCELL
  mstr_standard offpage *
  page226_i40
#CELL
  dev_discrete cap_a *
  page226_i41
#ISCELL
  mstr_symbols gnd *
  page226_i42
#ISCELL
  mstr_symbols gnd *
  page226_i43
#CELL
  dev_discrete cap_a *
  page226_i44
#ISCELL
  mstr_standard offpage *
  page226_i45
#ISCELL
  mstr_symbols gnd *
  page226_i46
#ISCELL
  mstr_symbols gnd *
  page226_i47
#ISCELL
  mstr_symbols gnd *
  page226_i48
#ISCELL
  mstr_symbols pvccio_cpu1 *
  page226_i49
#CELL
  mstr_discrete res *
  page226_i50
#CELL
  mstr_discrete res *
  page226_i53
#ISCELL
  mstr_symbols vcc_core *
  page226_i56
#CELL
  mstr_discrete res *
  page226_i57
#CELL
  mstr_discrete res *
  page226_i58
#CELL
  mstr_discrete cap *
  page226_i59
#ISCELL
  mstr_symbols gnd *
  page226_i60
#ISCELL
  mstr_symbols gnd *
  page226_i61
#ISCELL
  mstr_standard offpage *
  page226_i62
#ISCELL
  mstr_standard offpage *
  page226_i63
#ISCELL
  mstr_standard offpage *
  page226_i64
#ISCELL
  mstr_standard offpage *
  page226_i65
#ISCELL
  mstr_standard offpage *
  page226_i67
#ISCELL
  mstr_standard offpage *
  page226_i68
#ISCELL
  mstr_symbols pvccio_cpu1 *
  page226_i7
#ISCELL
  mstr_standard offpage *
  page226_i70
#ISCELL
  mstr_standard offpage *
  page226_i71
#ISCELL
  mstr_standard offpage *
  page226_i72
#ISCELL
  mstr_standard offpage *
  page226_i74
#CELL
  mstr_discrete res *
  page226_i77
#CELL
  mstr_discrete res *
  page226_i78
#CELL
  mstr_discrete res *
  page226_i79
#CELL
  mstr_discrete res *
  page226_i8
#CELL
  mstr_discrete cap *
  page226_i80
#ISCELL
  mstr_symbols gnd *
  page226_i81
#CELL
  mstr_discrete res *
  page226_i82
#CELL
  mstr_discrete res *
  page226_i84
#CELL
  mstr_discrete res *
  page226_i85
#CELL
  mstr_discrete res *
  page226_i87
#CELL
  mstr_discrete res *
  page226_i88
#ISCELL
  mstr_standard offpage *
  page226_i89
#ISCELL
  mstr_standard offpage *
  page226_i9
#CELL
  mstr_controller pxm1310b *
  page226_i90
#ISCELL
  mstr_symbols gnd *
  page226_i91
#CELL
  dev_discrete cap_a *
  page226_i92
#ISCELL
  mstr_misc dns *
  *
#ISCELL
  mstr_symbols intel_corp_bpage *
  *
#ISCELL
  mstr_symbols pvddq_klm *
  page227_i1
#CELL
  mstr_discrete ir354xx *
  page227_i101
#CELL
  mstr_discrete ir354xx *
  page227_i102
#CELL
  mstr_discrete res *
  page227_i103
#ISCELL
  mstr_symbols gnd *
  page227_i104
#CELL
  mstr_discrete res *
  page227_i105
#ISCELL
  mstr_symbols gnd *
  page227_i106
#ISCELL
  mstr_symbols p5v_stby *
  page227_i107
#CELL
  dev_discrete cap_a *
  page227_i109
#ISCELL
  mstr_symbols gnd *
  page227_i110
#CELL
  w_hdl sc2k2p50v3kx-gp *
  page227_i111
#ISCELL
  mstr_symbols gnd *
  page227_i113
#CELL
  mstr_discrete cap *
  page227_i114
#ISCELL
  mstr_symbols gnd *
  page227_i115
#CELL
  w_hdl sc2k2p50v3kx-gp *
  page227_i116
#ISCELL
  mstr_symbols gnd *
  page227_i117
#CELL
  mstr_discrete cap *
  page227_i119
#ISCELL
  mstr_symbols gnd *
  page227_i120
#CELL
  dev_discrete cap_a *
  page227_i122
#ISCELL
  mstr_symbols gnd *
  page227_i123
#CELL
  w_hdl 3d01r5f-gp *
  page227_i124
#CELL
  w_hdl 3d01r5f-gp *
  page227_i125
#CELL
  mstr_discrete res *
  page227_i126
#CELL
  mstr_discrete res *
  page227_i127
#ISCELL
  mstr_symbols gnd *
  page227_i19
#ISCELL
  mstr_standard offpage *
  page227_i3
#ISCELL
  mstr_standard offpage *
  page227_i33
#ISCELL
  mstr_symbols gnd *
  page227_i35
#ISCELL
  mstr_standard offpage *
  page227_i4
#CELL
  mstr_discrete cap *
  page227_i44
#CELL
  mstr_discrete cap *
  page227_i45
#CELL
  mstr_discrete cap *
  page227_i46
#CELL
  mstr_discrete cap *
  page227_i47
#CELL
  mstr_discrete cap *
  page227_i48
#CELL
  mstr_discrete cap *
  page227_i50
#CELL
  dev_discrete cap_a *
  page227_i51
#CELL
  mstr_discrete res *
  page227_i52
#CELL
  dev_discrete cap_a *
  page227_i53
#CELL
  mstr_discrete cap *
  page227_i54
#CELL
  mstr_discrete inductor *
  page227_i55
#ISCELL
  mstr_standard offpage *
  page227_i58
#CELL
  mstr_discrete cap *
  page227_i6
#ISCELL
  mstr_standard offpage *
  page227_i61
#ISCELL
  mstr_standard offpage *
  page227_i62
#ISCELL
  mstr_standard offpage *
  page227_i63
#ISCELL
  mstr_symbols pvddq_klm *
  page227_i64
#CELL
  mstr_discrete inductor *
  page227_i65
#CELL
  mstr_discrete cap *
  page227_i68
#ISCELL
  mstr_symbols gnd *
  page227_i69
#ISCELL
  mstr_symbols gnd *
  page227_i7
#ISCELL
  mstr_symbols gnd *
  page227_i70
#CELL
  mstr_discrete cap *
  page227_i72
#CELL
  dev_discrete cap_a *
  page227_i73
#CELL
  mstr_discrete cap *
  page227_i75
#CELL
  mstr_discrete res *
  page227_i76
#CELL
  mstr_discrete cap *
  page227_i77
#CELL
  dev_discrete cap_a *
  page227_i78
#CELL
  mstr_discrete cap *
  page227_i79
#CELL
  mstr_discrete cap *
  page227_i80
#CELL
  mstr_discrete cap *
  page227_i81
#ISCELL
  mstr_standard offpage *
  page227_i82
#ISCELL
  mstr_symbols vcc_core *
  page227_i83
#CELL
  mstr_discrete cap *
  page227_i84
#ISCELL
  mstr_symbols gnd *
  page227_i85
#ISCELL
  mstr_symbols vcc_core *
  page227_i86
#ISCELL
  mstr_symbols p5v_stby *
  page227_i88
#ISCELL
  mstr_misc dns *
  *
#ISCELL
  mstr_symbols intel_corp_bpage *
  *
#ISCELL
  mstr_symbols pvddq_klm *
  page228_i109
#CELL
  mstr_discrete cap *
  page228_i110
#ISCELL
  mstr_symbols gnd *
  page228_i114
#ISCELL
  mstr_symbols vcc_core *
  page228_i120
#ISCELL
  mstr_symbols gnd *
  page228_i123
#CELL
  mstr_discrete inductor *
  page228_i124
#CELL
  mstr_discrete capp *
  page228_i175
#ISCELL
  mstr_symbols p12v_stby *
  page228_i182
#CELL
  mstr_discrete cap *
  page228_i183
#CELL
  mstr_discrete cap *
  page228_i185
#CELL
  mstr_discrete cap *
  page228_i186
#CELL
  mstr_discrete cap *
  page228_i187
#CELL
  mstr_discrete cap *
  page228_i188
#ISCELL
  mstr_symbols gnd *
  page228_i189
#CELL
  mstr_discrete cap *
  page228_i190
#ISCELL
  mstr_symbols pvddq_klm *
  page228_i191
#ISCELL
  mstr_symbols pvddq_klm *
  page228_i195
#ISCELL
  mstr_symbols gnd *
  page228_i197
#CELL
  dev_discrete cap_a *
  page228_i198
#CELL
  dev_discrete cap_a *
  page228_i199
#CELL
  dev_discrete cap_a *
  page228_i200
#CELL
  dev_discrete cap_a *
  page228_i201
#CELL
  dev_discrete cap_a *
  page228_i202
#CELL
  dev_discrete cap_a *
  page228_i203
#CELL
  dev_discrete cap_a *
  page228_i204
#CELL
  dev_discrete cap_a *
  page228_i205
#CELL
  dev_discrete cap_a *
  page228_i206
#ISCELL
  mstr_symbols pvddq_klm *
  page228_i207
#ISCELL
  mstr_symbols gnd *
  page228_i208
#CELL
  dev_discrete cap_a *
  page228_i209
#CELL
  dev_discrete cap_a *
  page228_i210
#CELL
  dev_discrete cap_a *
  page228_i211
#CELL
  dev_discrete cap_a *
  page228_i212
#CELL
  dev_discrete cap_a *
  page228_i213
#CELL
  dev_discrete cap_a *
  page228_i214
#CELL
  dev_discrete cap_a *
  page228_i215
#CELL
  dev_discrete cap_a *
  page228_i216
#CELL
  dev_discrete cap_a *
  page228_i217
#CELL
  dev_discrete cap_a *
  page228_i218
#CELL
  dev_discrete cap_a *
  page228_i219
#CELL
  dev_discrete cap_a *
  page228_i220
#CELL
  dev_discrete cap_a *
  page228_i221
#CELL
  dev_discrete cap_a *
  page228_i222
#CELL
  dev_discrete cap_a *
  page228_i223
#ISCELL
  mstr_symbols pvddq_klm *
  page228_i224
#CELL
  dev_discrete cap_a *
  page228_i225
#ISCELL
  mstr_symbols gnd *
  page228_i226
#CELL
  dev_discrete cap_a *
  page228_i227
#CELL
  dev_discrete cap_a *
  page228_i228
#CELL
  dev_discrete cap_a *
  page228_i229
#CELL
  dev_discrete cap_a *
  page228_i230
#CELL
  dev_discrete cap_a *
  page228_i231
#CELL
  dev_discrete cap_a *
  page228_i232
#CELL
  dev_discrete cap_a *
  page228_i233
#CELL
  dev_discrete cap_a *
  page228_i234
#CELL
  dev_discrete cap_a *
  page228_i235
#CELL
  dev_discrete cap_a *
  page228_i236
#CELL
  dev_discrete cap_a *
  page228_i237
#CELL
  dev_discrete cap_a *
  page228_i238
#CELL
  dev_discrete cap_a *
  page228_i239
#CELL
  dev_discrete cap_a *
  page228_i240
#CELL
  dev_discrete cap_a *
  page228_i241
#ISCELL
  mstr_symbols pvddq_klm *
  page228_i242
#CELL
  dev_discrete cap_a *
  page228_i243
#ISCELL
  mstr_symbols gnd *
  page228_i244
#CELL
  mstr_misc shunt *
  page228_i245
#CELL
  mstr_misc shunt *
  page228_i246
#CELL
  mstr_discrete res *
  page228_i58
#ISCELL
  mstr_symbols gnd *
  page228_i65
#ISCELL
  mstr_standard offpage *
  page228_i70
#ISCELL
  mstr_standard offpage *
  page228_i72
#ISCELL
  mstr_symbols pvddq_klm *
  page228_i73
#CELL
  mstr_discrete res *
  page228_i74
#CELL
  mstr_discrete capp *
  page228_i75
#CELL
  mstr_discrete capp *
  page228_i76
#CELL
  mstr_discrete capp *
  page228_i77
#CELL
  mstr_discrete capp *
  page228_i78
#ISCELL
  mstr_symbols pvddq_klm *
  page228_i80
#ISCELL
  mstr_symbols gnd *
  page228_i81
#CELL
  mstr_discrete cap *
  page228_i82
#CELL
  mstr_discrete cap *
  page228_i83
#CELL
  mstr_discrete cap *
  page228_i88
#CELL
  mstr_discrete cap *
  page228_i89
#CELL
  mstr_discrete cap *
  page228_i90
#CELL
  mstr_discrete cap *
  page228_i91
#CELL
  mstr_discrete cap *
  page228_i92
#ISCELL
  mstr_symbols pvddq_klm *
  page228_i93
#ISCELL
  mstr_symbols gnd *
  page228_i94
#ISCELL
  mstr_misc dns *
  *
#ISCELL
  mstr_misc prelim *
  *
#ISCELL
  mstr_symbols cad_note *
  *
#ISCELL
  mstr_symbols intel_corp_bpage *
  *
#ISCELL
  mstr_symbols pvtt_ghj *
  page229_i10
#CELL
  mstr_discrete res *
  page229_i14
#CELL
  mstr_discrete cap *
  page229_i15
#ISCELL
  mstr_symbols gnd *
  page229_i16
#CELL
  mstr_discrete cap *
  page229_i17
#ISCELL
  mstr_symbols gnd *
  page229_i19
#ISCELL
  mstr_standard offpage *
  page229_i2
#CELL
  mstr_discrete cap *
  page229_i21
#ISCELL
  mstr_symbols gnd *
  page229_i22
#ISCELL
  mstr_symbols gnd *
  page229_i23
#CELL
  mstr_vreg mic5166 *
  page229_i24
#CELL
  mstr_discrete cap *
  page229_i25
#ISCELL
  mstr_symbols gnd *
  page229_i26
#CELL
  mstr_discrete cap *
  page229_i27
#ISCELL
  mstr_symbols gnd *
  page229_i28
#CELL
  mstr_discrete cap *
  page229_i29
#ISCELL
  mstr_symbols pvtt_ghj *
  page229_i3
#ISCELL
  mstr_symbols gnd *
  page229_i30
#CELL
  mstr_discrete res *
  page229_i32
#CELL
  mstr_discrete res *
  page229_i34
#CELL
  mstr_discrete res *
  page229_i35
#CELL
  mstr_discrete cap *
  page229_i36
#ISCELL
  mstr_symbols gnd *
  page229_i37
#ISCELL
  mstr_symbols pvddq_ghj *
  page229_i38
#CELL
  mstr_discrete res *
  page229_i39
#ISCELL
  mstr_standard offpage *
  page229_i41
#ISCELL
  mstr_symbols p3v3 *
  page229_i42
#ISCELL
  mstr_symbols p3v3 *
  page229_i43
#ISCELL
  mstr_symbols gnd *
  page229_i45
#CELL
  mstr_discrete cap *
  page229_i46
#CELL
  dev_discrete cap_a *
  page229_i47
#CELL
  dev_discrete cap_a *
  page229_i48
#CELL
  dev_discrete cap_a *
  page229_i49
#CELL
  mstr_discrete res *
  page229_i51
#CELL
  mstr_discrete res *
  page229_i52
#CELL
  mstr_misc shunt *
  page229_i53
#ISCELL
  mstr_symbols gnd *
  page229_i7
#ISCELL
  mstr_misc dns *
  *
#ISCELL
  mstr_misc prelim *
  *
#ISCELL
  mstr_symbols cad_note *
  *
#ISCELL
  mstr_symbols intel_corp_bpage *
  *
#ISCELL
  mstr_symbols gnd *
  page230_i10
#ISCELL
  mstr_symbols gnd *
  page230_i15
#CELL
  mstr_discrete cap *
  page230_i16
#CELL
  mstr_discrete res *
  page230_i17
#CELL
  mstr_discrete cap *
  page230_i18
#ISCELL
  mstr_symbols gnd *
  page230_i19
#CELL
  mstr_discrete cap *
  page230_i21
#ISCELL
  mstr_symbols gnd *
  page230_i22
#ISCELL
  mstr_symbols gnd *
  page230_i23
#ISCELL
  mstr_symbols gnd *
  page230_i24
#CELL
  mstr_discrete cap *
  page230_i25
#CELL
  mstr_discrete cap *
  page230_i26
#ISCELL
  mstr_symbols gnd *
  page230_i27
#CELL
  mstr_discrete cap *
  page230_i28
#ISCELL
  mstr_symbols gnd *
  page230_i29
#CELL
  mstr_discrete res *
  page230_i30
#CELL
  mstr_vreg mic5166 *
  page230_i31
#CELL
  mstr_discrete res *
  page230_i34
#ISCELL
  mstr_symbols pvddq_klm *
  page230_i35
#CELL
  mstr_discrete res *
  page230_i37
#CELL
  mstr_discrete res *
  page230_i38
#CELL
  mstr_discrete cap *
  page230_i39
#ISCELL
  mstr_symbols gnd *
  page230_i40
#ISCELL
  mstr_standard offpage *
  page230_i41
#ISCELL
  mstr_symbols p3v3 *
  page230_i42
#ISCELL
  mstr_symbols p3v3 *
  page230_i43
#ISCELL
  mstr_symbols gnd *
  page230_i45
#CELL
  mstr_discrete cap *
  page230_i46
#CELL
  dev_discrete cap_a *
  page230_i47
#CELL
  dev_discrete cap_a *
  page230_i48
#CELL
  dev_discrete cap_a *
  page230_i49
#CELL
  mstr_discrete res *
  page230_i51
#CELL
  mstr_discrete res *
  page230_i52
#CELL
  mstr_misc shunt *
  page230_i53
#ISCELL
  mstr_symbols pvtt_klm *
  page230_i6
#ISCELL
  mstr_standard offpage *
  page230_i8
#ISCELL
  mstr_symbols pvtt_klm *
  page230_i9
#ISCELL
  mstr_misc dns *
  *
#ISCELL
  mstr_symbols cad_note *
  *
#ISCELL
  mstr_symbols intel_corp_bpage *
  *
#CELL
  mstr_discrete cap *
  page231_i122
#ISCELL
  mstr_symbols pvpp_abc *
  page231_i123
#CELL
  mstr_discrete cap *
  page231_i124
#CELL
  mstr_discrete cap *
  page231_i125
#CELL
  mstr_discrete cap *
  page231_i126
#ISCELL
  mstr_symbols gnd *
  page231_i127
#CELL
  mstr_discrete cap *
  page231_i128
#CELL
  mstr_discrete cap *
  page231_i129
#CELL
  mstr_discrete cap *
  page231_i130
#CELL
  mstr_discrete cap *
  page231_i131
#ISCELL
  mstr_symbols agnd_scsi *
  page231_i132
#CELL
  mstr_discrete res *
  page231_i134
#ISCELL
  mstr_standard offpage *
  page231_i135
#CELL
  mstr_discrete res *
  page231_i136
#CELL
  mstr_discrete cap *
  page231_i140
#ISCELL
  mstr_symbols gnd *
  page231_i141
#CELL
  mstr_discrete cap *
  page231_i142
#CELL
  mstr_discrete res *
  page231_i143
#CELL
  mstr_discrete cap *
  page231_i145
#CELL
  mstr_discrete cap *
  page231_i146
#ISCELL
  mstr_symbols gnd *
  page231_i147
#CELL
  mstr_discrete cap *
  page231_i148
#CELL
  mstr_discrete cap *
  page231_i149
#CELL
  mstr_discrete cap *
  page231_i151
#ISCELL
  mstr_symbols gnd *
  page231_i152
#CELL
  mstr_discrete res *
  page231_i154
#CELL
  mstr_discrete cap *
  page231_i159
#ISCELL
  mstr_symbols gnd *
  page231_i160
#CELL
  mstr_discrete cap *
  page231_i161
#CELL
  mstr_discrete ferrite *
  page231_i162
#ISCELL
  mstr_symbols p12v_stby *
  page231_i163
#ISCELL
  mstr_symbols agnd_scsi *
  page231_i165
#CELL
  mstr_discrete res *
  page231_i166
#CELL
  mstr_discrete res *
  page231_i167
#CELL
  mstr_discrete res *
  page231_i168
#ISCELL
  mstr_symbols gnd *
  page231_i169
#CELL
  mstr_discrete res *
  page231_i170
#ISCELL
  mstr_symbols agnd_scsi *
  page231_i171
#ISCELL
  mstr_symbols gnd *
  page231_i173
#CELL
  mstr_discrete res *
  page231_i174
#CELL
  mstr_discrete cap *
  page231_i175
#ISCELL
  mstr_symbols gnd *
  page231_i176
#CELL
  mstr_discrete res *
  page231_i177
#CELL
  mstr_discrete inductor *
  page231_i178
#ISCELL
  mstr_symbols gnd *
  page231_i179
#CELL
  mstr_discrete capp *
  page231_i180
#ISCELL
  mstr_symbols gnd *
  page231_i183
#CELL
  mstr_discrete cap *
  page231_i184
#ISCELL
  mstr_symbols gnd *
  page231_i185
#CELL
  mstr_discrete cap *
  page231_i186
#ISCELL
  mstr_symbols pvpp_abc *
  page231_i187
#ISCELL
  mstr_standard offpage *
  page231_i188
#ISCELL
  mstr_symbols agnd_scsi *
  page231_i189
#ISCELL
  mstr_symbols agnd_scsi *
  page231_i190
#ISCELL
  mstr_symbols p3v3_stby *
  page231_i192
#CELL
  mstr_vreg ncp3232l *
  page231_i193
#CELL
  mstr_discrete cap *
  page231_i194
#ISCELL
  mstr_symbols agnd_scsi *
  page231_i195
#ISCELL
  mstr_symbols gnd *
  page231_i196
#CELL
  mstr_discrete cap *
  page231_i199
#CELL
  mstr_discrete cap *
  page231_i200
#CELL
  mstr_discrete res *
  page231_i201
#CELL
  mstr_discrete cap *
  page231_i202
#ISCELL
  mstr_symbols agnd_scsi *
  page231_i203
#ISCELL
  mstr_symbols agnd_scsi *
  page231_i204
#CELL
  dev_discrete cap_a *
  page231_i205
#ISCELL
  mstr_symbols gnd *
  page231_i206
#CELL
  mstr_discrete res *
  page231_i208
#CELL
  mstr_discrete cap *
  page231_i209
#CELL
  mstr_discrete cap *
  page231_i210
#CELL
  mstr_discrete cap *
  page231_i211
#ISCELL
  mstr_symbols gnd *
  page231_i212
#ISCELL
  mstr_symbols gnd *
  page231_i213
#ISCELL
  mstr_symbols gnd *
  page231_i214
#CELL
  mstr_discrete cap *
  page231_i215
#ISCELL
  mstr_symbols gnd *
  page231_i216
#CELL
  mstr_discrete capp *
  page231_i217
#CELL
  mstr_discrete res *
  page231_i218
#CELL
  mstr_discrete cap *
  page231_i219
#CELL
  mstr_discrete res *
  page231_i220
#ISCELL
  mstr_misc dns *
  *
#ISCELL
  mstr_symbols intel_corp_bpage *
  *
#CELL
  mstr_discrete cap *
  page232_i102
#ISCELL
  mstr_symbols pvpp_def *
  page232_i103
#CELL
  mstr_discrete cap *
  page232_i104
#CELL
  mstr_discrete cap *
  page232_i105
#CELL
  mstr_discrete cap *
  page232_i106
#CELL
  mstr_discrete cap *
  page232_i108
#CELL
  mstr_discrete cap *
  page232_i109
#CELL
  mstr_discrete cap *
  page232_i110
#CELL
  mstr_discrete cap *
  page232_i111
#CELL
  mstr_discrete cap *
  page232_i125
#CELL
  mstr_discrete cap *
  page232_i126
#ISCELL
  mstr_symbols gnd *
  page232_i127
#CELL
  mstr_discrete cap *
  page232_i128
#CELL
  mstr_discrete cap *
  page232_i129
#ISCELL
  mstr_symbols gnd *
  page232_i149
#CELL
  mstr_discrete res *
  page232_i150
#ISCELL
  mstr_symbols agnd_scsi *
  page232_i151
#ISCELL
  mstr_symbols pvpp_def *
  page232_i167
#ISCELL
  mstr_standard offpage *
  page232_i181
#CELL
  mstr_discrete cap *
  page232_i185
#CELL
  mstr_discrete res *
  page232_i193
#CELL
  mstr_discrete cap *
  page232_i197
#ISCELL
  mstr_symbols gnd *
  page232_i198
#ISCELL
  mstr_symbols p12v_stby *
  page232_i199
#CELL
  mstr_discrete ferrite *
  page232_i200
#ISCELL
  mstr_symbols gnd *
  page232_i201
#CELL
  mstr_discrete cap *
  page232_i202
#CELL
  mstr_discrete cap *
  page232_i207
#ISCELL
  mstr_symbols gnd *
  page232_i208
#CELL
  mstr_discrete cap *
  page232_i209
#CELL
  mstr_discrete res *
  page232_i210
#ISCELL
  mstr_symbols p3v3_stby *
  page232_i211
#ISCELL
  mstr_standard offpage *
  page232_i212
#CELL
  mstr_vreg ncp3232l *
  page232_i214
#ISCELL
  mstr_symbols gnd *
  page232_i215
#CELL
  mstr_discrete res *
  page232_i218
#ISCELL
  mstr_symbols gnd *
  page232_i219
#CELL
  mstr_discrete cap *
  page232_i220
#ISCELL
  mstr_symbols gnd *
  page232_i226
#CELL
  mstr_discrete res *
  page232_i227
#ISCELL
  mstr_symbols gnd *
  page232_i228
#CELL
  mstr_discrete capp *
  page232_i229
#ISCELL
  mstr_symbols gnd *
  page232_i235
#CELL
  mstr_discrete cap *
  page232_i236
#ISCELL
  mstr_symbols gnd *
  page232_i237
#CELL
  mstr_discrete cap *
  page232_i238
#CELL
  mstr_discrete inductor *
  page232_i239
#CELL
  mstr_discrete res *
  page232_i240
#CELL
  mstr_discrete cap *
  page232_i241
#ISCELL
  mstr_symbols agnd_scsi *
  page232_i247
#ISCELL
  mstr_symbols agnd_scsi *
  page232_i248
#ISCELL
  mstr_symbols agnd_scsi *
  page232_i249
#ISCELL
  mstr_symbols agnd_scsi *
  page232_i250
#ISCELL
  mstr_symbols agnd_scsi *
  page232_i251
#CELL
  dev_discrete cap_a *
  page232_i252
#CELL
  mstr_discrete cap *
  page232_i253
#ISCELL
  mstr_symbols agnd_scsi *
  page232_i254
#ISCELL
  mstr_symbols gnd *
  page232_i255
#CELL
  mstr_discrete res *
  page232_i257
#CELL
  mstr_discrete cap *
  page232_i259
#CELL
  mstr_discrete cap *
  page232_i260
#CELL
  mstr_discrete cap *
  page232_i261
#CELL
  mstr_discrete cap *
  page232_i262
#ISCELL
  mstr_symbols gnd *
  page232_i263
#ISCELL
  mstr_symbols gnd *
  page232_i264
#ISCELL
  mstr_symbols gnd *
  page232_i265
#ISCELL
  mstr_symbols gnd *
  page232_i266
#CELL
  mstr_discrete capp *
  page232_i267
#CELL
  mstr_discrete res *
  page232_i298
#CELL
  mstr_discrete res *
  page232_i299
#CELL
  mstr_discrete res *
  page232_i300
#CELL
  mstr_discrete cap *
  page232_i301
#CELL
  mstr_discrete cap *
  page232_i302
#CELL
  mstr_discrete res *
  page232_i303
#CELL
  mstr_discrete res *
  page232_i304
#CELL
  mstr_discrete cap *
  page232_i306
#CELL
  mstr_discrete res *
  page232_i307
#ISCELL
  mstr_symbols agnd_scsi *
  page232_i308
#ISCELL
  mstr_misc dns *
  *
#ISCELL
  mstr_symbols intel_corp_bpage *
  *
#CELL
  mstr_discrete cap *
  page233_i109
#ISCELL
  mstr_symbols pvpp_ghj *
  page233_i110
#CELL
  mstr_discrete cap *
  page233_i111
#CELL
  mstr_discrete cap *
  page233_i112
#CELL
  mstr_discrete cap *
  page233_i113
#CELL
  mstr_discrete cap *
  page233_i115
#CELL
  mstr_discrete cap *
  page233_i116
#CELL
  mstr_discrete cap *
  page233_i117
#CELL
  mstr_discrete cap *
  page233_i118
#CELL
  mstr_discrete cap *
  page233_i132
#CELL
  mstr_discrete cap *
  page233_i133
#ISCELL
  mstr_symbols gnd *
  page233_i134
#CELL
  mstr_discrete cap *
  page233_i135
#CELL
  mstr_discrete cap *
  page233_i136
#ISCELL
  mstr_symbols gnd *
  page233_i156
#CELL
  mstr_discrete res *
  page233_i157
#ISCELL
  mstr_symbols agnd_scsi *
  page233_i158
#ISCELL
  mstr_symbols pvpp_ghj *
  page233_i174
#ISCELL
  mstr_symbols gnd *
  page233_i180
#ISCELL
  mstr_standard offpage *
  page233_i181
#CELL
  mstr_discrete res *
  page233_i182
#CELL
  mstr_discrete cap *
  page233_i183
#CELL
  mstr_discrete res *
  page233_i184
#CELL
  mstr_discrete res *
  page233_i185
#ISCELL
  mstr_symbols p3v3_stby *
  page233_i186
#CELL
  mstr_discrete cap *
  page233_i187
#ISCELL
  mstr_symbols gnd *
  page233_i188
#CELL
  mstr_discrete cap *
  page233_i189
#CELL
  mstr_discrete cap *
  page233_i194
#ISCELL
  mstr_symbols gnd *
  page233_i195
#CELL
  mstr_discrete cap *
  page233_i196
#ISCELL
  mstr_symbols p12v_stby *
  page233_i197
#CELL
  mstr_discrete ferrite *
  page233_i198
#CELL
  mstr_discrete res *
  page233_i199
#ISCELL
  mstr_symbols gnd *
  page233_i200
#CELL
  mstr_discrete cap *
  page233_i201
#ISCELL
  mstr_standard offpage *
  page233_i202
#ISCELL
  mstr_symbols gnd *
  page233_i203
#ISCELL
  mstr_symbols gnd *
  page233_i207
#CELL
  mstr_discrete res *
  page233_i208
#CELL
  mstr_discrete cap *
  page233_i209
#ISCELL
  mstr_symbols gnd *
  page233_i210
#CELL
  mstr_discrete res *
  page233_i211
#ISCELL
  mstr_symbols gnd *
  page233_i216
#CELL
  mstr_discrete capp *
  page233_i217
#ISCELL
  mstr_symbols gnd *
  page233_i220
#CELL
  mstr_discrete cap *
  page233_i221
#ISCELL
  mstr_symbols gnd *
  page233_i222
#CELL
  mstr_discrete cap *
  page233_i223
#CELL
  mstr_discrete cap *
  page233_i224
#CELL
  mstr_vreg ncp3232l *
  page233_i225
#ISCELL
  mstr_symbols agnd_scsi *
  page233_i226
#ISCELL
  mstr_symbols agnd_scsi *
  page233_i227
#ISCELL
  mstr_symbols agnd_scsi *
  page233_i228
#ISCELL
  mstr_symbols agnd_scsi *
  page233_i229
#ISCELL
  mstr_symbols agnd_scsi *
  page233_i230
#CELL
  dev_discrete cap_a *
  page233_i242
#ISCELL
  mstr_symbols gnd *
  page233_i243
#ISCELL
  mstr_symbols agnd_scsi *
  page233_i244
#ISCELL
  mstr_symbols gnd *
  page233_i246
#CELL
  mstr_discrete res *
  page233_i247
#CELL
  mstr_discrete cap *
  page233_i248
#ISCELL
  mstr_symbols gnd *
  page233_i249
#ISCELL
  mstr_symbols gnd *
  page233_i250
#ISCELL
  mstr_symbols gnd *
  page233_i251
#ISCELL
  mstr_symbols gnd *
  page233_i252
#CELL
  mstr_discrete cap *
  page233_i253
#CELL
  mstr_discrete cap *
  page233_i254
#CELL
  mstr_discrete cap *
  page233_i255
#CELL
  mstr_discrete capp *
  page233_i256
#CELL
  mstr_discrete res *
  page233_i266
#CELL
  mstr_discrete cap *
  page233_i267
#CELL
  mstr_discrete res *
  page233_i269
#CELL
  mstr_discrete res *
  page233_i270
#CELL
  mstr_discrete res *
  page233_i271
#CELL
  mstr_discrete res *
  page233_i272
#CELL
  mstr_discrete cap *
  page233_i273
#CELL
  mstr_discrete cap *
  page233_i274
#CELL
  mstr_discrete res *
  page233_i275
#ISCELL
  mstr_symbols agnd_scsi *
  page233_i276
#CELL
  mstr_discrete inductor *
  page233_i277
#ISCELL
  mstr_misc dns *
  *
#ISCELL
  mstr_symbols intel_corp_bpage *
  *
#ISCELL
  mstr_standard offpage *
  page234_i118
#CELL
  mstr_discrete cap *
  page234_i129
#CELL
  mstr_discrete cap *
  page234_i130
#ISCELL
  mstr_symbols gnd *
  page234_i131
#ISCELL
  mstr_symbols gnd *
  page234_i138
#CELL
  mstr_discrete cap *
  page234_i139
#CELL
  mstr_discrete res *
  page234_i140
#ISCELL
  mstr_symbols p3v3_stby *
  page234_i142
#CELL
  mstr_discrete res *
  page234_i143
#CELL
  mstr_discrete cap *
  page234_i144
#CELL
  mstr_discrete cap *
  page234_i146
#ISCELL
  mstr_symbols gnd *
  page234_i151
#CELL
  mstr_discrete cap *
  page234_i152
#ISCELL
  mstr_symbols p12v_stby *
  page234_i153
#CELL
  mstr_discrete ferrite *
  page234_i154
#CELL
  mstr_discrete res *
  page234_i155
#ISCELL
  mstr_standard offpage *
  page234_i156
#ISCELL
  mstr_symbols gnd *
  page234_i157
#ISCELL
  mstr_symbols gnd *
  page234_i161
#CELL
  mstr_discrete res *
  page234_i162
#CELL
  mstr_discrete cap *
  page234_i163
#CELL
  mstr_discrete inductor *
  page234_i164
#ISCELL
  mstr_symbols gnd *
  page234_i165
#ISCELL
  mstr_symbols gnd *
  page234_i166
#CELL
  mstr_discrete capp *
  page234_i167
#ISCELL
  mstr_symbols gnd *
  page234_i175
#CELL
  mstr_discrete cap *
  page234_i177
#ISCELL
  mstr_symbols gnd *
  page234_i178
#ISCELL
  mstr_symbols gnd *
  page234_i179
#CELL
  mstr_discrete cap *
  page234_i180
#CELL
  mstr_discrete cap *
  page234_i182
#CELL
  mstr_discrete res *
  page234_i183
#CELL
  mstr_vreg ncp3232l *
  page234_i184
#ISCELL
  mstr_symbols pvpp_klm *
  page234_i185
#ISCELL
  mstr_symbols agnd_scsi *
  page234_i187
#ISCELL
  mstr_symbols agnd_scsi *
  page234_i188
#ISCELL
  mstr_symbols agnd_scsi *
  page234_i189
#ISCELL
  mstr_symbols agnd_scsi *
  page234_i190
#ISCELL
  mstr_symbols agnd_scsi *
  page234_i191
#ISCELL
  mstr_symbols gnd *
  page234_i198
#CELL
  dev_discrete cap_a *
  page234_i199
#ISCELL
  mstr_symbols agnd_scsi *
  page234_i200
#CELL
  mstr_discrete res *
  page234_i201
#CELL
  mstr_discrete cap *
  page234_i202
#CELL
  mstr_discrete cap *
  page234_i203
#CELL
  mstr_discrete cap *
  page234_i204
#CELL
  mstr_discrete cap *
  page234_i205
#ISCELL
  mstr_symbols gnd *
  page234_i206
#ISCELL
  mstr_symbols gnd *
  page234_i207
#ISCELL
  mstr_symbols gnd *
  page234_i208
#ISCELL
  mstr_symbols gnd *
  page234_i209
#CELL
  mstr_discrete capp *
  page234_i210
#CELL
  mstr_discrete cap *
  page234_i211
#CELL
  mstr_discrete cap *
  page234_i212
#CELL
  mstr_discrete res *
  page234_i213
#CELL
  mstr_discrete res *
  page234_i214
#CELL
  mstr_discrete res *
  page234_i215
#CELL
  mstr_discrete res *
  page234_i216
#CELL
  mstr_discrete cap *
  page234_i218
#CELL
  mstr_discrete res *
  page234_i219
#CELL
  mstr_discrete res *
  page234_i220
#ISCELL
  mstr_symbols agnd_scsi *
  page234_i221
#ISCELL
  mstr_symbols gnd *
  page234_i27
#ISCELL
  mstr_symbols agnd_scsi *
  page234_i28
#CELL
  mstr_discrete res *
  page234_i29
#ISCELL
  mstr_symbols gnd *
  page234_i66
#CELL
  mstr_discrete cap *
  page234_i84
#ISCELL
  mstr_symbols gnd *
  page234_i85
#CELL
  mstr_discrete cap *
  page234_i86
#CELL
  mstr_discrete cap *
  page234_i87
#CELL
  mstr_discrete cap *
  page234_i88
#CELL
  mstr_discrete cap *
  page234_i89
#CELL
  mstr_discrete cap *
  page234_i90
#CELL
  mstr_discrete cap *
  page234_i91
#CELL
  mstr_discrete cap *
  page234_i92
#CELL
  mstr_discrete cap *
  page234_i93
#CELL
  mstr_discrete cap *
  page234_i94
#CELL
  mstr_discrete cap *
  page234_i95
#ISCELL
  mstr_symbols pvpp_klm *
  page234_i96
#CELL
  mstr_discrete cap *
  page234_i97
#ISCELL
  mstr_misc dns *
  *
#ISCELL
  mstr_symbols design_note *
  *
#ISCELL
  mstr_symbols intel_corp_bpage *
  *
#ISCELL
  mstr_symbols p3v3_stby *
  page235_i135
#ISCELL
  mstr_standard offpage *
  page235_i136
#ISCELL
  mstr_standard offpage *
  page235_i139
#ISCELL
  mstr_standard offpage *
  page235_i142
#CELL
  dev_discrete cap_a *
  page235_i143
#ISCELL
  mstr_symbols gnd *
  page235_i144
#CELL
  dev_discrete cap_a *
  page235_i145
#ISCELL
  mstr_symbols gnd *
  page235_i146
#CELL
  mstr_discrete res *
  page235_i147
#CELL
  mstr_discrete res *
  page235_i148
#CELL
  mstr_discrete res *
  page235_i149
#CELL
  dev_discrete cap_a *
  page235_i151
#ISCELL
  mstr_symbols gnd *
  page235_i152
#CELL
  mstr_discrete cap *
  page235_i153
#CELL
  mstr_discrete res *
  page235_i154
#ISCELL
  mstr_symbols gnd *
  page235_i155
#ISCELL
  mstr_standard offpage *
  page235_i156
#ISCELL
  mstr_standard offpage *
  page235_i157
#ISCELL
  mstr_symbols p3v3_stby *
  page235_i158
#CELL
  mstr_discrete res *
  page235_i159
#CELL
  mstr_discrete res *
  page235_i165
#CELL
  mstr_discrete res *
  page235_i166
#CELL
  mstr_discrete cap *
  page235_i167
#ISCELL
  mstr_standard offpage *
  page235_i168
#CELL
  dev_discrete cap_a *
  page235_i169
#ISCELL
  mstr_symbols gnd *
  page235_i170
#CELL
  mstr_discrete res *
  page235_i172
#CELL
  mstr_discrete res *
  page235_i173
#CELL
  mstr_discrete res *
  page235_i176
#ISCELL
  mstr_symbols gnd *
  page235_i178
#ISCELL
  mstr_symbols gnd *
  page235_i181
#ISCELL
  mstr_symbols gnd *
  page235_i183
#ISCELL
  mstr_standard offpage *
  page235_i185
#ISCELL
  mstr_standard offpage *
  page235_i186
#ISCELL
  mstr_standard offpage *
  page235_i187
#ISCELL
  mstr_standard offpage *
  page235_i188
#ISCELL
  mstr_standard offpage *
  page235_i189
#ISCELL
  mstr_standard offpage *
  page235_i191
#ISCELL
  mstr_standard offpage *
  page235_i194
#ISCELL
  mstr_standard offpage *
  page235_i195
#ISCELL
  mstr_standard offpage *
  page235_i198
#ISCELL
  mstr_standard offpage *
  page235_i199
#ISCELL
  mstr_standard offpage *
  page235_i200
#CELL
  mstr_discrete cap *
  page235_i209
#CELL
  mstr_discrete res *
  page235_i210
#ISCELL
  mstr_standard offpage *
  page235_i211
#ISCELL
  mstr_standard offpage *
  page235_i212
#ISCELL
  mstr_standard offpage *
  page235_i215
#CELL
  mstr_discrete res *
  page235_i216
#CELL
  mstr_discrete res *
  page235_i217
#CELL
  mstr_discrete cap *
  page235_i218
#ISCELL
  mstr_symbols gnd *
  page235_i219
#CELL
  mstr_discrete res *
  page235_i221
#CELL
  mstr_discrete res *
  page235_i222
#CELL
  mstr_discrete res *
  page235_i224
#CELL
  mstr_discrete res *
  page235_i225
#ISCELL
  mstr_standard offpage *
  page235_i226
#ISCELL
  mstr_standard offpage *
  page235_i227
#ISCELL
  mstr_symbols vcc_core *
  page235_i228
#CELL
  mstr_controller pxe1110b *
  page235_i229
#ISCELL
  mstr_standard offpage *
  page235_i232
#ISCELL
  mstr_standard offpage *
  page235_i234
#CELL
  mstr_discrete res *
  page235_i235
#CELL
  mstr_discrete res *
  page235_i236
#ISCELL
  mstr_misc dns *
  *
#ISCELL
  mstr_symbols intel_corp_bpage *
  *
#ISCELL
  mstr_standard offpage *
  page236_i1
#CELL
  mstr_discrete inductor *
  page236_i10
#ISCELL
  mstr_symbols gnd *
  page236_i11
#CELL
  mstr_discrete ir354xx *
  page236_i116
#CELL
  mstr_discrete ir354xx *
  page236_i117
#CELL
  mstr_discrete res *
  page236_i118
#ISCELL
  mstr_symbols gnd *
  page236_i119
#CELL
  mstr_discrete res *
  page236_i120
#ISCELL
  mstr_symbols gnd *
  page236_i121
#ISCELL
  mstr_symbols p5v_stby *
  page236_i122
#CELL
  dev_discrete cap_a *
  page236_i124
#ISCELL
  mstr_symbols gnd *
  page236_i125
#ISCELL
  mstr_symbols gnd *
  page236_i126
#CELL
  dev_discrete cap_a *
  page236_i127
#ISCELL
  mstr_symbols gnd *
  page236_i130
#CELL
  w_hdl sc2k2p50v3kx-gp *
  page236_i131
#CELL
  w_hdl 3d01r5f-gp *
  page236_i132
#ISCELL
  mstr_symbols gnd *
  page236_i133
#CELL
  mstr_discrete cap *
  page236_i134
#ISCELL
  mstr_symbols gnd *
  page236_i135
#CELL
  mstr_discrete cap *
  page236_i136
#CELL
  w_hdl 3d01r5f-gp *
  page236_i137
#ISCELL
  mstr_symbols gnd *
  page236_i139
#CELL
  mstr_discrete res *
  page236_i14
#CELL
  w_hdl sc2k2p50v3kx-gp *
  page236_i140
#CELL
  mstr_discrete res *
  page236_i141
#CELL
  mstr_discrete res *
  page236_i142
#CELL
  mstr_discrete cap *
  page236_i16
#CELL
  dev_discrete cap_a *
  page236_i17
#CELL
  mstr_discrete cap *
  page236_i19
#ISCELL
  mstr_standard offpage *
  page236_i2
#CELL
  dev_discrete cap_a *
  page236_i20
#CELL
  mstr_discrete cap *
  page236_i21
#CELL
  mstr_discrete cap *
  page236_i22
#CELL
  mstr_discrete cap *
  page236_i23
#CELL
  mstr_discrete cap *
  page236_i24
#ISCELL
  mstr_standard offpage *
  page236_i25
#CELL
  mstr_discrete cap *
  page236_i26
#ISCELL
  mstr_symbols gnd *
  page236_i27
#ISCELL
  mstr_symbols gnd *
  page236_i28
#CELL
  mstr_discrete cap *
  page236_i29
#ISCELL
  mstr_standard offpage *
  page236_i3
#ISCELL
  mstr_standard offpage *
  page236_i30
#CELL
  mstr_discrete cap *
  page236_i31
#CELL
  mstr_discrete cap *
  page236_i32
#CELL
  mstr_discrete cap *
  page236_i33
#CELL
  mstr_discrete cap *
  page236_i34
#CELL
  dev_discrete cap_a *
  page236_i35
#CELL
  mstr_discrete cap *
  page236_i36
#CELL
  dev_discrete cap_a *
  page236_i38
#CELL
  mstr_discrete cap *
  page236_i39
#CELL
  mstr_discrete res *
  page236_i41
#ISCELL
  mstr_symbols p5v_stby *
  page236_i42
#ISCELL
  mstr_symbols gnd *
  page236_i44
#CELL
  mstr_discrete inductor *
  page236_i45
#CELL
  mstr_discrete cap *
  page236_i46
#ISCELL
  mstr_symbols gnd *
  page236_i47
#ISCELL
  mstr_symbols p1v05_pch_stby *
  page236_i48
#ISCELL
  mstr_standard offpage *
  page236_i52
#ISCELL
  mstr_standard offpage *
  page236_i53
#ISCELL
  mstr_standard offpage *
  page236_i54
#ISCELL
  mstr_symbols p1v05_pch_stby *
  page236_i55
#CELL
  mstr_discrete res *
  page236_i56
#CELL
  mstr_discrete res *
  page236_i57
#ISCELL
  mstr_symbols gnd *
  page236_i58
#CELL
  mstr_discrete res *
  page236_i59
#ISCELL
  mstr_standard offpage *
  page236_i60
#ISCELL
  mstr_standard offpage *
  page236_i61
#CELL
  mstr_discrete cap *
  page236_i63
#ISCELL
  mstr_symbols gnd *
  page236_i64
#CELL
  mstr_discrete cap *
  page236_i65
#ISCELL
  mstr_symbols gnd *
  page236_i66
#ISCELL
  mstr_symbols pvnn_pch_stby *
  page236_i7
#CELL
  mstr_discrete capp *
  page236_i71
#CELL
  mstr_discrete capp *
  page236_i73
#CELL
  mstr_discrete capp *
  page236_i74
#CELL
  mstr_discrete capp *
  page236_i75
#CELL
  mstr_discrete capp *
  page236_i76
#CELL
  mstr_discrete capp *
  page236_i77
#CELL
  mstr_discrete capp *
  page236_i78
#CELL
  mstr_discrete capp *
  page236_i79
#ISCELL
  mstr_symbols gnd *
  page236_i8
#ISCELL
  mstr_symbols gnd *
  page236_i82
#ISCELL
  mstr_standard offpage *
  page236_i85
#ISCELL
  mstr_standard offpage *
  page236_i86
#ISCELL
  mstr_symbols pvnn_pch_stby *
  page236_i87
#ISCELL
  mstr_standard offpage *
  page236_i88
#ISCELL
  mstr_standard offpage *
  page236_i89
#CELL
  mstr_discrete cap *
  page236_i9
#CELL
  mstr_discrete res *
  page236_i90
#CELL
  mstr_discrete res *
  page236_i92
#CELL
  mstr_discrete res *
  page236_i93
#CELL
  mstr_discrete res *
  page236_i94
#ISCELL
  mstr_symbols vcc_core *
  page236_i95
#ISCELL
  mstr_symbols vcc_core *
  page236_i96
#ISCELL
  mstr_symbols vcc_core *
  page236_i97
#ISCELL
  mstr_misc dns *
  *
#ISCELL
  mstr_symbols design_note *
  *
#ISCELL
  mstr_symbols intel_corp_bpage *
  *
#ISCELL
  mstr_standard offpage *
  page237_i1
#CELL
  mstr_discrete cap *
  page237_i12
#CELL
  mstr_discrete cap *
  page237_i13
#ISCELL
  mstr_symbols gnd *
  page237_i14
#CELL
  mstr_discrete res *
  page237_i15
#CELL
  mstr_discrete cap *
  page237_i29
#CELL
  mstr_discrete res *
  page237_i3
#ISCELL
  mstr_symbols gnd *
  page237_i30
#CELL
  mstr_discrete cap *
  page237_i31
#ISCELL
  mstr_symbols gnd *
  page237_i32
#ISCELL
  mstr_symbols p1v8_pch_stby *
  page237_i4
#CELL
  mstr_discrete cap *
  page237_i5
#CELL
  mstr_discrete cap *
  page237_i55
#ISCELL
  mstr_standard offpage *
  page237_i58
#ISCELL
  mstr_symbols gnd *
  page237_i6
#ISCELL
  mstr_symbols p3v3_stby *
  page237_i65
#ISCELL
  mstr_symbols gnd *
  page237_i71
#CELL
  mstr_discrete cap *
  page237_i77
#CELL
  mstr_discrete cap *
  page237_i79
#CELL
  mstr_discrete res *
  page237_i80
#CELL
  mstr_discrete res *
  page237_i81
#ISCELL
  mstr_symbols p3v3_stby *
  page237_i85
#CELL
  mstr_vreg rt9059 *
  page237_i86
#CELL
  mstr_discrete res *
  page237_i90
#ISCELL
  mstr_symbols gnd *
  page237_i91
#ISCELL
  mstr_symbols gnd *
  page237_i92
#ISCELL
  mstr_misc dns *
  *
#ISCELL
  mstr_symbols cad_note *
  *
#ISCELL
  mstr_symbols design_note *
  *
#ISCELL
  mstr_symbols intel_corp_bpage *
  *
#ISCELL
  mstr_standard offpage *
  page238_i1
#ISCELL
  mstr_symbols gnd *
  page238_i13
#CELL
  mstr_discrete res *
  page238_i14
#ISCELL
  mstr_symbols gnd *
  page238_i15
#CELL
  mstr_discrete cap *
  page238_i19
#ISCELL
  mstr_symbols gnd *
  page238_i20
#CELL
  mstr_discrete res *
  page238_i21
#ISCELL
  mstr_symbols p3v3_stby *
  page238_i22
#CELL
  mstr_discrete cap *
  page238_i23
#ISCELL
  mstr_standard offpage *
  page238_i25
#ISCELL
  mstr_symbols gnd *
  page238_i27
#ISCELL
  mstr_symbols gnd *
  page238_i3
#CELL
  mstr_discrete cap *
  page238_i30
#CELL
  mstr_discrete cap *
  page238_i39
#ISCELL
  mstr_symbols gnd *
  page238_i4
#CELL
  mstr_vreg rt9059 *
  page238_i40
#CELL
  mstr_discrete res *
  page238_i41
#ISCELL
  mstr_symbols p3v3_stby *
  page238_i42
#ISCELL
  w_power w_vcc_circle *
  page238_i43
#ISCELL
  mstr_symbols p3v3_stby *
  page238_i44
#CELL
  w_hdl 4k42r2f-gp *
  page238_i45
#CELL
  mstr_discrete cap *
  page238_i5
#ISCELL
  mstr_symbols gnd *
  page238_i6
#CELL
  mstr_discrete cap *
  page238_i7
#ISCELL
  mstr_misc dns *
  *
#ISCELL
  mstr_symbols cad_note *
  *
#ISCELL
  mstr_symbols design_note *
  *
#ISCELL
  mstr_symbols intel_corp_bpage *
  *
#CELL
  mstr_discrete cap *
  page239_i12
#CELL
  mstr_discrete res *
  page239_i15
#ISCELL
  mstr_symbols gnd *
  page239_i16
#CELL
  mstr_discrete cap *
  page239_i22
#CELL
  mstr_discrete cap *
  page239_i30
#ISCELL
  mstr_standard offpage *
  page239_i33
#ISCELL
  mstr_symbols p3v3_stby *
  page239_i35
#ISCELL
  mstr_symbols gnd *
  page239_i38
#ISCELL
  mstr_symbols gnd *
  page239_i39
#CELL
  mstr_discrete cap *
  page239_i4
#ISCELL
  mstr_standard offpage *
  page239_i42
#ISCELL
  mstr_symbols gnd *
  page239_i5
#CELL
  mstr_discrete res *
  page239_i6
#ISCELL
  mstr_symbols gnd *
  page239_i62
#ISCELL
  mstr_symbols p3v3_stby *
  page239_i67
#ISCELL
  mstr_symbols gnd *
  page239_i69
#CELL
  mstr_discrete cap *
  page239_i7
#CELL
  mstr_vreg rt9059 *
  page239_i70
#CELL
  dev_discrete cap_a *
  page239_i71
#CELL
  mstr_discrete res *
  page239_i72
#CELL
  mstr_vreg rt9059 *
  page239_i73
#ISCELL
  mstr_symbols gnd *
  page239_i74
#ISCELL
  mstr_symbols p3v3_stby *
  page239_i75
#ISCELL
  mstr_standard offpage *
  page239_i76
#CELL
  mstr_discrete res *
  page239_i77
#ISCELL
  mstr_symbols p3v3_stby *
  page239_i78
#CELL
  mstr_discrete res *
  page239_i79
#CELL
  mstr_discrete cap *
  page239_i81
#ISCELL
  mstr_symbols gnd *
  page239_i82
#CELL
  mstr_discrete cap *
  page239_i83
#CELL
  mstr_discrete cap *
  page239_i84
#ISCELL
  mstr_symbols gnd *
  page239_i85
#CELL
  mstr_discrete res *
  page239_i87
#ISCELL
  mstr_symbols gnd *
  page239_i88
#ISCELL
  mstr_symbols gnd *
  page239_i89
#ISCELL
  mstr_symbols gnd *
  page239_i9
#CELL
  dev_discrete cap_a *
  page239_i90
#CELL
  mstr_discrete cap *
  page239_i91
#CELL
  mstr_discrete cap *
  page239_i92
#ISCELL
  mstr_symbols gnd *
  page239_i93
#ISCELL
  mstr_standard offpage *
  page239_i94
#ISCELL
  mstr_symbols gnd *
  page239_i95
#ISCELL
  w_power w_vcc_circle *
  page239_i96
#ISCELL
  w_power w_vcc_circle *
  page239_i97
#CELL
  w_hdl 5k1r2f-2-gp *
  page239_i98
#CELL
  w_hdl 21k5r2f-gp *
  page239_i99
#ISCELL
  mstr_misc dns *
  *
#ISCELL
  mstr_symbols design_note *
  *
#ISCELL
  mstr_symbols intel_corp_bpage *
  *
#CELL
  mstr_discrete res *
  page240_i106
#ISCELL
  mstr_standard offpage *
  page240_i107
#CELL
  mstr_discrete cap *
  page240_i109
#ISCELL
  mstr_symbols gnd *
  page240_i110
#CELL
  mstr_discrete res *
  page240_i111
#CELL
  mstr_discrete cap *
  page240_i113
#ISCELL
  mstr_symbols p5v_stby *
  page240_i114
#ISCELL
  mstr_symbols gnd *
  page240_i115
#CELL
  mstr_discrete cap *
  page240_i116
#CELL
  mstr_discrete res *
  page240_i117
#CELL
  mstr_vreg rt8240 *
  page240_i125
#ISCELL
  mstr_standard offpage *
  page240_i126
#CELL
  mstr_discrete res *
  page240_i127
#ISCELL
  mstr_symbols gnd *
  page240_i128
#CELL
  mstr_discrete cap *
  page240_i129
#ISCELL
  mstr_symbols p3v3_stby *
  page240_i130
#ISCELL
  mstr_symbols p12v_stby *
  page240_i131
#CELL
  mstr_discrete ferrite *
  page240_i132
#ISCELL
  mstr_symbols gnd *
  page240_i133
#CELL
  mstr_discrete cap *
  page240_i134
#CELL
  mstr_discrete cap *
  page240_i135
#ISCELL
  mstr_symbols gnd *
  page240_i136
#CELL
  mstr_discrete cap *
  page240_i137
#ISCELL
  mstr_symbols gnd *
  page240_i138
#CELL
  mstr_discrete cap *
  page240_i139
#CELL
  mstr_discrete res *
  page240_i140
#CELL
  mstr_discrete res *
  page240_i142
#CELL
  mstr_discrete res *
  page240_i143
#CELL
  mstr_discrete res *
  page240_i144
#ISCELL
  mstr_symbols gnd *
  page240_i145
#CELL
  mstr_discrete res *
  page240_i146
#ISCELL
  mstr_symbols gnd *
  page240_i147
#CELL
  mstr_discrete res *
  page240_i148
#ISCELL
  mstr_symbols gnd *
  page240_i149
#ISCELL
  mstr_symbols gnd *
  page240_i151
#CELL
  mstr_discrete res *
  page240_i152
#ISCELL
  mstr_symbols gnd *
  page240_i153
#CELL
  mstr_discrete capp *
  page240_i154
#CELL
  mstr_discrete capp *
  page240_i155
#ISCELL
  mstr_symbols gnd *
  page240_i156
#ISCELL
  mstr_symbols gnd *
  page240_i157
#CELL
  mstr_discrete cap *
  page240_i158
#ISCELL
  mstr_symbols gnd *
  page240_i159
#CELL
  mstr_discrete cap *
  page240_i160
#CELL
  mstr_discrete cap *
  page240_i163
#ISCELL
  mstr_symbols agnd_scsi *
  page240_i164
#ISCELL
  mstr_symbols agnd_scsi *
  page240_i165
#ISCELL
  mstr_symbols agnd_scsi *
  page240_i166
#ISCELL
  mstr_symbols agnd_scsi *
  page240_i167
#ISCELL
  mstr_symbols agnd_scsi *
  page240_i168
#ISCELL
  mstr_symbols agnd_scsi *
  page240_i169
#CELL
  mstr_discrete csd87384m *
  page240_i170
#CELL
  mstr_discrete res *
  page240_i171
#CELL
  mstr_discrete inductor *
  page240_i173
#CELL
  mstr_discrete cap *
  page240_i174
#ISCELL
  mstr_symbols gnd *
  page240_i175
#CELL
  mstr_discrete res *
  page240_i176
#CELL
  mstr_discrete res *
  page240_i177
#ISCELL
  mstr_symbols p3v3_stby *
  page240_i178
#ISCELL
  mstr_symbols p3v3_stby *
  page240_i85
#ISCELL
  mstr_misc dns *
  *
#ISCELL
  mstr_symbols cad_note *
  *
#ISCELL
  mstr_symbols design_note *
  *
#ISCELL
  mstr_symbols intel_corp_bpage *
  *
#ISCELL
  mstr_standard offpage *
  page241_i1
#CELL
  mstr_discrete res *
  page241_i11
#CELL
  mstr_discrete cap *
  page241_i12
#CELL
  mstr_discrete cap *
  page241_i14
#ISCELL
  mstr_symbols gnd *
  page241_i16
#CELL
  mstr_discrete res *
  page241_i18
#ISCELL
  mstr_symbols gnd *
  page241_i19
#CELL
  mstr_discrete cap *
  page241_i2
#CELL
  mstr_discrete cap *
  page241_i3
#CELL
  mstr_discrete cap *
  page241_i30
#ISCELL
  mstr_symbols gnd *
  page241_i31
#ISCELL
  mstr_symbols gnd *
  page241_i32
#CELL
  mstr_discrete res *
  page241_i37
#CELL
  mstr_discrete cap *
  page241_i39
#ISCELL
  mstr_symbols gnd *
  page241_i4
#ISCELL
  mstr_symbols gnd *
  page241_i40
#CELL
  mstr_discrete cap *
  page241_i41
#ISCELL
  mstr_symbols gnd *
  page241_i44
#CELL
  mstr_discrete cap *
  page241_i45
#ISCELL
  mstr_symbols gnd *
  page241_i46
#CELL
  mstr_discrete cap *
  page241_i47
#ISCELL
  mstr_standard offpage *
  page241_i48
#CELL
  mstr_discrete res *
  page241_i50
#CELL
  mstr_discrete res *
  page241_i51
#ISCELL
  mstr_symbols gnd *
  page241_i52
#CELL
  mstr_discrete cap *
  page241_i53
#CELL
  mstr_discrete res *
  page241_i54
#ISCELL
  mstr_symbols gnd *
  page241_i55
#CELL
  mstr_discrete cap *
  page241_i57
#CELL
  mstr_discrete res *
  page241_i58
#ISCELL
  mstr_symbols gnd *
  page241_i59
#CELL
  mstr_discrete cap *
  page241_i63
#ISCELL
  mstr_symbols gnd *
  page241_i64
#ISCELL
  mstr_symbols p5v_stby *
  page241_i69
#ISCELL
  mstr_symbols p12v_stby *
  page241_i71
#CELL
  mstr_discrete res *
  page241_i78
#CELL
  mstr_discrete capp *
  page241_i8
#CELL
  mstr_discrete ferrite *
  page241_i82
#CELL
  mstr_vreg tps54821 *
  page241_i83
#ISCELL
  mstr_symbols p5v_stby *
  page241_i85
#ISCELL
  mstr_symbols gnd *
  page241_i86
#CELL
  mstr_discrete res *
  page241_i89
#CELL
  mstr_discrete res *
  page241_i9
#CELL
  mstr_discrete inductor *
  page241_i90
#CELL
  mstr_discrete res *
  page241_i91
#ISCELL
  mstr_symbols intel_corp_bpage *
  *
#ISCELL
  mstr_symbols gnd *
  page242_i1
#ISCELL
  mstr_symbols gnd *
  page242_i10
#CELL
  mstr_discrete cap *
  page242_i11
#CELL
  mstr_discrete cap *
  page242_i15
#ISCELL
  mstr_symbols pvddq_abc *
  page242_i26
#ISCELL
  mstr_symbols gnd *
  page242_i27
#ISCELL
  mstr_symbols pvddq_def *
  page242_i29
#ISCELL
  mstr_symbols pvddq_abc *
  page242_i3
#ISCELL
  mstr_symbols gnd *
  page242_i33
#ISCELL
  mstr_symbols pvddq_def *
  page242_i35
#ISCELL
  mstr_symbols gnd *
  page242_i36
#CELL
  mstr_discrete cap *
  page242_i37
#CELL
  mstr_discrete cap *
  page242_i41
#ISCELL
  mstr_symbols pvddq_def *
  page242_i50
#CELL
  dev_discrete cap_a *
  page242_i53
#CELL
  dev_discrete cap_a *
  page242_i54
#CELL
  dev_discrete cap_a *
  page242_i55
#CELL
  dev_discrete cap_a *
  page242_i56
#CELL
  dev_discrete cap_a *
  page242_i57
#CELL
  dev_discrete cap_a *
  page242_i58
#CELL
  dev_discrete cap_a *
  page242_i59
#CELL
  dev_discrete cap_a *
  page242_i60
#CELL
  dev_discrete cap_a *
  page242_i61
#CELL
  dev_discrete cap_a *
  page242_i62
#CELL
  dev_discrete cap_a *
  page242_i63
#CELL
  dev_discrete cap_a *
  page242_i64
#CELL
  dev_discrete cap_a *
  page242_i65
#CELL
  dev_discrete cap_a *
  page242_i66
#CELL
  dev_discrete cap_a *
  page242_i67
#CELL
  dev_discrete cap_a *
  page242_i68
#CELL
  dev_discrete cap_a *
  page242_i69
#ISCELL
  mstr_symbols gnd *
  page242_i7
#CELL
  dev_discrete cap_a *
  page242_i70
#CELL
  dev_discrete cap_a *
  page242_i71
#CELL
  dev_discrete cap_a *
  page242_i72
#CELL
  dev_discrete cap_a *
  page242_i73
#CELL
  dev_discrete cap_a *
  page242_i74
#CELL
  dev_discrete cap_a *
  page242_i75
#CELL
  dev_discrete cap_a *
  page242_i76
#CELL
  dev_discrete cap_a *
  page242_i77
#CELL
  dev_discrete cap_a *
  page242_i78
#CELL
  dev_discrete cap_a *
  page242_i79
#CELL
  dev_discrete cap_a *
  page242_i80
#CELL
  dev_discrete cap_a *
  page242_i81
#CELL
  dev_discrete cap_a *
  page242_i82
#CELL
  dev_discrete cap_a *
  page242_i83
#CELL
  dev_discrete cap_a *
  page242_i84
#CELL
  dev_discrete cap_a *
  page242_i85
#CELL
  dev_discrete cap_a *
  page242_i86
#CELL
  dev_discrete cap_a *
  page242_i87
#CELL
  dev_discrete cap_a *
  page242_i88
#ISCELL
  mstr_symbols pvddq_abc *
  page242_i9
#ISCELL
  mstr_symbols intel_corp_bpage *
  *
#ISCELL
  mstr_symbols gnd *
  page243_i1
#ISCELL
  mstr_symbols gnd *
  page243_i11
#CELL
  mstr_discrete cap *
  page243_i12
#CELL
  mstr_discrete cap *
  page243_i13
#ISCELL
  mstr_symbols pvddq_ghj *
  page243_i26
#ISCELL
  mstr_symbols gnd *
  page243_i27
#ISCELL
  mstr_symbols pvddq_klm *
  page243_i29
#ISCELL
  mstr_symbols pvddq_ghj *
  page243_i3
#ISCELL
  mstr_symbols gnd *
  page243_i34
#ISCELL
  mstr_symbols pvddq_klm *
  page243_i36
#ISCELL
  mstr_symbols gnd *
  page243_i38
#CELL
  mstr_discrete cap *
  page243_i39
#CELL
  mstr_discrete cap *
  page243_i43
#ISCELL
  mstr_symbols pvddq_klm *
  page243_i51
#CELL
  dev_discrete cap_a *
  page243_i53
#CELL
  dev_discrete cap_a *
  page243_i54
#CELL
  dev_discrete cap_a *
  page243_i55
#CELL
  dev_discrete cap_a *
  page243_i56
#CELL
  dev_discrete cap_a *
  page243_i57
#CELL
  dev_discrete cap_a *
  page243_i58
#CELL
  dev_discrete cap_a *
  page243_i59
#ISCELL
  mstr_symbols gnd *
  page243_i6
#CELL
  dev_discrete cap_a *
  page243_i60
#CELL
  dev_discrete cap_a *
  page243_i61
#CELL
  dev_discrete cap_a *
  page243_i62
#CELL
  dev_discrete cap_a *
  page243_i63
#CELL
  dev_discrete cap_a *
  page243_i64
#CELL
  dev_discrete cap_a *
  page243_i65
#CELL
  dev_discrete cap_a *
  page243_i66
#CELL
  dev_discrete cap_a *
  page243_i67
#CELL
  dev_discrete cap_a *
  page243_i68
#CELL
  dev_discrete cap_a *
  page243_i69
#CELL
  dev_discrete cap_a *
  page243_i70
#CELL
  dev_discrete cap_a *
  page243_i71
#CELL
  dev_discrete cap_a *
  page243_i72
#CELL
  dev_discrete cap_a *
  page243_i73
#CELL
  dev_discrete cap_a *
  page243_i74
#CELL
  dev_discrete cap_a *
  page243_i75
#CELL
  dev_discrete cap_a *
  page243_i76
#CELL
  dev_discrete cap_a *
  page243_i77
#CELL
  dev_discrete cap_a *
  page243_i78
#CELL
  dev_discrete cap_a *
  page243_i79
#ISCELL
  mstr_symbols pvddq_ghj *
  page243_i8
#CELL
  dev_discrete cap_a *
  page243_i80
#CELL
  dev_discrete cap_a *
  page243_i81
#CELL
  dev_discrete cap_a *
  page243_i82
#CELL
  dev_discrete cap_a *
  page243_i83
#CELL
  dev_discrete cap_a *
  page243_i84
#CELL
  dev_discrete cap_a *
  page243_i85
#CELL
  dev_discrete cap_a *
  page243_i86
#CELL
  dev_discrete cap_a *
  page243_i87
#CELL
  dev_discrete cap_a *
  page243_i88
#ISCELL
  mstr_symbols intel_corp_bpage *
  *
#ISCELL
  mstr_standard tap *
  page244_i1
#ISCELL
  mstr_standard offpage *
  page244_i10
#ISCELL
  mstr_standard tap *
  page244_i100
#ISCELL
  mstr_standard tap *
  page244_i101
#ISCELL
  mstr_standard tap *
  page244_i102
#CELL
  mstr_discrete res *
  page244_i103
#ISCELL
  mstr_standard offpage *
  page244_i104
#ISCELL
  mstr_standard tap *
  page244_i11
#CELL
  mstr_discrete cap *
  page244_i12
#ISCELL
  mstr_standard tap *
  page244_i13
#ISCELL
  mstr_standard tap *
  page244_i14
#ISCELL
  mstr_standard tap *
  page244_i15
#ISCELL
  mstr_standard tap *
  page244_i16
#CELL
  mstr_discrete cap *
  page244_i17
#ISCELL
  mstr_standard tap *
  page244_i18
#ISCELL
  mstr_standard tap *
  page244_i19
#CELL
  mstr_discrete cap *
  page244_i2
#ISCELL
  mstr_standard tap *
  page244_i20
#ISCELL
  mstr_standard tap *
  page244_i21
#ISCELL
  mstr_standard tap *
  page244_i22
#CELL
  mstr_discrete cap *
  page244_i23
#CELL
  mstr_discrete cap *
  page244_i24
#ISCELL
  mstr_standard tap *
  page244_i25
#ISCELL
  mstr_standard tap *
  page244_i26
#ISCELL
  mstr_standard tap *
  page244_i27
#CELL
  mstr_discrete cap *
  page244_i28
#CELL
  mstr_discrete cap *
  page244_i29
#ISCELL
  mstr_standard tap *
  page244_i3
#CELL
  mstr_discrete cap *
  page244_i30
#ISCELL
  mstr_standard tap *
  page244_i31
#ISCELL
  mstr_standard tap *
  page244_i32
#ISCELL
  mstr_standard tap *
  page244_i33
#ISCELL
  mstr_standard tap *
  page244_i34
#CELL
  mstr_discrete cap *
  page244_i35
#ISCELL
  mstr_standard tap *
  page244_i36
#ISCELL
  mstr_standard offpage *
  page244_i37
#ISCELL
  mstr_standard tap *
  page244_i38
#CELL
  mstr_discrete res *
  page244_i39
#ISCELL
  mstr_standard tap *
  page244_i4
#ISCELL
  mstr_standard tap *
  page244_i40
#CELL
  mstr_discrete cap *
  page244_i41
#ISCELL
  mstr_standard tap *
  page244_i42
#ISCELL
  mstr_standard tap *
  page244_i43
#ISCELL
  mstr_standard tap *
  page244_i44
#ISCELL
  mstr_standard tap *
  page244_i45
#ISCELL
  mstr_standard tap *
  page244_i46
#CELL
  mstr_discrete cap *
  page244_i47
#ISCELL
  mstr_standard tap *
  page244_i48
#ISCELL
  mstr_standard offpage *
  page244_i49
#CELL
  mstr_discrete cap *
  page244_i5
#CELL
  mstr_discrete cap *
  page244_i50
#CELL
  mstr_discrete cap *
  page244_i51
#CELL
  mstr_discrete cap *
  page244_i52
#ISCELL
  mstr_standard tap *
  page244_i53
#ISCELL
  mstr_standard tap *
  page244_i54
#ISCELL
  mstr_standard tap *
  page244_i55
#ISCELL
  mstr_standard offpage *
  page244_i56
#ISCELL
  mstr_standard tap *
  page244_i57
#CELL
  mstr_discrete res *
  page244_i58
#ISCELL
  mstr_standard tap *
  page244_i59
#ISCELL
  mstr_standard tap *
  page244_i6
#ISCELL
  mstr_standard tap *
  page244_i60
#ISCELL
  mstr_standard tap *
  page244_i61
#ISCELL
  mstr_standard tap *
  page244_i62
#ISCELL
  mstr_standard offpage *
  page244_i63
#CELL
  mstr_discrete res *
  page244_i64
#CELL
  mstr_discrete res *
  page244_i65
#CELL
  mstr_discrete res *
  page244_i66
#ISCELL
  mstr_standard tap *
  page244_i67
#ISCELL
  mstr_standard tap *
  page244_i68
#ISCELL
  mstr_standard tap *
  page244_i69
#ISCELL
  mstr_standard tap *
  page244_i7
#ISCELL
  mstr_standard tap *
  page244_i70
#ISCELL
  mstr_standard tap *
  page244_i71
#CELL
  mstr_discrete res *
  page244_i72
#ISCELL
  mstr_standard tap *
  page244_i73
#CELL
  mstr_discrete res *
  page244_i74
#ISCELL
  mstr_standard tap *
  page244_i75
#ISCELL
  mstr_standard tap *
  page244_i76
#CELL
  mstr_discrete res *
  page244_i77
#ISCELL
  mstr_standard tap *
  page244_i78
#ISCELL
  mstr_standard offpage *
  page244_i79
#CELL
  mstr_discrete cap *
  page244_i8
#CELL
  mstr_discrete res *
  page244_i80
#ISCELL
  mstr_standard tap *
  page244_i81
#ISCELL
  mstr_standard tap *
  page244_i82
#ISCELL
  mstr_standard tap *
  page244_i83
#ISCELL
  mstr_standard tap *
  page244_i84
#ISCELL
  mstr_standard tap *
  page244_i85
#CELL
  mstr_discrete res *
  page244_i86
#ISCELL
  mstr_standard tap *
  page244_i87
#ISCELL
  mstr_standard tap *
  page244_i88
#ISCELL
  mstr_standard tap *
  page244_i89
#ISCELL
  mstr_standard offpage *
  page244_i9
#ISCELL
  mstr_standard tap *
  page244_i90
#ISCELL
  mstr_standard tap *
  page244_i91
#ISCELL
  mstr_standard tap *
  page244_i92
#CELL
  mstr_discrete res *
  page244_i93
#CELL
  mstr_discrete res *
  page244_i94
#ISCELL
  mstr_standard tap *
  page244_i95
#ISCELL
  mstr_standard tap *
  page244_i96
#CELL
  mstr_discrete res *
  page244_i97
#CELL
  mstr_discrete res *
  page244_i98
#CELL
  mstr_discrete res *
  page244_i99
#ISCELL
  mstr_symbols intel_corp_bpage *
  *
#ISCELL
  mstr_standard offpage *
  page245_i1
#ISCELL
  mstr_standard tap *
  page245_i10
#ISCELL
  mstr_standard tap *
  page245_i11
#ISCELL
  mstr_standard tap *
  page245_i12
#ISCELL
  mstr_standard tap *
  page245_i13
#ISCELL
  mstr_standard tap *
  page245_i14
#ISCELL
  mstr_standard tap *
  page245_i15
#ISCELL
  mstr_standard tap *
  page245_i16
#ISCELL
  mstr_standard tap *
  page245_i17
#ISCELL
  mstr_standard tap *
  page245_i18
#ISCELL
  mstr_symbols gnd *
  page245_i19
#ISCELL
  mstr_standard offpage *
  page245_i2
#ISCELL
  mstr_symbols gnd *
  page245_i20
#ISCELL
  mstr_standard offpage *
  page245_i21
#ISCELL
  mstr_standard offpage *
  page245_i22
#ISCELL
  mstr_standard tap *
  page245_i23
#ISCELL
  mstr_standard tap *
  page245_i24
#ISCELL
  mstr_symbols gnd *
  page245_i25
#ISCELL
  mstr_symbols gnd *
  page245_i26
#ISCELL
  mstr_symbols gnd *
  page245_i27
#ISCELL
  mstr_standard offpage *
  page245_i28
#ISCELL
  mstr_standard tap *
  page245_i29
#ISCELL
  mstr_standard offpage *
  page245_i3
#ISCELL
  mstr_standard tap *
  page245_i30
#ISCELL
  mstr_standard tap *
  page245_i31
#ISCELL
  mstr_standard tap *
  page245_i32
#ISCELL
  mstr_standard tap *
  page245_i33
#ISCELL
  mstr_standard tap *
  page245_i34
#ISCELL
  mstr_standard tap *
  page245_i35
#ISCELL
  mstr_standard tap *
  page245_i36
#ISCELL
  mstr_standard tap *
  page245_i37
#ISCELL
  mstr_standard tap *
  page245_i38
#ISCELL
  mstr_standard tap *
  page245_i39
#ISCELL
  mstr_standard offpage *
  page245_i4
#ISCELL
  mstr_standard tap *
  page245_i40
#ISCELL
  mstr_standard tap *
  page245_i41
#ISCELL
  mstr_standard tap *
  page245_i42
#ISCELL
  mstr_standard tap *
  page245_i43
#ISCELL
  mstr_standard tap *
  page245_i44
#ISCELL
  mstr_standard offpage *
  page245_i45
#ISCELL
  mstr_standard offpage *
  page245_i46
#ISCELL
  mstr_standard offpage *
  page245_i47
#CELL
  w_hdl smc-conn60a-22-gp *
  page245_i48
#ISCELL
  mstr_standard tap *
  page245_i5
#ISCELL
  mstr_standard tap *
  page245_i6
#ISCELL
  mstr_standard tap *
  page245_i7
#ISCELL
  mstr_standard tap *
  page245_i8
#ISCELL
  mstr_standard tap *
  page245_i9
#ISCELL
  mstr_misc dns *
  *
#ISCELL
  mstr_symbols bom_note *
  *
#ISCELL
  mstr_symbols cad_note *
  *
#ISCELL
  mstr_symbols intel_corp_bpage *
  *
#ISCELL
  mstr_standard offpage *
  page246_i1
#CELL
  mstr_discrete res *
  page246_i10
#CELL
  mstr_discrete res *
  page246_i11
#CELL
  mstr_discrete res *
  page246_i12
#ISCELL
  mstr_symbols gnd *
  page246_i13
#ISCELL
  mstr_symbols gnd *
  page246_i14
#CELL
  mstr_discrete cap *
  page246_i15
#CELL
  mstr_discrete cap *
  page246_i16
#CELL
  mstr_memory w25q256 *
  page246_i17
#ISCELL
  mstr_standard offpage *
  page246_i2
#ISCELL
  mstr_standard offpage *
  page246_i3
#ISCELL
  mstr_standard offpage *
  page246_i4
#CELL
  mstr_discrete res *
  page246_i5
#ISCELL
  mstr_symbols p3v3_stby *
  page246_i6
#ISCELL
  mstr_symbols gnd *
  page246_i7
#CELL
  mstr_discrete res *
  page246_i8
#CELL
  mstr_discrete res *
  page246_i9
#ISCELL
  mstr_misc dns *
  *
#ISCELL
  mstr_symbols cad_note *
  *
#ISCELL
  mstr_symbols design_note *
  *
#ISCELL
  mstr_symbols intel_corp_bpage *
  *
#CELL
  mstr_discrete res *
  page247_i1
#CELL
  mstr_discrete res *
  page247_i10
#CELL
  mstr_discrete res *
  page247_i11
#ISCELL
  mstr_symbols p3v3_stby *
  page247_i12
#ISCELL
  mstr_symbols gnd *
  page247_i13
#ISCELL
  mstr_symbols gnd *
  page247_i17
#CELL
  mstr_discrete cap *
  page247_i18
#ISCELL
  mstr_symbols p3v3_stby *
  page247_i19
#ISCELL
  mstr_symbols gnd *
  page247_i20
#ISCELL
  mstr_standard offpage *
  page247_i21
#ISCELL
  mstr_standard offpage *
  page247_i22
#ISCELL
  mstr_standard offpage *
  page247_i23
#ISCELL
  mstr_standard offpage *
  page247_i24
#ISCELL
  mstr_standard offpage *
  page247_i25
#ISCELL
  mstr_standard offpage *
  page247_i26
#ISCELL
  mstr_standard offpage *
  page247_i27
#ISCELL
  mstr_standard offpage *
  page247_i28
#ISCELL
  mstr_standard offpage *
  page247_i29
#CELL
  mstr_discrete res *
  page247_i3
#ISCELL
  mstr_standard offpage *
  page247_i30
#ISCELL
  mstr_symbols gnd *
  page247_i4
#CELL
  mstr_discrete res *
  page247_i5
#ISCELL
  mstr_symbols p3v3_stby *
  page247_i6
#CELL
  mstr_discrete res *
  page247_i67
#CELL
  mstr_discrete res *
  page247_i68
#ISCELL
  mstr_symbols gnd *
  page247_i7
#ISCELL
  mstr_standard offpage *
  page247_i70
#ISCELL
  mstr_standard offpage *
  page247_i72
#ISCELL
  mstr_symbols p3v3_stby *
  page247_i73
#ISCELL
  mstr_standard offpage *
  page247_i74
#ISCELL
  mstr_standard offpage *
  page247_i75
#CELL
  w_hdl pca9515adgkr-1-gp *
  page247_i77
#ISCELL
  mstr_symbols gnd *
  page247_i78
#ISCELL
  mstr_standard offpage *
  page247_i79
#CELL
  mstr_discrete res *
  page247_i8
#ISCELL
  mstr_standard offpage *
  page247_i80
#CELL
  mstr_discrete cap *
  page247_i81
#ISCELL
  mstr_symbols gnd *
  page247_i82
#ISCELL
  mstr_symbols p3v3_stby *
  page247_i83
#ISCELL
  mstr_standard offpage *
  page247_i84
#CELL
  dev_discrete cap_a *
  page247_i85
#ISCELL
  mstr_symbols gnd *
  page247_i86
#CELL
  mstr_discrete res *
  page247_i87
#ISCELL
  mstr_symbols p3v3_stby *
  page247_i88
#CELL
  mstr_memory at24c64 *
  page247_i89
#CELL
  mstr_discrete res *
  page247_i9
#CELL
  mstr_discrete res *
  page247_i90
#ISCELL
  mstr_symbols gnd *
  page247_i91
#CELL
  mstr_discrete res *
  page247_i92
#ISCELL
  mstr_symbols gnd *
  page247_i93
#CELL
  mstr_discrete res *
  page247_i94
#ISCELL
  mstr_standard offpage *
  page247_i95
#ISCELL
  mstr_standard offpage *
  page247_i96
#CELL
  w_hdl pca9555pwrg4-gp *
  page247_i97
#ISCELL
  mstr_symbols intel_corp_bpage *
  *
#ISCELL
  mstr_symbols intel_corp_bpage *
  *
#ISCELL
  mstr_standard offpage *
  page249_i1
#ISCELL
  mstr_symbols gnd *
  page249_i10
#ISCELL
  mstr_symbols gnd *
  page249_i11
#CELL
  mstr_discrete res *
  page249_i12
#ISCELL
  mstr_symbols gnd *
  page249_i14
#CELL
  w_hdl lmv331idckrg4-gp *
  page249_i15
#ISCELL
  mstr_symbols p3v3_stby *
  page249_i16
#CELL
  mstr_discrete res *
  page249_i17
#ISCELL
  mstr_symbols gnd *
  page249_i18
#ISCELL
  mstr_symbols p3v3_stby *
  page249_i19
#CELL
  mstr_discrete res *
  page249_i2
#ISCELL
  mstr_symbols gnd *
  page249_i20
#CELL
  mstr_discrete cap *
  page249_i21
#ISCELL
  mstr_standard offpage *
  page249_i22
#ISCELL
  mstr_symbols p3v3_stby *
  page249_i24
#CELL
  mstr_discrete npn *
  page249_i26
#CELL
  mstr_discrete res *
  page249_i27
#ISCELL
  mstr_standard offpage *
  page249_i28
#CELL
  mstr_discrete npn *
  page249_i29
#ISCELL
  mstr_symbols gnd *
  page249_i3
#CELL
  mstr_discrete fet_n *
  page249_i30
#CELL
  w_hdl 47kr2f-gp *
  page249_i31
#CELL
  mstr_discrete cap *
  page249_i32
#CELL
  w_hdl 82k5r2f-gp *
  page249_i33
#ISCELL
  mstr_standard offpage *
  page249_i5
#ISCELL
  mstr_symbols gnd *
  page249_i6
#CELL
  mstr_discrete res *
  page249_i7
#CELL
  mstr_discrete res *
  page249_i8
#ISCELL
  mstr_symbols p3v3_stby *
  page249_i9
